# ODB++ job SA45_DaughterCard_X1_FAB.tgz
### matrix/matrix

STEP {
    COL=1
    NAME=PCB
}


LAYER {
    ROW=1
    CONTEXT=BOARD
    TYPE=COMPONENT
    NAME=COMP_+_TOP
    POLARITY=POSITIVE
    START_NAME=
    END_NAME=
    OLD_NAME=
}

LAYER {
    ROW=2
    CONTEXT=BOARD
    TYPE=SOLDER_PASTE
    NAME=TOP_PASTE
    POLARITY=POSITIVE
    START_NAME=
    END_NAME=
    OLD_NAME=
}

LAYER {
    ROW=3
    CONTEXT=BOARD
    TYPE=SILK_SCREEN
    NAME=TOP_OVERLAY
    POLARITY=POSITIVE
    START_NAME=
    END_NAME=
    OLD_NAME=
}

LAYER {
    ROW=4
    CONTEXT=BOARD
    TYPE=SOLDER_MASK
    NAME=TOP_SOLDER
    POLARITY=POSITIVE
    START_NAME=
    END_NAME=
    OLD_NAME=
}

LAYER {
    ROW=5
    CONTEXT=BOARD
    TYPE=SIGNAL
    NAME=L01-TOP_LAYER
    POLARITY=POSITIVE
    START_NAME=
    END_NAME=
    OLD_NAME=
}

LAYER {
    ROW=6
    CONTEXT=BOARD
    TYPE=DIELECTRIC
    NAME=DIELECTRIC_1
    POLARITY=POSITIVE
    START_NAME=
    END_NAME=
    OLD_NAME=
    DIELECTRIC_TYPE=PREPREG
    DIELECTRIC_NAME=2x106
}

LAYER {
    ROW=7
    CONTEXT=BOARD
    TYPE=SIGNAL
    NAME=L02-INNER_LAYER
    POLARITY=POSITIVE
    START_NAME=
    END_NAME=
    OLD_NAME=
}

LAYER {
    ROW=8
    CONTEXT=BOARD
    TYPE=DIELECTRIC
    NAME=DIELECTRIC_2
    POLARITY=POSITIVE
    START_NAME=
    END_NAME=
    OLD_NAME=
    DIELECTRIC_TYPE=CORE
    DIELECTRIC_NAME=FR4
}

LAYER {
    ROW=9
    CONTEXT=BOARD
    TYPE=SIGNAL
    NAME=L03-INNER_LAYER
    POLARITY=POSITIVE
    START_NAME=
    END_NAME=
    OLD_NAME=
}

LAYER {
    ROW=10
    CONTEXT=BOARD
    TYPE=DIELECTRIC
    NAME=DIELECTRIC_3
    POLARITY=POSITIVE
    START_NAME=
    END_NAME=
    OLD_NAME=
    DIELECTRIC_TYPE=PREPREG
    DIELECTRIC_NAME=2x106
}

LAYER {
    ROW=11
    CONTEXT=BOARD
    TYPE=SIGNAL
    NAME=L04-BOTTOM_LAYER
    POLARITY=POSITIVE
    START_NAME=
    END_NAME=
    OLD_NAME=
}

LAYER {
    ROW=12
    CONTEXT=BOARD
    TYPE=SOLDER_MASK
    NAME=BOTTOM_SOLDER
    POLARITY=POSITIVE
    START_NAME=
    END_NAME=
    OLD_NAME=
}

LAYER {
    ROW=13
    CONTEXT=BOARD
    TYPE=SILK_SCREEN
    NAME=BOTTOM_OVERLAY
    POLARITY=POSITIVE
    START_NAME=
    END_NAME=
    OLD_NAME=
}

LAYER {
    ROW=14
    CONTEXT=BOARD
    TYPE=SOLDER_PASTE
    NAME=BOTTOM_PASTE
    POLARITY=POSITIVE
    START_NAME=
    END_NAME=
    OLD_NAME=
}

LAYER {
    ROW=15
    CONTEXT=BOARD
    TYPE=DRILL
    NAME=DRILL_NON-PLATED_BOTTOM-TOP
    POLARITY=POSITIVE
    START_NAME=L01-TOP_LAYER
    END_NAME=L04-BOTTOM_LAYER
    OLD_NAME=
}

LAYER {
    ROW=16
    CONTEXT=BOARD
    TYPE=DRILL
    NAME=DRILL_PLATED_BOTTOM-TOP
    POLARITY=POSITIVE
    START_NAME=L01-TOP_LAYER
    END_NAME=L04-BOTTOM_LAYER
    OLD_NAME=
}

LAYER {
    ROW=17
    CONTEXT=BOARD
    TYPE=COMPONENT
    NAME=COMP_+_BOT
    POLARITY=POSITIVE
    START_NAME=
    END_NAME=
    OLD_NAME=
}

LAYER {
    ROW=18
    CONTEXT=MISC
    TYPE=DOCUMENT
    NAME=M01_PCB_OUTLINE
    POLARITY=POSITIVE
    START_NAME=
    END_NAME=
    OLD_NAME=
}

### misc/info
UNITS=MM
PRODUCT_MODEL_NAME=odb
ODB_VERSION_MAJOR=8
ODB_VERSION_MINOR=0
ODB_SOURCE=Altium Designer
CREATION_DATE=20220928.133535
SAVE_DATE=20230124.171802
SAVE_APP=Altium Designer 23.1.1.15

### misc/attrlist
UNITS=MM
.customer = 
.comment = 
.technology = 
.global_camtek_aoiset = 
.drc_route_keepin_lyr = 
.drc_comp_keepin_lyr = 
.drc_tp_keepin_lyr = 
.drc_route_keepout_lyr = 
.drc_via_keepout_lyr = 
.drc_trace_keepout_lyr = 
.drc_trace_keepout_lyr = 
.drc_plane_keepout_lyr = 
.drc_pad_keepout_lyr = 
.drc_comp_keepout_lyr = 
.drc_comp_height_lyr = 
.drc_tp_keepout_lyr = 
.variant_list = 
.primary_side = top
.design_origin_x = 0
.design_origin_y = 0
.board_thickness = 1.57074108
_board_material = thermon

### steps/pcb/stephdr
UNITS=MM
X_DATUM=0.0000
Y_DATUM=0.0000

TOP_ACTIVE=0
BOTTOM_ACTIVE=0
RIGHT_ACTIVE=0
LEFT_ACTIVE=0
ONLINE_DRC_NAME=
ONLINE_DRC_MODE=DISABLED
ONLINE_DRC_STAT=RED
ONLINE_DRC_TIME=0
ONLINE_DRC_BEEP_VOL=2
ONLINE_DRC_BEEP_TONE=500
ONLINE_NET_MODE=DISABLED
ONLINE_NET_STAT=RED
ONLINE_NET_TIME=0
ONLINE_NET_BEEP_VOL=2
ONLINE_NET_BEEP_TONE=1000

### steps/pcb/attrlist
UNITS=MM
.out_drill_full = no
.out_drill_optional = no
.out_rout_optional = no
.array_with_rotation = no
.flipped_out_of_date = no
.comment = 
.out_name = 
.assembly_proc_top = 
.assembly_proc_bottom = 
.all_eda_layers = 
.etm_tester = 
.flipped_of = 
.pnl_scheme = 
.pnl_pcb = 
.pnl_class = 
.pnl_place = 
.fs_direction_top = right2left
.fs_direction_bottom = right2left
.smt_direction_top = right2left
.smt_direction_bottom = right2left
.viacap_layer = none
.etm_pin_style = regular
.etm_repear_fmt = none
.out_drill_order = 0
.out_rout_order = 0
.etm_adapter_h = 95250.000000
.gold_plating = no

### steps/pcb/layers/bottom_overlay/attrlist
UNITS=MM
.out_mirror = no
.lpol_done = no
.cu_base = no
.comment =
.inp_file =
.eda_layers = "BottomOverlay"
.out_angle = 0.0
.out_polarity = positive
.layer_hdi_type = buildup
.out_x_scale = 1.000000
.out_y_scale = 1.000000
.out_comp = 0.000000
.et_adjacency = 508.000000
.layer_dielectric = 0.00254

### steps/pcb/layers/bottom_paste/attrlist
UNITS=MM
.out_mirror = no
.lpol_done = no
.cu_base = no
.comment =
.inp_file =
.eda_layers = "BottomPaste"
.out_angle = 0.0
.out_polarity = positive
.layer_hdi_type = buildup
.out_x_scale = 1.000000
.out_y_scale = 1.000000
.out_comp = 0.000000
.et_adjacency = 508.000000
.layer_dielectric = 0.00254

### steps/pcb/layers/bottom_solder/attrlist
UNITS=MM
.out_mirror = no
.lpol_done = no
.cu_base = no
.comment =
.inp_file =
.eda_layers = "BottomSolderMask"
.out_angle = 0.0
.out_polarity = positive
.layer_hdi_type = buildup
.out_x_scale = 1.000000
.out_y_scale = 1.000000
.out_comp = 0.000000
.et_adjacency = 508.000000
.layer_dielectric = 0.01778
.loss_tangent = 0
.dielectric_constant = 3.5
.comment = Solder Resist

### steps/pcb/layers/dielectric_1/attrlist
UNITS=MM
.out_mirror = no
.lpol_done = no
.cu_base = no
.comment =
.inp_file =
.eda_layers = "Dielectric1"
.out_angle = 0.0
.out_polarity = positive
.layer_hdi_type = buildup
.out_x_scale = 1.000000
.out_y_scale = 1.000000
.out_comp = 0.000000
.et_adjacency = 508.000000
.layer_dielectric = 0.11735
.loss_tangent = 0
.dielectric_constant = 4.1
.comment = 2x106

### steps/pcb/layers/dielectric_2/attrlist
UNITS=MM
.out_mirror = no
.lpol_done = no
.cu_base = no
.comment =
.inp_file =
.eda_layers = "Dielectric2"
.out_angle = 0.0
.out_polarity = positive
.layer_hdi_type = buildup
.out_x_scale = 1.000000
.out_y_scale = 1.000000
.out_comp = 0.000000
.et_adjacency = 508.000000
.layer_dielectric = 1.12268
.loss_tangent = 0
.dielectric_constant = 4.2
.comment = FR4

### steps/pcb/layers/dielectric_3/attrlist
UNITS=MM
.out_mirror = no
.lpol_done = no
.cu_base = no
.comment =
.inp_file =
.eda_layers = "Dielectric3"
.out_angle = 0.0
.out_polarity = positive
.layer_hdi_type = buildup
.out_x_scale = 1.000000
.out_y_scale = 1.000000
.out_comp = 0.000000
.et_adjacency = 508.000000
.layer_dielectric = 0.11735
.loss_tangent = 0
.dielectric_constant = 4.1
.comment = 2x106

### steps/pcb/layers/drill_non-plated_bottom-top/attrlist
UNITS=MM
.out_mirror = no
.lpol_done = no
.cu_base = no
.comment =
.inp_file =
.eda_layers = ""
.out_angle = 0.0
.out_polarity = positive
.layer_hdi_type = buildup
.out_x_scale = 1.000000
.out_y_scale = 1.000000
.out_comp = 0.000000
.et_adjacency = 508.000000
.layer_dielectric = 0.00254

### steps/pcb/layers/drill_plated_bottom-top/attrlist
UNITS=MM
.out_mirror = no
.lpol_done = no
.cu_base = no
.comment =
.inp_file =
.eda_layers = ""
.out_angle = 0.0
.out_polarity = positive
.layer_hdi_type = buildup
.out_x_scale = 1.000000
.out_y_scale = 1.000000
.out_comp = 0.000000
.et_adjacency = 508.000000
.layer_dielectric = 0.00254

### steps/pcb/layers/l01-top_layer/attrlist
UNITS=MM
.out_mirror = no
.lpol_done = no
.cu_base = no
.comment =
.inp_file =
.eda_layers = "L01-TopLayer"
.out_angle = 0.0
.out_polarity = positive
.layer_hdi_type = buildup
.out_x_scale = 1.000000
.out_y_scale = 1.000000
.out_comp = 0.000000
.et_adjacency = 508.000000
.layer_dielectric = 0.11735
.copper_weight = 71.12
.dielectric_constant = 1

### steps/pcb/layers/l02-inner_layer/attrlist
UNITS=MM
.out_mirror = no
.lpol_done = no
.cu_base = no
.comment =
.inp_file =
.eda_layers = "L02-InnerLayer"
.out_angle = 0.0
.out_polarity = positive
.layer_hdi_type = buildup
.out_x_scale = 1.000000
.out_y_scale = 1.000000
.out_comp = 0.000000
.et_adjacency = 508.000000
.layer_dielectric = 1.12268
.copper_weight = 35.56
.dielectric_constant = 1

### steps/pcb/layers/l03-inner_layer/attrlist
UNITS=MM
.out_mirror = no
.lpol_done = no
.cu_base = no
.comment =
.inp_file =
.eda_layers = "L03-InnerLayer"
.out_angle = 0.0
.out_polarity = positive
.layer_hdi_type = buildup
.out_x_scale = 1.000000
.out_y_scale = 1.000000
.out_comp = 0.000000
.et_adjacency = 508.000000
.layer_dielectric = 0.11735
.copper_weight = 35.56
.dielectric_constant = 1

### steps/pcb/layers/l04-bottom_layer/attrlist
UNITS=MM
.out_mirror = no
.lpol_done = no
.cu_base = no
.comment =
.inp_file =
.eda_layers = "L04-BottomLayer"
.out_angle = 0.0
.out_polarity = positive
.layer_hdi_type = buildup
.out_x_scale = 1.000000
.out_y_scale = 1.000000
.out_comp = 0.000000
.et_adjacency = 508.000000
.layer_dielectric = 0.01778
.copper_weight = 71.12
.dielectric_constant = 1

### steps/pcb/layers/top_overlay/attrlist
UNITS=MM
.out_mirror = no
.lpol_done = no
.cu_base = no
.comment =
.inp_file =
.eda_layers = "TopOverlay"
.out_angle = 0.0
.out_polarity = positive
.layer_hdi_type = buildup
.out_x_scale = 1.000000
.out_y_scale = 1.000000
.out_comp = 0.000000
.et_adjacency = 508.000000
.layer_dielectric = 0.00254

### steps/pcb/layers/top_paste/attrlist
UNITS=MM
.out_mirror = no
.lpol_done = no
.cu_base = no
.comment =
.inp_file =
.eda_layers = "TopPaste"
.out_angle = 0.0
.out_polarity = positive
.layer_hdi_type = buildup
.out_x_scale = 1.000000
.out_y_scale = 1.000000
.out_comp = 0.000000
.et_adjacency = 508.000000
.layer_dielectric = 0.00254

### steps/pcb/layers/top_solder/attrlist
UNITS=MM
.out_mirror = no
.lpol_done = no
.cu_base = no
.comment =
.inp_file =
.eda_layers = "TopSolderMask"
.out_angle = 0.0
.out_polarity = positive
.layer_hdi_type = buildup
.out_x_scale = 1.000000
.out_y_scale = 1.000000
.out_comp = 0.000000
.et_adjacency = 508.000000
.layer_dielectric = 0.01778
.loss_tangent = 0
.dielectric_constant = 3.5
.comment = Solder Resist

### steps/pcb/profile
UNITS=MM
#
#Layer features
#
S P 0
OB -5.06000004 -2.06000096 I
OS -5.06000766 42.74000088
OS -5.06000004 42.74000088
OS -5.06000004 42.9366299
OS -5.00867172 43.32652498
OS -4.9068863 43.70638706
OS -4.75639384 44.0697112
OS -4.55976228 44.4102871
OS -4.32035966 44.72228038
OS -4.042283 45.00035704
OS -3.73028972 45.23975966
OS -3.38971382 45.43639122
OS -3.02638968 45.58688368
OS -2.6465276 45.6886691
OS -2.25663252 45.73999996
OS -2.06000096 45.73999996
OS -2.06000096 45.73999996
OS -2.16000076 45.74000504
OS 42.74000088 45.73999996
OS 42.9366299 45.73999996
OS 43.32652498 45.6886691
OS 43.70638706 45.58688368
OS 44.0697112 45.43639122
OS 44.4102871 45.23975966
OS 44.72228038 45.00035704
OS 45.00035704 44.72228038
OS 45.23975966 44.4102871
OS 45.43639122 44.0697112
OS 45.58688368 43.70638706
OS 45.6886691 43.32652498
OS 45.73999996 42.9366299
OS 45.73999996 42.74000088
OS 45.73999996 42.74000088
OS 45.73999742 42.74000088
OS 45.73999996 -2.06000096
OS 45.73999996 -2.25663252
OS 45.6886691 -2.6465276
OS 45.58688368 -3.02638968
OS 45.43639122 -3.38971382
OS 45.23975966 -3.73028972
OS 45.00035704 -4.042283
OS 44.72228038 -4.32035966
OS 44.4102871 -4.55976228
OS 44.0697112 -4.75639384
OS 43.70638706 -4.9068863
OS 43.32652498 -5.00867172
OS 42.9366299 -5.06000004
OS 42.74000088 -5.06000004
OS 42.74000088 -5.06000004
OS -2.06000096 -5.06000512
OS -2.06000096 -5.06000004
OS -2.25663252 -5.06000004
OS -2.6465276 -5.00867172
OS -3.02638968 -4.9068863
OS -3.38971382 -4.75639384
OS -3.73028972 -4.55976228
OS -4.042283 -4.32035966
OS -4.32035966 -4.042283
OS -4.55976228 -3.73028972
OS -4.75639384 -3.38971382
OS -4.9068863 -3.02638968
OS -5.00867172 -2.6465276
OS -5.06000004 -2.25663252
OS -5.06000004 -2.06000096
OE
SE

### steps/pcb/eda/data
# 1/24/2023 5:18:01 PM
#
HDR Altium Designer file - Version 1.0.0.30000
UNITS=MM
LYR dielectric_1 dielectric_2 dielectric_3 drill_non-plated_bottom-top drill_plated_bottom-top top_paste l02-inner_layer bottom_solder l04-bottom_layer bottom_paste top_overlay bottom_overlay l03-inner_layer l01-top_layer m01_pcb_outline top_solder 
#
#NET 0
NET $NONE$
SNT PLN S C 0.00
FID C 13 66
SNT PLN S C 0.00
FID C 13 60
SNT PLN S C 0.00
FID C 13 64
SNT PLN S C 0.00
FID C 13 61
SNT PLN S C 0.00
FID C 13 59
SNT PLN S C 0.00
FID C 13 62
SNT PLN S C 0.00
FID C 13 58
SNT PLN S C 0.00
FID C 13 63
SNT VIA
FID C 13 57
FID C 15 60
SNT VIA
FID C 13 25
FID C 15 24
SNT VIA
FID C 13 26
FID C 15 25
SNT TOP B 1 1
FID C 7 92
FID C 8 121
FID C 9 68
SNT TOP B 2 1
FID C 7 90
FID C 8 120
FID C 9 67
SNT TOP B 3 1
FID C 7 29
FID C 8 63
FID C 9 24
SNT VIA
FID C 7 113
FID C 8 142
SNT VIA
FID C 7 112
FID C 8 141
SNT VIA
FID C 7 24
FID C 8 59
SNT TOP B 21 4
FID C 7 74
FID C 8 105
FID C 9 54
SNT TOP B 0 1
FID C 7 31
FID C 8 64
FID C 9 25
SNT TOP B 1 0
FID H 4 18
FID C 7 91
FID C 15 46
SNT TOP B 2 0
FID H 4 17
FID C 7 89
FID C 15 45
SNT TOP B 3 0
FID H 4 3
FID C 7 28
FID C 15 29
SNT TOP B 30 0
FID H 3 1
FID C 7 78
FID C 8 109
FID C 13 43
FID C 15 44
SNT TOP T 0 1
FID H 4 10
FID C 7 36
FID C 8 69
FID C 13 34
FID C 15 35
SNT TOP T 0 0
FID H 4 12
FID C 7 38
FID C 8 72
FID C 13 36
FID C 15 37
SNT TOP B 0 0
FID H 4 4
FID C 7 30
FID C 15 30
SNT TOP T 1 0
FID H 4 11
FID C 7 39
FID C 8 71
FID C 13 37
FID C 15 38
SNT TOP T 1 1
FID H 4 9
FID C 7 37
FID C 8 70
FID C 13 35
FID C 15 36
SNT TOP B 29 0
FID H 3 0
FID C 7 77
FID C 8 108
FID C 13 42
FID C 15 43
#NET 1
NET NetR5_1
SNT TOP B 16 0
FID C 7 62
FID C 8 94
FID C 9 43
SNT TOP B 21 3
FID C 7 58
FID C 8 91
FID C 9 40
SNT TOP B 15 0
FID C 7 50
FID C 8 83
FID C 9 32
SNT TRC
FID C 8 25
SNT TRC
FID C 8 27
SNT TRC
FID C 8 28
SNT TRC
FID C 8 23
#NET 2
NET NetC9_1
SNT TOP B 16 1
FID C 7 63
FID C 8 95
FID C 9 44
SNT TOP B 17 0
FID C 7 64
FID C 8 96
FID C 9 45
SNT TRC
FID C 8 29
#NET 3
NET NetC4_2
SNT TOP B 19 0
FID C 7 46
FID C 8 79
FID C 9 28
SNT TOP B 28 1
FID C 7 48
FID C 8 81
FID C 9 30
SNT TOP B 21 2
FID C 7 57
FID C 8 90
FID C 9 39
SNT TOP B 14 1
FID C 7 47
FID C 8 80
FID C 9 29
SNT TRC
FID C 8 22
SNT TRC
FID C 8 19
SNT TRC
FID C 8 21
SNT TRC
FID C 8 20
SNT TRC
FID C 8 0
SNT TRC
FID C 8 1
#NET 4
NET SW
SNT PLN S C 0.00
FID C 8 144
SNT TOP B 24 1
FID C 7 76
FID C 8 107
FID C 9 56
SNT TOP B 21 6
FID C 7 72
FID C 8 103
FID C 9 52
SNT TOP B 21 8
FID C 7 65
FID C 8 97
FID C 9 46
SNT TOP B 18 0
FID C 7 79
FID C 8 110
FID C 9 57
SNT TRC
FID C 8 30
SNT TRC
FID C 8 31
SNT TRC
FID C 8 32
SNT TRC
FID C 8 34
SNT TRC
FID C 8 33
SNT TRC
FID C 8 38
SNT TRC
FID C 8 39
SNT TRC
FID C 8 40
SNT TRC
FID C 8 6
#NET 5
NET NetC3_1
SNT TOP B 24 0
FID C 7 75
FID C 8 106
FID C 9 55
SNT TOP B 21 5
FID C 7 73
FID C 8 104
FID C 9 53
SNT TRC
FID C 8 36
SNT TRC
FID C 8 37
SNT TRC
FID C 8 35
SNT TRC
FID C 8 4
SNT TRC
FID C 8 5
SNT TRC
FID C 8 3
#NET 6
NET +3.3V_OSC
SNT PLN S C 0.00
FID C 8 146
SNT TOP B 26 0
FID C 7 107
FID C 8 136
FID C 9 73
SNT TOP B 27 0
FID C 7 95
FID C 8 124
FID C 9 69
SNT TOP B 22 1
FID C 7 88
FID C 8 119
FID C 9 66
SNT TOP T 0 4
FID H 4 20
FID C 7 93
FID C 8 122
FID C 13 44
FID C 15 47
SNT TOP T 1 4
FID H 4 19
FID C 7 94
FID C 8 123
FID C 13 45
FID C 15 48
#NET 7
NET TX
SNT TOP B 7 0
FID H 4 13
FID C 6 63
FID C 7 40
FID C 8 73
FID C 13 38
FID C 15 39
SNT TOP T 0 2
FID H 4 7
FID C 6 61
FID C 7 34
FID C 8 67
FID C 13 32
FID C 15 33
SNT TOP T 1 2
FID H 4 8
FID C 6 62
FID C 7 35
FID C 8 68
FID C 13 33
FID C 15 34
SNT TRC
FID C 6 27
SNT TRC
FID C 6 30
SNT TRC
FID C 6 24
SNT TRC
FID C 6 26
SNT TRC
FID C 6 25
SNT TRC
FID C 6 0
SNT TRC
FID C 6 4
SNT TRC
FID C 6 3
SNT TRC
FID C 6 1
#NET 8
NET RX
SNT TOP B 6 0
FID H 4 14
FID C 6 64
FID C 7 41
FID C 8 74
FID C 13 39
FID C 15 40
SNT TOP T 0 3
FID H 4 5
FID C 6 59
FID C 7 32
FID C 8 65
FID C 13 30
FID C 15 31
SNT TOP T 1 3
FID H 4 6
FID C 6 60
FID C 7 33
FID C 8 66
FID C 13 31
FID C 15 32
SNT TRC
FID C 6 28
SNT TRC
FID C 6 23
SNT TRC
FID C 6 31
SNT TRC
FID C 6 33
SNT TRC
FID C 6 32
SNT TRC
FID C 6 29
SNT TRC
FID C 6 2
SNT TRC
FID C 6 5
SNT TRC
FID C 6 6
#NET 9
NET RF_OUTPUT
SNT TOP T 0 8
FID H 4 28
FID C 7 103
FID C 8 132
FID C 13 53
FID C 15 56
SNT TOP T 1 8
FID H 4 27
FID C 7 102
FID C 8 131
FID C 13 52
FID C 15 55
SNT TOP B 11 0
FID H 4 30
FID C 7 110
FID C 8 139
FID C 13 55
FID C 15 58
SNT TRC
FID C 8 51
SNT TRC
FID C 8 47
SNT TRC
FID C 8 8
#NET 10
NET NC
SNT TOP B 13 0
FID H 4 29
FID C 7 109
FID C 8 138
FID C 13 54
FID C 15 57
#NET 11
NET LOCK
SNT TOP B 8 0
FID H 4 2
FID C 7 27
FID C 8 62
FID C 13 29
FID C 15 28
#NET 12
NET 1PPS_OUT
SNT TOP T 0 7
FID H 4 26
FID C 6 72
FID C 7 101
FID C 8 130
FID C 13 51
FID C 15 54
SNT TOP T 1 7
FID H 4 25
FID C 6 71
FID C 7 100
FID C 8 129
FID C 13 50
FID C 15 53
SNT TOP B 4 0
FID H 4 16
FID C 6 66
FID C 7 45
FID C 8 78
FID C 13 41
FID C 15 42
SNT TRC
FID C 6 48
SNT TRC
FID C 6 40
SNT TRC
FID C 6 38
SNT TRC
FID C 6 37
SNT TRC
FID C 6 36
SNT TRC
FID C 6 39
SNT TRC
FID C 6 12
SNT TRC
FID C 6 10
SNT TRC
FID C 6 8
#NET 13
NET 1PPS_IN
SNT TOP B 23 1
FID C 7 106
FID C 8 135
FID C 9 72
SNT TOP B 5 0
FID H 4 15
FID C 6 65
FID C 7 42
FID C 8 75
FID C 13 40
FID C 15 41
SNT TOP T 0 6
FID H 4 23
FID C 6 69
FID C 7 98
FID C 8 127
FID C 13 48
FID C 15 51
SNT TOP T 1 6
FID H 4 24
FID C 6 70
FID C 7 99
FID C 8 128
FID C 13 49
FID C 15 52
SNT TRC
FID C 6 34
SNT TRC
FID C 6 35
SNT TRC
FID C 6 42
SNT TRC
FID C 6 41
SNT TRC
FID C 8 46
SNT TRC
FID C 8 48
SNT TRC
FID C 6 7
SNT TRC
FID C 6 9
SNT TRC
FID C 6 11
SNT TRC
FID C 8 7
#NET 14
NET GND
SNT PLN S C 0.00
FID C 13 65
SNT PLN S C 0.00
FID C 13 67
SNT PLN S C 0.00
FID C 8 147
SNT PLN S C 0.00
FID C 6 74
SNT PLN S C 0.00
FID C 12 28
SNT TOP B 19 1
FID C 7 43
FID C 8 76
FID C 9 26
SNT TOP B 26 1
FID C 7 108
FID C 8 137
FID C 9 74
SNT TOP B 32 1
FID C 7 81
FID C 8 112
FID C 9 59
SNT TOP B 33 1
FID C 7 66
FID C 8 98
FID C 9 47
SNT TOP B 34 1
FID C 7 67
FID C 8 99
FID C 9 48
SNT TOP B 35 1
FID C 7 69
FID C 8 101
FID C 9 50
SNT TOP B 17 1
FID C 7 55
FID C 8 88
FID C 9 37
SNT TOP B 20 1
FID C 7 82
FID C 8 113
FID C 9 60
SNT TOP B 27 1
FID C 7 104
FID C 8 133
FID C 9 70
SNT TOP B 31 1
FID C 7 80
FID C 8 111
FID C 9 58
SNT TOP B 25 1
FID C 7 68
FID C 8 100
FID C 9 49
SNT TOP B 21 7
FID C 7 70
FID C 8 102
FID C 9 51
SNT TOP B 15 1
FID C 7 51
FID C 8 84
FID C 9 33
SNT TOP B 23 0
FID C 7 105
FID C 8 134
FID C 9 71
SNT TOP B 12 0
FID H 4 31
FID C 6 73
FID C 7 111
FID C 8 140
FID C 12 27
FID C 13 56
FID C 15 59
SNT TOP T 0 5
FID H 4 22
FID C 6 67
FID C 7 96
FID C 8 125
FID C 12 25
FID C 13 46
FID C 15 49
SNT TOP T 1 5
FID H 4 21
FID C 6 68
FID C 7 97
FID C 8 126
FID C 12 26
FID C 13 47
FID C 15 50
SNT TOP B 10 0
FID H 4 1
FID C 6 58
FID C 7 26
FID C 8 61
FID C 12 24
FID C 13 28
FID C 15 27
SNT TRC
FID C 13 17
SNT VIA
FID H 4 71
FID C 6 120
FID C 8 193
FID C 12 74
FID C 13 113
SNT VIA
FID H 4 72
FID C 6 121
FID C 8 194
FID C 12 75
FID C 13 114
SNT VIA
FID H 4 73
FID C 6 122
FID C 8 195
FID C 12 76
FID C 13 115
SNT VIA
FID H 4 66
FID C 6 115
FID C 8 188
FID C 12 69
FID C 13 108
SNT VIA
FID H 4 67
FID C 6 116
FID C 8 189
FID C 12 70
FID C 13 109
SNT VIA
FID H 4 76
FID C 6 125
FID C 8 198
FID C 12 79
FID C 13 118
SNT VIA
FID H 4 74
FID C 6 123
FID C 8 196
FID C 12 77
FID C 13 116
SNT VIA
FID H 4 68
FID C 6 117
FID C 8 190
FID C 12 71
FID C 13 110
SNT VIA
FID H 4 69
FID C 6 118
FID C 8 191
FID C 12 72
FID C 13 111
SNT VIA
FID H 4 70
FID C 6 119
FID C 8 192
FID C 12 73
FID C 13 112
SNT VIA
FID H 4 63
FID C 6 112
FID C 8 185
FID C 12 66
FID C 13 105
SNT VIA
FID H 4 64
FID C 6 113
FID C 8 186
FID C 12 67
FID C 13 106
SNT VIA
FID H 4 62
FID C 6 111
FID C 8 184
FID C 12 65
FID C 13 104
SNT VIA
FID H 4 61
FID C 6 110
FID C 8 183
FID C 12 64
FID C 13 103
SNT VIA
FID H 4 65
FID C 6 114
FID C 8 187
FID C 12 68
FID C 13 107
SNT VIA
FID H 4 56
FID C 6 105
FID C 8 178
FID C 12 59
FID C 13 98
SNT VIA
FID H 4 75
FID C 6 124
FID C 8 197
FID C 12 78
FID C 13 117
SNT VIA
FID H 4 58
FID C 6 107
FID C 8 180
FID C 12 61
FID C 13 100
SNT VIA
FID H 4 59
FID C 6 108
FID C 8 181
FID C 12 62
FID C 13 101
SNT VIA
FID H 4 81
FID C 6 130
FID C 8 203
FID C 12 84
FID C 13 123
SNT VIA
FID H 4 80
FID C 6 129
FID C 8 202
FID C 12 83
FID C 13 122
SNT VIA
FID H 4 77
FID C 6 126
FID C 8 199
FID C 12 80
FID C 13 119
SNT VIA
FID H 4 94
FID C 6 143
FID C 8 216
FID C 12 97
FID C 13 136
SNT VIA
FID H 4 93
FID C 6 142
FID C 8 215
FID C 12 96
FID C 13 135
SNT VIA
FID H 4 55
FID C 6 104
FID C 8 177
FID C 12 58
FID C 13 97
SNT VIA
FID H 4 53
FID C 6 102
FID C 8 175
FID C 12 56
FID C 13 95
SNT VIA
FID H 4 54
FID C 6 103
FID C 8 176
FID C 12 57
FID C 13 96
SNT VIA
FID H 4 52
FID C 6 101
FID C 8 174
FID C 12 55
FID C 13 94
SNT VIA
FID H 4 91
FID C 6 140
FID C 8 213
FID C 12 94
FID C 13 133
SNT VIA
FID H 4 88
FID C 6 137
FID C 8 210
FID C 12 91
FID C 13 130
SNT VIA
FID H 4 89
FID C 6 138
FID C 8 211
FID C 12 92
FID C 13 131
SNT VIA
FID H 4 83
FID C 6 132
FID C 8 205
FID C 12 86
FID C 13 125
SNT VIA
FID H 4 78
FID C 6 127
FID C 8 200
FID C 12 81
FID C 13 120
SNT VIA
FID H 4 79
FID C 6 128
FID C 8 201
FID C 12 82
FID C 13 121
SNT VIA
FID H 4 32
FID C 6 81
FID C 8 154
FID C 12 35
FID C 13 74
SNT VIA
FID H 4 33
FID C 6 82
FID C 8 155
FID C 12 36
FID C 13 75
SNT VIA
FID H 4 34
FID C 6 83
FID C 8 156
FID C 12 37
FID C 13 76
SNT VIA
FID H 4 35
FID C 6 84
FID C 8 157
FID C 12 38
FID C 13 77
SNT VIA
FID H 4 36
FID C 6 85
FID C 8 158
FID C 12 39
FID C 13 78
SNT VIA
FID H 4 37
FID C 6 86
FID C 8 159
FID C 12 40
FID C 13 79
SNT VIA
FID H 4 38
FID C 6 87
FID C 8 160
FID C 12 41
FID C 13 80
SNT VIA
FID H 4 39
FID C 6 88
FID C 8 161
FID C 12 42
FID C 13 81
SNT VIA
FID H 4 40
FID C 6 89
FID C 8 162
FID C 12 43
FID C 13 82
SNT VIA
FID H 4 41
FID C 6 90
FID C 8 163
FID C 12 44
FID C 13 83
SNT VIA
FID H 4 42
FID C 6 91
FID C 8 164
FID C 12 45
FID C 13 84
SNT VIA
FID H 4 43
FID C 6 92
FID C 8 165
FID C 12 46
FID C 13 85
SNT VIA
FID H 4 44
FID C 6 93
FID C 8 166
FID C 12 47
FID C 13 86
SNT VIA
FID H 4 115
FID C 6 164
FID C 8 237
FID C 12 118
FID C 13 157
SNT VIA
FID H 4 114
FID C 6 163
FID C 8 236
FID C 12 117
FID C 13 156
SNT VIA
FID H 4 113
FID C 6 162
FID C 8 235
FID C 12 116
FID C 13 155
SNT VIA
FID H 4 112
FID C 6 161
FID C 8 234
FID C 12 115
FID C 13 154
SNT VIA
FID H 4 111
FID C 6 160
FID C 8 233
FID C 12 114
FID C 13 153
SNT VIA
FID H 4 110
FID C 6 159
FID C 8 232
FID C 12 113
FID C 13 152
SNT VIA
FID H 4 109
FID C 6 158
FID C 8 231
FID C 12 112
FID C 13 151
SNT VIA
FID H 4 108
FID C 6 157
FID C 8 230
FID C 12 111
FID C 13 150
SNT VIA
FID H 4 107
FID C 6 156
FID C 8 229
FID C 12 110
FID C 13 149
SNT VIA
FID H 4 106
FID C 6 155
FID C 8 228
FID C 12 109
FID C 13 148
SNT VIA
FID H 4 105
FID C 6 154
FID C 8 227
FID C 12 108
FID C 13 147
SNT VIA
FID H 4 104
FID C 6 153
FID C 8 226
FID C 12 107
FID C 13 146
SNT VIA
FID H 4 103
FID C 6 152
FID C 8 225
FID C 12 106
FID C 13 145
SNT VIA
FID H 4 102
FID C 6 151
FID C 8 224
FID C 12 105
FID C 13 144
SNT VIA
FID H 4 101
FID C 6 150
FID C 8 223
FID C 12 104
FID C 13 143
SNT VIA
FID H 4 100
FID C 6 149
FID C 8 222
FID C 12 103
FID C 13 142
SNT VIA
FID H 4 99
FID C 6 148
FID C 8 221
FID C 12 102
FID C 13 141
SNT VIA
FID H 4 98
FID C 6 147
FID C 8 220
FID C 12 101
FID C 13 140
SNT VIA
FID H 4 97
FID C 6 146
FID C 8 219
FID C 12 100
FID C 13 139
SNT VIA
FID H 4 96
FID C 6 145
FID C 8 218
FID C 12 99
FID C 13 138
SNT VIA
FID H 4 95
FID C 6 144
FID C 8 217
FID C 12 98
FID C 13 137
SNT VIA
FID H 4 45
FID C 6 94
FID C 8 167
FID C 12 48
FID C 13 87
SNT VIA
FID H 4 46
FID C 6 95
FID C 8 168
FID C 12 49
FID C 13 88
SNT VIA
FID H 4 47
FID C 6 96
FID C 8 169
FID C 12 50
FID C 13 89
SNT VIA
FID H 4 48
FID C 6 97
FID C 8 170
FID C 12 51
FID C 13 90
SNT VIA
FID H 4 49
FID C 6 98
FID C 8 171
FID C 12 52
FID C 13 91
SNT VIA
FID H 4 50
FID C 6 99
FID C 8 172
FID C 12 53
FID C 13 92
SNT VIA
FID H 4 51
FID C 6 100
FID C 8 173
FID C 12 54
FID C 13 93
SNT VIA
FID H 4 57
FID C 6 106
FID C 8 179
FID C 12 60
FID C 13 99
SNT VIA
FID H 4 60
FID C 6 109
FID C 8 182
FID C 12 63
FID C 13 102
SNT VIA
FID H 4 82
FID C 6 131
FID C 8 204
FID C 12 85
FID C 13 124
SNT VIA
FID H 4 84
FID C 6 133
FID C 8 206
FID C 12 87
FID C 13 126
SNT VIA
FID H 4 85
FID C 6 134
FID C 8 207
FID C 12 88
FID C 13 127
SNT VIA
FID H 4 86
FID C 6 135
FID C 8 208
FID C 12 89
FID C 13 128
SNT VIA
FID H 4 87
FID C 6 136
FID C 8 209
FID C 12 90
FID C 13 129
SNT VIA
FID H 4 90
FID C 6 139
FID C 8 212
FID C 12 93
FID C 13 132
SNT VIA
FID H 4 92
FID C 6 141
FID C 8 214
FID C 12 95
FID C 13 134
#NET 15
NET +5V
SNT PLN S C 0.00
FID C 8 143
SNT TOP B 33 0
FID C 7 61
FID C 8 93
FID C 9 42
SNT TOP B 34 0
FID C 7 52
FID C 8 85
FID C 9 34
SNT TOP B 35 0
FID C 7 54
FID C 8 87
FID C 9 36
SNT TOP B 25 0
FID C 7 53
FID C 8 86
FID C 9 35
SNT TOP B 21 0
FID C 7 60
FID C 8 92
FID C 9 41
SNT TOP B 21 1
FID C 7 56
FID C 8 89
FID C 9 38
SNT TOP B 9 0
FID H 4 0
FID C 7 25
FID C 8 60
FID C 13 27
FID C 15 26
SNT TRC
FID C 8 26
SNT TRC
FID C 8 24
SNT TRC
FID C 8 2
#NET 16
NET +3.3V
SNT PLN S C 0.00
FID C 8 145
SNT TOP B 28 0
FID C 7 49
FID C 8 82
FID C 9 31
SNT TOP B 32 0
FID C 7 85
FID C 8 116
FID C 9 63
SNT TOP B 20 0
FID C 7 83
FID C 8 114
FID C 9 61
SNT TOP B 31 0
FID C 7 84
FID C 8 115
FID C 9 62
SNT TOP B 18 1
FID C 7 86
FID C 8 117
FID C 9 64
SNT TOP B 14 0
FID C 7 44
FID C 8 77
FID C 9 27
SNT TOP B 22 0
FID C 7 87
FID C 8 118
FID C 9 65
# PKG 0
PKG CAPC0603X033N 0.65999868 -0.55999888 -0.20999958 0.55999888 0.20999958
CT
OB 0.30008068 -0.14988032 I
OS -0.29991812 -0.14988032
OS -0.29991812 0.15011908
OS 0.30008068 0.15011908
OS 0.30008068 -0.14988032
OE
CE
PIN 1 S -0.32999934 0 0 U U
CT
OB -0.55999888 0.20999958 I
OS -0.0999998 0.20999958
OS -0.0999998 -0.20999958
OS -0.55999888 -0.20999958
OS -0.55999888 0.20999958
OE
CE
PIN 2 S 0.32999934 0 0 U U
CT
OB 0.0999998 0.20999958 I
OS 0.55999888 0.20999958
OS 0.55999888 -0.20999958
OS 0.0999998 -0.20999958
OS 0.0999998 0.20999958
OE
CE
#
# PKG 1
PKG CAPC1005X055N 0.91999816 -0.75999848 -0.30999938 0.75999848 0.30999938
CT
OB 0.50008028 -0.24989282 I
OS -0.49991772 -0.24989282
OS -0.49991772 0.25010618
OS 0.50008028 0.25010618
OS 0.50008028 -0.24989282
OE
CE
PIN 1 S -0.45999908 0 0 U U
CT
OB -0.75999848 0.30999938 I
OS -0.15999968 0.30999938
OS -0.15999968 -0.30999938
OS -0.75999848 -0.30999938
OS -0.75999848 0.30999938
OE
CE
PIN 2 S 0.45999908 0 0 U U
CT
OB 0.15999968 0.30999938 I
OS 0.75999848 0.30999938
OS 0.75999848 -0.30999938
OS 0.15999968 -0.30999938
OS 0.15999968 0.30999938
OE
CE
#
# PKG 2
PKG CAPC1005X061N 0.91999816 -0.75999848 -0.30999938 0.75999848 0.30999938
CT
OB 0.49995328 -0.24991822 I
OS -0.50004472 -0.24991822
OS -0.50004472 0.25008078
OS 0.49995328 0.25008078
OS 0.49995328 -0.24991822
OE
CE
PIN 1 S -0.45999908 0 0 U U
CT
OB -0.75999848 0.30999938 I
OS -0.15999968 0.30999938
OS -0.15999968 -0.30999938
OS -0.75999848 -0.30999938
OS -0.75999848 0.30999938
OE
CE
PIN 2 S 0.45999908 0 0 U U
CT
OB 0.15999968 0.30999938 I
OS 0.75999848 0.30999938
OS 0.75999848 -0.30999938
OS 0.15999968 -0.30999938
OS 0.15999968 0.30999938
OE
CE
#
# PKG 3
PKG CAPC2013X140N 1.80000148 -1.54999944 -0.82499708 1.54999944 0.82500216
CT
OB 0.99991926 -0.6249543 I
OS -1.00008182 -0.6249543
OS -1.00008182 0.62504574
OS 0.99991926 0.62504574
OS 0.99991926 -0.6249543
OE
CE
PIN 1 S -0.90000074 0.00000254 0 U U
CT
OB -1.55000071 0.82500216 I
OS -0.25000077 0.82500216
OS -0.25000077 -0.82499708
OS -1.55000071 -0.82499708
OS -1.55000071 0.82500216
OE
CE
PIN 2 S 0.90000074 0.00000254 0 U U
CT
OB 0.25000077 0.82500216 I
OS 1.55000071 0.82500216
OS 1.55000071 -0.82499708
OS 0.25000077 -0.82499708
OS 0.25000077 0.82500216
OE
CE
#
# PKG 4
PKG CAPC2013X145N 1.80000148 -1.54999944 -0.82499708 1.54999944 0.82500216
CT
OB 1.00005642 -0.62491874 I
OS -0.99994466 -0.62491874
OS -0.99994466 0.6250813
OS 1.00005642 0.6250813
OS 1.00005642 -0.62491874
OE
CE
PIN 1 S -0.90000074 0.00000254 0 U U
CT
OB -1.55000071 0.82500216 I
OS -0.25000077 0.82500216
OS -0.25000077 -0.82499708
OS -1.55000071 -0.82499708
OS -1.55000071 0.82500216
OE
CE
PIN 2 S 0.90000074 0.00000254 0 U U
CT
OB 0.25000077 0.82500216 I
OS 1.55000071 0.82500216
OS 1.55000071 -0.82499708
OS 0.25000077 -0.82499708
OS 0.25000077 0.82500216
OE
CE
#
# PKG 5
PKG DiodesInc_AP63356QZV-7 0.4499991 -1.1499977 -1.13124996 1.15000024 1.9750024
CT
OB 1.00000308 -1.13124996 I
OS -0.999998 -1.13124996
OS -0.999998 1.86875166
OS 1.00000308 1.86875166
OS 1.00000308 -1.13124996
OE
CE
PIN 1 S -0.7499985 0.97500186 0 U U
CT
OB -1.14999897 1.70000168 I
OS -0.34999803 1.70000168
OS -0.34999803 0.25000204
OS -1.14999897 0.25000204
OS -1.14999897 1.70000168
OE
CE
PIN 2 S -0.8499983 -0.07499858 0 U U
CT
OB -1.1499977 0.07500112 I
OS -0.5499989 0.07500112
OS -0.5499989 -0.22499828
OS -1.1499977 -0.22499828
OS -1.1499977 0.07500112
OE
CE
PIN 3 S -0.8499983 -0.52499768 0 U U
CT
OB -1.1499977 -0.37499798 I
OS -0.5499989 -0.37499798
OS -0.5499989 -0.67499738
OS -1.1499977 -0.67499738
OS -1.1499977 -0.37499798
OE
CE
PIN 4 S -0.8499983 -0.97499932 0 U U
CT
OB -1.1499977 -0.82499962 I
OS -0.5499989 -0.82499962
OS -0.5499989 -1.12499902
OS -1.1499977 -1.12499902
OS -1.1499977 -0.82499962
OE
CE
PIN 5 S 0.85000084 -0.97499932 0 U U
CT
OB 0.55000144 -0.82499962 I
OS 1.15000024 -0.82499962
OS 1.15000024 -1.12499902
OS 0.55000144 -1.12499902
OS 0.55000144 -0.82499962
OE
CE
PIN 6 S 0.85000084 -0.52499768 0 U U
CT
OB 0.55000144 -0.37499798 I
OS 1.15000024 -0.37499798
OS 1.15000024 -0.67499738
OS 0.55000144 -0.67499738
OS 0.55000144 -0.37499798
OE
CE
PIN 7 S 0.85000084 -0.07499858 0 U U
CT
OB 0.55000144 0.07500112 I
OS 1.15000024 0.07500112
OS 1.15000024 -0.22499828
OS 0.55000144 -0.22499828
OS 0.55000144 0.07500112
OE
CE
PIN 8 S 0.75000104 0.97500186 0 U U
CT
OB 0.35000057 1.70000168 I
OS 1.15000151 1.70000168
OS 1.15000151 0.25000204
OS 0.35000057 0.25000204
OS 0.35000057 1.70000168
OE
CE
PIN 9 S 0.00000254 1.11250222 0 U U
CT
OB -0.14999716 1.9750024 I
OS 0.15000224 1.9750024
OS 0.15000224 0.25000204
OS -0.14999716 0.25000204
OS -0.14999716 1.9750024
OE
CE
#
# PKG 6
PKG Eaton_HCM0703-4R7-R 5.29999956 -3.80000002 -3.30000102 3.80000002 3.30000102
CT
OB 3.55000052 -3.30000102 I
OS -3.55000052 -3.30000102
OS -3.55000052 3.30000102
OS 3.55000052 3.30000102
OS 3.55000052 -3.30000102
OE
CE
PIN 1 S -2.64999978 0 0 U U
CT
OB -3.80000002 1.65000051 I
OS -1.49999954 1.65000051
OS -1.49999954 -1.65000051
OS -3.80000002 -1.65000051
OS -3.80000002 1.65000051
OE
CE
PIN 2 S 2.64999978 0 0 U U
CT
OB 1.49999954 1.65000051 I
OS 3.80000002 1.65000051
OS 3.80000002 -1.65000051
OS 1.49999954 -1.65000051
OS 1.49999954 1.65000051
OE
CE
#
# PKG 7
PKG IQD_ICPT-1 5.08 -22.50001596 -18.00000972 22.49998548 17.99999448
CT
OB 22.49998548 -18.00000972 I
OS -22.50001596 -18.00000972
OS -22.50001596 17.99999448
OS 22.49998548 17.99999448
OS 22.49998548 -18.00000972
OE
CE
PIN 1 T 16.51 -12.7 0 U U
CR 16.51 -12.7 0.89999947
PIN 2 T 16.51 2.54 0 U U
CR 16.51 2.54 0.89999947
PIN 3 T 16.51 7.62 0 U U
CR 16.51 7.62 0.89999947
PIN 4 T 16.51 12.7 0 U U
CR 16.51 12.7 0.89999947
PIN 5 T -16.51 12.7 0 U U
CR -16.51 12.7 0.89999947
PIN 6 T -16.51 7.62 0 U U
CR -16.51 7.62 0.89999947
PIN 7 T -16.51 2.54 0 U U
CR -16.51 2.54 0.89999947
PIN 8 T -16.51 -2.54 0 U U
CR -16.51 -2.54 0.89999947
PIN 9 T -16.51 -12.7 0 U U
CR -16.51 -12.7 0.89999947
#
# PKG 8
PKG Keystone_4871 0 -3.09999888 -3.09999888 3.09999888 3.09999888
CT
OB 2.7813 -2.76943566 I
OS -2.7813 -2.76943566
OS -2.7813 2.76943566
OS 2.7813 2.76943566
OS 2.7813 -2.76943566
OE
CE
PIN Hole T 0 0 0 U U
CR 0 0 1.85000011
PIN MT S 0 0 0 U U
CR 0 0 3.10000015
#
# PKG 9
PKG Microchip_SA45 5.08 -20.32000254 -17.653 20.32 17.653
CT
OB 20.32 -17.653 I
OS -20.32000254 -17.653
OS -20.32000254 17.653
OS 20.32 17.653
OS 20.32 -17.653
OE
CE
PIN 1 T 16.51 -12.7 0 U U
CR 16.51 -12.7 0.762
PIN 4 T 16.51 2.54 0 U U
CR 16.51 2.54 0.762
PIN 5 T 16.51 7.62 0 U U
CR 16.51 7.62 0.762
PIN 6 T 16.51 12.7 0 U U
CR 16.51 12.7 0.762
PIN 7 T -16.51 12.7 0 U U
CR -16.51 12.7 0.78100047
PIN 8 T -16.51 7.62 0 U U
CR -16.51 7.62 0.78100047
PIN 9 T -16.51 2.54 0 U U
CR -16.51 2.54 0.78100047
PIN 10 T -16.51 -2.54 0 U U
CR -16.51 -2.54 0.78100047
PIN 12 T -16.51 -12.7 0 U U
CR -16.51 -12.7 0.78100047
#
# PKG 10
PKG RESC0603X026N 0.67999864 -0.55999888 -0.20999958 0.55999888 0.20999958
CT
OB 0.30011624 -0.14991588 I
OS -0.29988256 -0.14991588
OS -0.29988256 0.15008352
OS 0.30011624 0.15008352
OS 0.30011624 -0.14991588
OE
CE
PIN 1 S -0.33999932 0 0 U U
CT
OB -0.55999888 0.20999958 I
OS -0.11999976 0.20999958
OS -0.11999976 -0.20999958
OS -0.55999888 -0.20999958
OS -0.55999888 0.20999958
OE
CE
PIN 2 S 0.33999932 0 0 U U
CT
OB 0.11999976 0.20999958 I
OS 0.55999888 0.20999958
OS 0.55999888 -0.20999958
OS 0.11999976 -0.20999958
OS 0.11999976 0.20999958
OE
CE
#
# PKG 11
PKG RESC1005X040N 0.95999808 -0.7649972 -0.30999938 0.7649972 0.30999938
CT
OB 0.50008536 -0.24993346 I
OS -0.49991264 -0.24993346
OS -0.49991264 0.25006554
OS 0.50008536 0.25006554
OS 0.50008536 -0.24993346
OE
CE
PIN 1 S -0.47999904 0 0 U U
CT
OB -0.76499847 0.30999938 I
OS -0.19499961 0.30999938
OS -0.19499961 -0.30999938
OS -0.76499847 -0.30999938
OS -0.76499847 0.30999938
OE
CE
PIN 2 S 0.47999904 0 0 U U
CT
OB 0.19499961 0.30999938 I
OS 0.76499847 0.30999938
OS 0.76499847 -0.30999938
OS 0.19499961 -0.30999938
OS 0.19499961 0.30999938
OE
CE
#
# PKG 12
PKG RESC1608X55X30ML15T15 1.44999964 -1.17499892 -0.52500022 1.17499892 0.52500022
CT
OB 0.87499952 -0.47500032 I
OS -0.87499952 -0.47500032
OS -0.87499952 0.47500032
OS 0.87499952 0.47500032
OS 0.87499952 -0.47500032
OE
CE
PIN 1 S -0.72499982 0 0 U U
CT
OB -1.17457982 -0.52324 I
OS -1.17457982 0.52324
OS -0.27541982 0.52324
OS -0.27541982 -0.52324
OS -1.17457982 -0.52324
OE
CE
PIN 2 S 0.72499982 0 0 U U
CT
OB 0.27541982 -0.52324 I
OS 0.27541982 0.52324
OS 1.17457982 0.52324
OS 1.17457982 -0.52324
OS 0.27541982 -0.52324
OE
CE
#
# PKG 13
PKG RESC3216X070N 2.99999908 -2.02499976 -0.87499698 2.02499976 0.87500206
CT
OB 1.60006284 -0.79993236 I
OS -1.59993584 -0.79993236
OS -1.59993584 0.80006952
OS 1.60006284 0.80006952
OS 1.60006284 -0.79993236
OE
CE
PIN 1 S -1.49999954 0.00000254 0 U U
CT
OB -2.02499976 0.87500206 I
OS -0.97499932 0.87500206
OS -0.97499932 -0.87499698
OS -2.02499976 -0.87499698
OS -2.02499976 0.87500206
OE
CE
PIN 2 S 1.49999954 0.00000254 0 U U
CT
OB 0.97499932 0.87500206 I
OS 2.02499976 0.87500206
OS 2.02499976 -0.87499698
OS 0.97499932 -0.87499698
OS 0.97499932 0.87500206
OE
CE
#
# PKG 14
PKG TH000V_300DIAx400_001mt_9774040243R 0 -2.64999978 -2.64999978 2.64999978 2.64999978
CT
OB 2.17499946 -2.16308432 I
OS -2.17499946 -2.16308432
OS -2.17499946 2.16308432
OS 2.17499946 2.16308432
OS 2.17499946 -2.16308432
OE
CE
PIN MT1 T 0 0 0 U U
CR 0 0 2.64999978
#
# PKG 15
PKG TH001V_109DIA_000mt_8600-0 0 -1.04499918 -1.06499914 1.04499918 1.02499922
CT
OB 0.9144 -0.91428824 I
OS -0.9144 -0.91428824
OS -0.9144 0.91428824
OS 0.9144 0.91428824
OS 0.9144 -0.91428824
OE
CE
PIN 1 T 0 -0.01999996 0 U U
CR 0 -0.01999996 1.04500045
#
# PKG 16
PKG TH001V_109DIA_000mt_8600-0_1 0 -1.04499918 -1.04499918 1.04499918 1.04499918
CT
OB 0.9144 -0.91428824 I
OS -0.9144 -0.91428824
OS -0.9144 0.91428824
OS 0.9144 0.91428824
OS 0.9144 -0.91428824
OE
CE
PIN 1 T 0 0 0 U U
CR 0 0 1.04500045
#
# PKG 17
PKG TH001V_109DIA_000mt_8600-0_1_2 0 -1.04499918 -1.0849991 1.04499918 1.00499926
CT
OB 0.9144 -0.91428824 I
OS -0.9144 -0.91428824
OS -0.9144 0.91428824
OS 0.9144 0.91428824
OS 0.9144 -0.91428824
OE
CE
PIN 1 T 0 -0.03999992 0 U U
CR 0 -0.03999992 1.04500045
#
# PKG 18
PKG TH001V_109DIA_000mt_8600-0_1_2_3 0 -1.00499926 -1.0849991 1.0849991 1.00499926
CT
OB 0.9144 -0.91428824 I
OS -0.9144 -0.91428824
OS -0.9144 0.91428824
OS 0.9144 0.91428824
OS 0.9144 -0.91428824
OE
CE
PIN 1 T 0.03999992 -0.03999992 0 U U
CR 0.03999992 -0.03999992 1.04500045
#
# PKG 19
PKG TH001V_109DIA_000mt_8600-0_1_2_3_4 0 -1.00499926 -1.04499918 1.0849991 1.04499918
CT
OB 0.9144 -0.91428824 I
OS -0.9144 -0.91428824
OS -0.9144 0.91428824
OS 0.9144 0.91428824
OS 0.9144 -0.91428824
OE
CE
PIN 1 T 0.03999992 0 0 U U
CR 0.03999992 0 1.04500045
#

### steps/pcb/netlists/cadnet/netlist
UNITS=MM
H optimize n staggered n
$0 $NONE$
$1 +3.3V
$2 +3.3V_OSC
$3 +5V
$4 1PPS_IN
$5 1PPS_OUT
$6 GND
$7 LOCK
$8 NC
$9 NetC3_1
$10 NetC4_2
$11 NetC9_1
$12 NetR5_1
$13 RF_OUTPUT
$14 RX
$15 SW
$16 TX
#
#Netlist points
#
0 1.49999954 20.24000016 42.13999954 B e e staggered 0 0 0
0 0.381 4.8300005 33.03999996 B e e staggered 0 0 0
0 0.381 4.8300005 17.79999996 B e e staggered 0 0 0
0 1.84999884 4.39999882 38.599999 B e e staggered 0 0 0
0 0.5999988 4.8300005 17.79999996 B e e staggered 0 0 0
0 0.5999988 4.8300005 33.03999996 B e e staggered 0 0 0
0 1.49999954 20.43999976 -1.26000002 B e e staggered 0 0 0
0 1.84999884 4.39999882 2.00000108 B e e staggered 0 0 0
0 1.84999884 35.50000012 -1.00000054 B e e staggered 0 0 0
0 1.84999884 36.20000126 40.10000108 B e e staggered 0 0 0
0 0 4.39999882 38.599999 D 6.2000003 6.2000003 e p
0 0 18.0150008 18.94000276 D 0.5999988 0.2999994 e p
0 0 -2.38499904 43.5150006 D 1.00000054 1.00000054 e p
0 0 43.11499886 43.5150006 D 1.00000054 1.00000054 e p
0 0 43.18999998 -2.80999946 D 1.00000054 1.00000054 e p
0 0 4.39999882 2.00000108 D 6.2000003 6.2000003 e p
0 0 35.50000012 -1.00000054 D 6.2000003 6.2000003 e p
0 0 36.20000126 40.10000108 D 6.2000003 6.2000003 e p
0 0 -2.37499906 43.52500058 T 1.00000054 1.00000054 e s
0 0 -2.20000068 -2.69999968 T 1.00000054 1.00000054 e s
0 0 43.12499884 43.52500058 T 1.00000054 1.00000054 e s
1 0 32.24000156 7.63999996 D 1.05000044 1.74999904 e p
1 0 13.9050014 19.16500104 D 0.56999886 0.61999876 e p
1 0 26.06499994 16.85250122 D 2.30000048 3.30000102 e p
1 0 24.21500364 7.7900022 D 1.29999994 1.64999924 e p
1 0 23.87500178 12.29000082 D 0.5999988 0.61999876 e p
1 0 24.21500364 10.29000228 D 1.29999994 1.64999924 e p
1 0 14.86499948 20.87500016 D 0.41999916 0.45999908 e p
2 0.4809998 37.8500005 7.63999996 B e e staggered 0 0 0
2 0.5999988 37.8500005 7.63999996 B e e staggered 0 0 0
2 0 35.24000064 7.63999996 D 1.05000044 1.74999904 e p
2 0 37.8500005 9.94000044 D 0.5999988 0.61999876 e p
2 0 40.0900011 7.63999996 D 0.61999876 0.5999988 e p
3 0.54500018 0 0 B e e staggered 0 0 0
3 0 16.31500166 18.04000202 D 0.5999988 0.2999994 e p
3 0 16.41500146 16.99000158 D 0.80000094 1.44999964 e p
3 0 15.91499992 9.7899982 D 1.29999994 1.64999924 e p
3 0 15.91499992 12.39000062 D 1.29999994 1.64999924 e p
3 0 15.91499992 7.38999792 D 1.29999994 1.64999924 e p
3 0 16.65500352 14.7900009 D 0.5999988 0.61999876 e p
4 0.4809998 37.8500005 17.79999996 B e e staggered 0 0 0
4 0.5999988 37.8500005 17.79999996 B e e staggered 0 0 0
4 0.54500018 11.2219994 43.3299997 B e e staggered 0 0 0
4 0 39.78999916 15.96499982 D 1.05000044 0.90000074 e p
5 0.54500018 14.2699994 43.3299997 B e e staggered 0 0 0
5 0.4809998 37.8500005 22.87999996 B e e staggered 0 0 0
5 0.5999988 37.8500005 22.87999996 B e e staggered 0 0 0
6 0.54500018 0 40.64 B e e staggered 0 0 0
6 0.4809998 37.8500005 12.71999996 B e e staggered 0 0 0
6 0.5999988 37.8500005 12.71999996 B e e staggered 0 0 0
6 0.54500018 40.67999992 20.33999996 B e e staggered 0 0 0
6 0 39.78999916 14.51500018 D 1.05000044 0.90000074 e p
6 0 15.86500002 20.89500012 D 0.41999916 0.43999912 e p
6 0 17.915001 16.99000158 D 0.80000094 1.44999964 e p
6 0 17.7150014 9.7899982 D 1.29999994 1.64999924 e p
6 0 22.41500216 7.7900022 D 1.29999994 1.64999924 e p
6 0 38.76999866 9.94000044 D 0.5999988 0.61999876 e p
6 0 22.95500362 12.29000082 D 0.5999988 0.61999876 e p
6 0 16.29499916 22.29000114 D 0.45999908 0.41999916 e p
6 0 17.7150014 12.39000062 D 1.29999994 1.64999924 e p
6 0 17.7150014 7.38999792 D 1.29999994 1.64999924 e p
6 0 17.57500168 14.7900009 D 0.5999988 0.61999876 e p
6 0 22.41500216 10.29000228 D 1.29999994 1.64999924 e p
6 0 40.0900011 8.55999812 D 0.61999876 0.5999988 e p
6 0 13.9050014 18.0150008 D 0.56999886 0.61999876 e p
6 0.1499997 40.50000028 -3.50000062 B e c staggered 0 0 0 v
6 0.1499997 38.4999992 -3.50000062 B e c staggered 0 0 0 v
6 0.1499997 32.50000104 -3.50000062 B e c staggered 0 0 0 v
6 0.1499997 30.49999996 -3.50000062 B e c staggered 0 0 0 v
6 0.1499997 28.50000142 -3.50000062 B e c staggered 0 0 0 v
6 0.1499997 26.50000034 -3.50000062 B e c staggered 0 0 0 v
6 0.1499997 24.49999926 -3.50000062 B e c staggered 0 0 0 v
6 0.1499997 16.50000002 -3.99999962 B e c staggered 0 0 0 v
6 0.1499997 14.50000148 -3.99999962 B e c staggered 0 0 0 v
6 0.1499997 12.5000004 -3.99999962 B e c staggered 0 0 0 v
6 0.1499997 10.49999932 -3.99999962 B e c staggered 0 0 0 v
6 0.1499997 8.50000078 -3.99999962 B e c staggered 0 0 0 v
6 0.1499997 6.4999997 -3.99999962 B e c staggered 0 0 0 v
6 0.1499997 4.50000116 -3.99999962 B e c staggered 0 0 0 v
6 0.1499997 2.50000008 -3.99999962 B e c staggered 0 0 0 v
6 0.1499997 0.50000154 -3.99999962 B e c staggered 0 0 0 v
6 0.1499997 44.4999999 0.499999 B e c staggered 0 0 0 v
6 0.1499997 44.4999999 2.50000008 B e c staggered 0 0 0 v
6 0.1499997 44.4999999 4.49999862 B e c staggered 0 0 0 v
6 0.1499997 44.4999999 6.4999997 B e c staggered 0 0 0 v
6 0.1499997 44.4999999 8.49999824 B e c staggered 0 0 0 v
6 0.1499997 44.4999999 10.49999932 B e c staggered 0 0 0 v
6 0.1499997 44.4999999 12.49999786 B e c staggered 0 0 0 v
6 0.1499997 44.4999999 14.49999894 B e c staggered 0 0 0 v
6 0.1499997 44.4999999 16.50000002 B e c staggered 0 0 0 v
6 0.1499997 44.4999999 18.49999856 B e c staggered 0 0 0 v
6 0.1499997 44.4999999 20.49999964 B e c staggered 0 0 0 v
6 0.1499997 44.4999999 22.49999818 B e c staggered 0 0 0 v
6 0.1499997 44.4999999 24.49999926 B e c staggered 0 0 0 v
6 0.1499997 44.4999999 26.4999978 B e c staggered 0 0 0 v
6 0.1499997 44.4999999 28.49999888 B e c staggered 0 0 0 v
6 0.1499997 44.4999999 30.49999996 B e c staggered 0 0 0 v
6 0.1499997 44.4999999 32.4999985 B e c staggered 0 0 0 v
6 0.1499997 44.4999999 34.49999958 B e c staggered 0 0 0 v
6 0.1499997 44.4999999 36.49999812 B e c staggered 0 0 0 v
6 0.1499997 44.4999999 38.4999992 B e c staggered 0 0 0 v
6 0.1499997 44.4999999 40.49999774 B e c staggered 0 0 0 v
6 0.1499997 -2.99999908 39.99999874 B e c staggered 0 0 0 v
6 0.1499997 -2.99999908 38.0000002 B e c staggered 0 0 0 v
6 0.1499997 -2.99999908 35.99999912 B e c staggered 0 0 0 v
6 0.1499997 -2.99999908 34.00000058 B e c staggered 0 0 0 v
6 0.1499997 -2.99999908 31.9999995 B e c staggered 0 0 0 v
6 0.1499997 -2.99999908 30.00000096 B e c staggered 0 0 0 v
6 0.1499997 -2.99999908 27.99999988 B e c staggered 0 0 0 v
6 0.1499997 -2.99999908 25.9999988 B e c staggered 0 0 0 v
6 0.1499997 -2.99999908 24.00000026 B e c staggered 0 0 0 v
6 0.1499997 -2.99999908 21.99999918 B e c staggered 0 0 0 v
6 0.1499997 -2.99999908 20.00000064 B e c staggered 0 0 0 v
6 0.1499997 -2.99999908 17.99999956 B e c staggered 0 0 0 v
6 0.1499997 -2.99999908 16.00000102 B e c staggered 0 0 0 v
6 0.1499997 23.33999904 44.0138312 B e c staggered 0 0 0 v
6 0.1499997 23.29999912 38.90000094 B e c staggered 0 0 0 v
6 0.1499997 25.7999992 38.90000094 B e c staggered 0 0 0 v
6 0.1499997 35.30000052 44.0000009 B e c staggered 0 0 0 v
6 0.1499997 32.80000044 38.90000094 B e c staggered 0 0 0 v
6 0.1499997 39.60000208 38.91499964 B e c staggered 0 0 0 v
6 0.1499997 12.74500118 40.26499948 B e c staggered 0 0 0 v
6 0.1499997 12.74500118 44.63999962 B e c staggered 0 0 0 v
6 0.1499997 12.74500118 41.21500012 B e c staggered 0 0 0 v
6 0.1499997 12.75500116 42.16500076 B e c staggered 0 0 0 v
6 0.1499997 40.67999992 42.76499956 B e c staggered 0 0 0 v
6 0.1499997 42.2249981 38.91499964 B e c staggered 0 0 0 v
6 0.1499997 22.45970616 20.01499934 B e c staggered 0 0 0 v
6 0.1499997 23.4097068 20.04000056 B e c staggered 0 0 0 v
6 0.1499997 24.35970744 20.04000056 B e c staggered 0 0 0 v
6 0.1499997 16.30970576 23.03999964 B e c staggered 0 0 0 v
6 0.1499997 15.88470534 21.56499878 B e c staggered 0 0 0 v
6 0.1499997 21.11499968 11.38590052 B e c staggered 0 0 0 v
6 0.1499997 12.98999942 18.0150008 B e c staggered 0 0 0 v
6 0.1499997 18.8149992 16.85250122 B e c staggered 0 0 0 v
6 0.1499997 17.57500168 13.89000016 B e c staggered 0 0 0 v
6 0.1499997 17.915001 15.69625258 B e c staggered 0 0 0 v
6 0.1499997 18.8149992 15.98270108 B e c staggered 0 0 0 v
6 0.1499997 18.8149992 15.10000028 B e c staggered 0 0 0 v
6 0.1499997 19.01500134 12.39000062 B e c staggered 0 0 0 v
6 0.1499997 19.01500134 11.09000068 B e c staggered 0 0 0 v
6 0.1499997 19.01500134 9.7899982 B e c staggered 0 0 0 v
6 0.1499997 21.11499968 10.28999974 B e c staggered 0 0 0 v
6 0.1499997 22.05919388 12.29000082 B e c staggered 0 0 0 v
6 0.1499997 19.01500134 8.5900006 B e c staggered 0 0 0 v
6 0.1499997 19.01500134 7.39000046 B e c staggered 0 0 0 v
6 0.1499997 21.11499968 8.9899998 B e c staggered 0 0 0 v
6 0.1499997 21.11499968 7.78999966 B e c staggered 0 0 0 v
6 0.1499997 21.11499968 6.76500044 B e c staggered 0 0 0 v
7 0.54500018 2.0779994 43.3299997 B e e staggered 0 0 0
8 0.54500018 40.64 0 B e e staggered 0 0 0
9 0 18.0150008 18.49000112 D 0.5999988 0.2999994 e p
9 0 18.22000166 21.17499956 D 0.5999988 0.61999876 e p
10 0 14.86499948 19.16500104 D 0.56999886 0.61999876 e p
10 0 16.31500166 18.49000112 D 0.5999988 0.2999994 e p
10 0 14.86499948 20.21500148 D 0.41999916 0.45999908 e p
10 0 14.86499948 18.0150008 D 0.56999886 0.61999876 e p
11 0 16.95499784 22.29000114 D 0.45999908 0.41999916 e p
11 0 16.95499784 21.17499956 D 0.61999876 0.56999886 e p
12 0 15.86500002 20.21500148 D 0.41999916 0.43999912 e p
12 0 16.31500166 18.94000276 D 0.5999988 0.2999994 e p
12 0 16.95499784 20.21500148 D 0.61999876 0.56999886 e p
13 0.54500018 40.64 40.64 B e e staggered 0 0 0
13 0.4809998 37.8500005 33.03999996 B e e staggered 0 0 0
13 0.5999988 37.8500005 33.03999996 B e e staggered 0 0 0
14 0.381 4.8300005 7.63999996 B e e staggered 0 0 0
14 0.5999988 4.8300005 7.63999996 B e e staggered 0 0 0
14 0.54500018 8.1739994 43.3299997 B e e staggered 0 0 0
15 0 20.76500038 16.85250122 D 2.30000048 3.30000102 e p
15 0 17.1650025 16.85250122 D 0.2999994 1.72500036 e p
15 0 18.0150008 18.04000202 D 0.5999988 0.2999994 e p
15 0 19.13999982 21.17499956 D 0.5999988 0.61999876 e p
16 0.381 4.8300005 12.71999996 B e e staggered 0 0 0
16 0.5999988 4.8300005 12.71999996 B e e staggered 0 0 0
16 0.54500018 5.1259994 43.3299997 B e e staggered 0 0 0

### steps/pcb/layers/bottom_overlay/features
UNITS=MM
#Layer_Color=32896
#
#Feature symbol names
#
$0 r99.9998

#
#Feature attribute names
#
@0 .nomenclature
@1 .string
@2 .string_angle

#
#Feature attribute text strings
#

#
#Layer features
#
L -9.5600012 -24.45999934 40.4400004 -24.45999934 0 P 0
L -9.5600012 -35.9599992 -9.5600012 -24.45999934 0 P 0
L -9.5600012 -35.9599992 28.439999 -35.9599992 0 P 0
L -9.5600012 -39.45999982 -9.5600012 -35.9599992 0 P 0
L -9.5600012 -39.45999982 28.439999 -39.45999982 0 P 0
L -9.5600012 -42.96000044 -9.5600012 -39.45999982 0 P 0
L -9.5600012 -42.96000044 28.439999 -42.96000044 0 P 0
L -10.0600002 -23.96000034 62.93999858 -23.96000034 0 P 0
L -10.0600002 -43.45999944 -10.0600002 -23.96000034 0 P 0
L -10.0600002 -43.45999944 62.93999858 -43.45999944 0 P 0
L 28.439999 -35.96000174 45.44000056 -35.9599992 0 P 0
L 28.439999 -39.45999982 28.439999 -35.9599992 0 P 0
L 28.439999 -39.46000236 45.44000056 -39.45999982 0 P 0
L 28.439999 -42.96000044 28.439999 -39.45999982 0 P 0
L 28.439999 -42.96000298 45.44000056 -42.96000044 0 P 0
L 33.03999996 6.74000176 34.44000224 6.74000176 0 P 0
L 33.03999996 8.54000324 34.44000224 8.54000324 0 P 0
L 40.4400004 -24.45999934 62.43999958 -24.45999934 0 P 0
L 40.4400004 -35.9599992 40.4400004 -24.45999934 0 P 0
L 45.44000056 -35.9599992 62.43999958 -35.9599992 0 P 0
L 45.44000056 -39.45999982 62.43999958 -39.45999982 0 P 0
L 45.44000056 -42.96000044 45.44000056 -35.9599992 0 P 0
L 45.44000056 -42.96000044 62.43999958 -42.96000044 0 P 0
L 62.43999958 -35.9599992 62.43999958 -24.45999934 0 P 0
L 62.43999958 -42.96000044 62.43999958 -35.9599992 0 P 0
L 62.93999858 -43.45999944 62.93999858 -23.96000034 0 P 0
S P 0
OB -1.93923666 -38.95999828 I
OS -2.01412602 -38.95999828
OS -2.18886786 -38.49586916
OS -2.10565746 -38.49586916
OS -2.00580498 -38.77416172
OS -2.00580498 -38.77508628
OS -2.00488042 -38.77601084
OS -2.00395586 -38.77878452
OS -2.0030313 -38.7815582
OS -2.00025762 -38.7908038
OS -1.99655938 -38.80282308
OS -1.99193658 -38.81669148
OS -1.98638922 -38.832409
OS -1.98176642 -38.84997564
OS -1.97621906 -38.86754228
OS -1.9752945 -38.86569316
OS -1.97436994 -38.86107036
OS -1.97159626 -38.85367388
OS -1.96882258 -38.84257916
OS -1.96419978 -38.83055988
OS -1.95957698 -38.81484236
OS -1.95310506 -38.79820028
OS -1.94663314 -38.77970908
OS -1.84400698 -38.49586916
OS -1.7626457 -38.49586916
OS -1.93923666 -38.95999828
OE
OB -1.48712682 -38.48662356 I
OS -1.47973034 -38.48754812
OS -1.47048474 -38.48939724
OS -1.46031458 -38.49124636
OS -1.4482953 -38.49402004
OS -1.43720058 -38.49679372
OS -1.42425674 -38.50141652
OS -1.41223746 -38.50603932
OS -1.39929362 -38.51251124
OS -1.38634978 -38.51990772
OS -1.37340594 -38.52822876
OS -1.36138666 -38.53839892
OS -1.35029194 -38.54949364
OS -1.34936738 -38.5504182
OS -1.34751826 -38.55226732
OS -1.34474458 -38.55596556
OS -1.34104634 -38.56151292
OS -1.33642354 -38.56798484
OS -1.33180074 -38.57538132
OS -1.32625338 -38.58462692
OS -1.32070602 -38.59572164
OS -1.31515866 -38.60774092
OS -1.3096113 -38.62068476
OS -1.3049885 -38.63547772
OS -1.3003657 -38.65119524
OS -1.29666746 -38.66876188
OS -1.29389378 -38.68725308
OS -1.29204466 -38.70666884
OS -1.2911201 -38.72793372
OS -1.2911201 -38.72885828
OS -1.2911201 -38.73255652
OS -1.2911201 -38.73902844
OS -1.29204466 -38.74827404
OS -1.63875466 -38.74827404
OS -1.63875466 -38.7491986
OS -1.63875466 -38.75197228
OS -1.6378301 -38.75567052
OS -1.6378301 -38.76121788
OS -1.63690554 -38.7676898
OS -1.63505642 -38.77508628
OS -1.63228274 -38.79172836
OS -1.62673538 -38.81021956
OS -1.6193389 -38.83055988
OS -1.60916874 -38.84905108
OS -1.5962249 -38.86569316
OS -1.59530034 -38.86569316
OS -1.59437578 -38.86754228
OS -1.58882842 -38.87216508
OS -1.58050738 -38.878637
OS -1.56941266 -38.88510892
OS -1.5546197 -38.8925054
OS -1.53797762 -38.89897732
OS -1.51948642 -38.90360012
OS -1.50931626 -38.90452468
OS -1.49822154 -38.90544924
OS -1.49082506 -38.90544924
OS -1.48250402 -38.90452468
OS -1.47233386 -38.90267556
OS -1.46123914 -38.89990188
OS -1.4482953 -38.89620364
OS -1.43627602 -38.89065628
OS -1.42425674 -38.8832598
OS -1.42333218 -38.88233524
OS -1.41870938 -38.878637
OS -1.41316202 -38.87308964
OS -1.4066901 -38.86569316
OS -1.39929362 -38.855523
OS -1.39097258 -38.84257916
OS -1.38265154 -38.8277862
OS -1.37525506 -38.81021956
OS -1.29389378 -38.82038972
OS -1.29389378 -38.82131428
OS -1.29481834 -38.8231634
OS -1.2957429 -38.82686164
OS -1.29759202 -38.832409
OS -1.3003657 -38.83795636
OS -1.30313938 -38.84535284
OS -1.31053586 -38.86107036
OS -1.31978146 -38.878637
OS -1.3327253 -38.8971282
OS -1.34751826 -38.91469484
OS -1.36600946 -38.93133692
OS -1.36693402 -38.93133692
OS -1.36878314 -38.93318604
OS -1.37155682 -38.93503516
OS -1.37525506 -38.93780884
OS -1.38080242 -38.94058252
OS -1.38634978 -38.9433562
OS -1.39374626 -38.94705444
OS -1.4020673 -38.95075268
OS -1.4113129 -38.95445092
OS -1.4205585 -38.95814916
OS -1.4436725 -38.96369652
OS -1.46956018 -38.96831932
OS -1.49822154 -38.97016844
OS -1.5083917 -38.97016844
OS -1.51486362 -38.96924388
OS -1.52318466 -38.96831932
OS -1.53335482 -38.9664702
OS -1.54444954 -38.96462108
OS -1.55646882 -38.96277196
OS -1.5823565 -38.95537548
OS -1.5962249 -38.94982812
OS -1.60916874 -38.94428076
OS -1.62303714 -38.93688428
OS -1.63598098 -38.92856324
OS -1.64800026 -38.91931764
OS -1.66001954 -38.90822292
OS -1.6609441 -38.90729836
OS -1.66279322 -38.90544924
OS -1.6655669 -38.901751
OS -1.66926514 -38.89620364
OS -1.67388794 -38.88973172
OS -1.67851074 -38.88233524
OS -1.6840581 -38.87308964
OS -1.68960546 -38.86291948
OS -1.69515282 -38.8509002
OS -1.70070018 -38.83795636
OS -1.70532298 -38.8231634
OS -1.70994578 -38.80744588
OS -1.71364402 -38.7908038
OS -1.7164177 -38.7723126
OS -1.71826682 -38.75289684
OS -1.71919138 -38.73255652
OS -1.71919138 -38.73163196
OS -1.71919138 -38.72700916
OS -1.71919138 -38.7214618
OS -1.71826682 -38.71314076
OS -1.71734226 -38.7029706
OS -1.7164177 -38.69187588
OS -1.71456858 -38.67893204
OS -1.7117949 -38.6659882
OS -1.70439842 -38.63640228
OS -1.69977562 -38.62160932
OS -1.69422826 -38.6058918
OS -1.68683178 -38.59109884
OS -1.67851074 -38.57723044
OS -1.66926514 -38.56336204
OS -1.65909498 -38.5504182
OS -1.65817042 -38.54949364
OS -1.6563213 -38.54764452
OS -1.65262306 -38.54487084
OS -1.64800026 -38.54024804
OS -1.6424529 -38.53562524
OS -1.63505642 -38.53007788
OS -1.62673538 -38.52360596
OS -1.61656522 -38.5180586
OS -1.60639506 -38.51158668
OS -1.59437578 -38.50603932
OS -1.58143194 -38.50049196
OS -1.56756354 -38.49586916
OS -1.55277058 -38.49124636
OS -1.53705306 -38.48847268
OS -1.52041098 -38.48662356
OS -1.50284434 -38.485699
OS -1.49359874 -38.485699
OS -1.48712682 -38.48662356
OE
OB -2.6872057 -39.1375138 I
OS -3.20773298 -39.1375138
OS -3.20773298 -39.08111564
OS -2.6872057 -39.08111564
OS -2.6872057 -39.1375138
OE
OB -2.43387626 -38.48662356 I
OS -2.42555522 -38.48754812
OS -2.41630962 -38.48939724
OS -2.40613946 -38.49124636
OS -2.39412018 -38.49309548
OS -2.36915706 -38.50141652
OS -2.35621322 -38.50603932
OS -2.34326938 -38.51251124
OS -2.33032554 -38.51898316
OS -2.3173817 -38.52822876
OS -2.30536242 -38.53747436
OS -2.29334314 -38.54856908
OS -2.29241858 -38.54949364
OS -2.29056946 -38.55134276
OS -2.28779578 -38.555041
OS -2.28409754 -38.5596638
OS -2.27947474 -38.56613572
OS -2.27392738 -38.57445676
OS -2.26838002 -38.58370236
OS -2.26283266 -38.59387252
OS -2.2572853 -38.60496724
OS -2.25173794 -38.61883564
OS -2.24619058 -38.63270404
OS -2.24156778 -38.64842156
OS -2.23786954 -38.66506364
OS -2.23509586 -38.68263028
OS -2.23324674 -38.70112148
OS -2.23232218 -38.7214618
OS -2.23232218 -38.72238636
OS -2.23232218 -38.72516004
OS -2.23232218 -38.72978284
OS -2.23232218 -38.73625476
OS -2.23324674 -38.74365124
OS -2.2341713 -38.75289684
OS -2.2341713 -38.76214244
OS -2.23602042 -38.7723126
OS -2.2387941 -38.7954266
OS -2.24434146 -38.8185406
OS -2.25081338 -38.8416546
OS -2.26005898 -38.86291948
OS -2.26005898 -38.86384404
OS -2.26098354 -38.8647686
OS -2.26283266 -38.86754228
OS -2.26468178 -38.87124052
OS -2.2711537 -38.88048612
OS -2.27947474 -38.89158084
OS -2.29056946 -38.90452468
OS -2.30443786 -38.91746852
OS -2.32015538 -38.93041236
OS -2.33864658 -38.94243164
OS -2.33957114 -38.94243164
OS -2.3404957 -38.9433562
OS -2.34326938 -38.94520532
OS -2.34789218 -38.94705444
OS -2.35251498 -38.94890356
OS -2.35806234 -38.95075268
OS -2.37193074 -38.95630004
OS -2.38764826 -38.96092284
OS -2.40706402 -38.96554564
OS -2.42740434 -38.96924388
OS -2.44959378 -38.97016844
OS -2.45883938 -38.97016844
OS -2.46623586 -38.96924388
OS -2.4745569 -38.96831932
OS -2.4838025 -38.9664702
OS -2.49489722 -38.96462108
OS -2.50599194 -38.96277196
OS -2.53095506 -38.95537548
OS -2.54482346 -38.94982812
OS -2.5577673 -38.94428076
OS -2.57071114 -38.93688428
OS -2.58365498 -38.92856324
OS -2.59567426 -38.91931764
OS -2.60769354 -38.90822292
OS -2.6086181 -38.90729836
OS -2.61046722 -38.90544924
OS -2.6132409 -38.901751
OS -2.61693914 -38.89620364
OS -2.62156194 -38.88973172
OS -2.62618474 -38.88233524
OS -2.6317321 -38.87308964
OS -2.63727946 -38.86199492
OS -2.64282682 -38.84997564
OS -2.64837418 -38.83610724
OS -2.65299698 -38.82131428
OS -2.65761978 -38.80559676
OS -2.66131802 -38.78803012
OS -2.6640917 -38.76953892
OS -2.66594082 -38.7491986
OS -2.66686538 -38.72793372
OS -2.66686538 -38.7260846
OS -2.66686538 -38.72238636
OS -2.66594082 -38.71591444
OS -2.66594082 -38.70666884
OS -2.66501626 -38.69649868
OS -2.66316714 -38.68355484
OS -2.66131802 -38.670611
OS -2.65761978 -38.65581804
OS -2.65392154 -38.64102508
OS -2.64929874 -38.62530756
OS -2.64375138 -38.60866548
OS -2.6363549 -38.59294796
OS -2.62895842 -38.578155
OS -2.61878826 -38.56336204
OS -2.6086181 -38.54949364
OS -2.59567426 -38.53747436
OS -2.5947497 -38.5365498
OS -2.59290058 -38.53562524
OS -2.58920234 -38.53285156
OS -2.58457954 -38.52915332
OS -2.57903218 -38.52545508
OS -2.5716357 -38.52083228
OS -2.56423922 -38.51620948
OS -2.55499362 -38.51158668
OS -2.54482346 -38.50696388
OS -2.53372874 -38.50234108
OS -2.50876562 -38.49402004
OS -2.48010426 -38.48754812
OS -2.4653113 -38.48662356
OS -2.44959378 -38.485699
OS -2.44034818 -38.485699
OS -2.43387626 -38.48662356
OE
OB -1.01005386 -38.48662356 I
OS -0.9998837 -38.48847268
OS -0.98786442 -38.49217092
OS -0.97492058 -38.49679372
OS -0.96012762 -38.50326564
OS -0.9444101 -38.51158668
OS -0.97307146 -38.58370236
OS -0.97399602 -38.5827778
OS -0.97769426 -38.58092868
OS -0.98324162 -38.578155
OS -0.9906381 -38.57538132
OS -0.99895914 -38.57260764
OS -1.0091293 -38.56983396
OS -1.01929946 -38.56798484
OS -1.02946962 -38.56706028
OS -1.03409242 -38.56706028
OS -1.03871522 -38.56798484
OS -1.04518714 -38.5689094
OS -1.05165906 -38.57075852
OS -1.0599801 -38.5735322
OS -1.06830114 -38.57723044
OS -1.07569762 -38.5827778
OS -1.07662218 -38.58370236
OS -1.07939586 -38.58555148
OS -1.08216954 -38.58924972
OS -1.08679234 -38.59387252
OS -1.09141514 -38.60034444
OS -1.09603794 -38.60774092
OS -1.10066074 -38.61606196
OS -1.10435898 -38.62623212
OS -1.10528354 -38.62808124
OS -1.1062081 -38.6336286
OS -1.10805722 -38.64194964
OS -1.1108309 -38.65304436
OS -1.11360458 -38.66691276
OS -1.1154537 -38.68263028
OS -1.11637826 -38.69927236
OS -1.11730282 -38.71776356
OS -1.11730282 -38.95999828
OS -1.19589042 -38.95999828
OS -1.19589042 -38.49586916
OS -1.1246993 -38.49586916
OS -1.1246993 -38.56613572
OS -1.12377474 -38.56521116
OS -1.1200765 -38.55873924
OS -1.1154537 -38.5504182
OS -1.10805722 -38.54024804
OS -1.10066074 -38.53007788
OS -1.0923397 -38.51898316
OS -1.08401866 -38.50973756
OS -1.07569762 -38.50234108
OS -1.07477306 -38.50141652
OS -1.07199938 -38.4995674
OS -1.06645202 -38.49679372
OS -1.06090466 -38.49402004
OS -1.05350818 -38.49124636
OS -1.04426258 -38.48847268
OS -1.03501698 -38.48662356
OS -1.02484682 -38.485699
OS -1.0183749 -38.485699
OS -1.01005386 -38.48662356
OE
OB 0.00233934 -38.96739476 I
OS 0.00233934 -38.96831932
OS 0.00141478 -38.971093
OS -0.00043434 -38.97479124
OS -0.00228346 -38.97941404
OS -0.00505714 -38.98588596
OS -0.00783082 -38.99328244
OS -0.01430274 -39.00899996
OS -0.02077466 -39.0265666
OS -0.02817114 -39.04413324
OS -0.03556762 -39.05985076
OS -0.03926586 -39.06632268
OS -0.04203954 -39.0727946
OS -0.0429641 -39.07464372
OS -0.04573778 -39.07926652
OS -0.05036058 -39.08573844
OS -0.05590794 -39.09405948
OS -0.06330442 -39.10330508
OS -0.07162546 -39.11255068
OS -0.0799465 -39.12179628
OS -0.09011666 -39.12919276
OS -0.09104122 -39.13011732
OS -0.09473946 -39.13196644
OS -0.10028682 -39.13474012
OS -0.10860786 -39.13843836
OS -0.11785346 -39.1421366
OS -0.12894818 -39.14491028
OS -0.14096746 -39.1467594
OS -0.15483586 -39.14768396
OS -0.1585341 -39.14768396
OS -0.1631569 -39.1467594
OS -0.16962882 -39.1467594
OS -0.1770253 -39.14491028
OS -0.18534634 -39.14306116
OS -0.19459194 -39.14121204
OS -0.2047621 -39.1375138
OS -0.21308314 -39.06447356
OS -0.21215858 -39.06447356
OS -0.20846034 -39.06539812
OS -0.20383754 -39.06632268
OS -0.19829018 -39.0681718
OS -0.18349722 -39.07094548
OS -0.16870426 -39.07187004
OS -0.16408146 -39.07187004
OS -0.15945866 -39.07094548
OS -0.1539113 -39.07094548
OS -0.1400429 -39.0681718
OS -0.13357098 -39.06539812
OS -0.12709906 -39.06262444
OS -0.1261745 -39.06262444
OS -0.12432538 -39.06077532
OS -0.1215517 -39.0589262
OS -0.11785346 -39.05615252
OS -0.10953242 -39.04875604
OS -0.10213594 -39.03858588
OS -0.10213594 -39.03766132
OS -0.10028682 -39.0358122
OS -0.0984377 -39.03211396
OS -0.09658858 -39.0265666
OS -0.09289034 -39.01917012
OS -0.0891921 -39.0080754
OS -0.08364474 -38.99513156
OS -0.07809738 -38.97941404
OS -0.07809738 -38.97848948
OS -0.07624826 -38.97479124
OS -0.07439914 -38.96831932
OS -0.0707009 -38.95999828
OS -0.2463673 -38.49586916
OS -0.1631569 -38.49586916
OS -0.0660781 -38.76491612
OS -0.0660781 -38.76584068
OS -0.06515354 -38.76676524
OS -0.06422898 -38.76953892
OS -0.06330442 -38.77416172
OS -0.0614553 -38.77878452
OS -0.05960618 -38.78433188
OS -0.05498338 -38.79727572
OS -0.04943602 -38.81299324
OS -0.04388866 -38.83148444
OS -0.0383413 -38.8509002
OS -0.03279394 -38.87216508
OS -0.03279394 -38.87124052
OS -0.03186938 -38.8693914
OS -0.03094482 -38.86661772
OS -0.03002026 -38.86291948
OS -0.0290957 -38.85829668
OS -0.02724658 -38.85274932
OS -0.02354834 -38.83888092
OS -0.01892554 -38.8231634
OS -0.01245362 -38.8046722
OS -0.00690626 -38.786181
OS 0.00049022 -38.76676524
OS 0.1003427 -38.49586916
OS 0.1789303 -38.49586916
OS 0.00233934 -38.96739476
OE
OB 0.31668974 -38.42745172 I
OS 0.29542486 -38.54671996
OS 0.24642318 -38.54671996
OS 0.22700742 -38.42745172
OS 0.22700742 -38.32020276
OS 0.31668974 -38.32020276
OS 0.31668974 -38.42745172
OE
OB -0.4821301 -38.48662356 I
OS -0.4682617 -38.48754812
OS -0.45254418 -38.48939724
OS -0.43682666 -38.49217092
OS -0.42110914 -38.49586916
OS -0.40631618 -38.50049196
OS -0.40446706 -38.50141652
OS -0.39984426 -38.50326564
OS -0.39337234 -38.50603932
OS -0.3850513 -38.50973756
OS -0.3758057 -38.51528492
OS -0.3665601 -38.52083228
OS -0.35823906 -38.52822876
OS -0.35084258 -38.53562524
OS -0.34991802 -38.5365498
OS -0.3480689 -38.53932348
OS -0.34529522 -38.54394628
OS -0.34159698 -38.54949364
OS -0.33697418 -38.55781468
OS -0.33327594 -38.56613572
OS -0.3295777 -38.57630588
OS -0.32680402 -38.58832516
OS -0.32680402 -38.58924972
OS -0.32587946 -38.5920234
OS -0.3249549 -38.59757076
OS -0.32403034 -38.60496724
OS -0.32403034 -38.6151374
OS -0.32310578 -38.62715668
OS -0.32218122 -38.6428742
OS -0.32218122 -38.66044084
OS -0.32218122 -38.76584068
OS -0.32218122 -38.76676524
OS -0.32218122 -38.77046348
OS -0.32218122 -38.77601084
OS -0.32218122 -38.78340732
OS -0.32218122 -38.79172836
OS -0.32218122 -38.80189852
OS -0.32125666 -38.82408796
OS -0.32125666 -38.84720196
OS -0.3203321 -38.87031596
OS -0.31940754 -38.88048612
OS -0.31940754 -38.88973172
OS -0.31848298 -38.89805276
OS -0.31755842 -38.90452468
OS -0.31755842 -38.90544924
OS -0.31663386 -38.90914748
OS -0.3157093 -38.91469484
OS -0.31293562 -38.92209132
OS -0.3110865 -38.93041236
OS -0.30738826 -38.93965796
OS -0.30276546 -38.94982812
OS -0.29814266 -38.95999828
OS -0.3804285 -38.95999828
OS -0.38135306 -38.95907372
OS -0.38227762 -38.95537548
OS -0.38412674 -38.95075268
OS -0.38690042 -38.9433562
OS -0.3896741 -38.93503516
OS -0.39152322 -38.924865
OS -0.39337234 -38.91377028
OS -0.39522146 -38.901751
OS -0.39614602 -38.901751
OS -0.39707058 -38.90360012
OS -0.40261794 -38.90822292
OS -0.41093898 -38.91469484
OS -0.4220337 -38.92301588
OS -0.4359021 -38.93133692
OS -0.4497705 -38.94058252
OS -0.46456346 -38.94890356
OS -0.48028098 -38.95537548
OS -0.4821301 -38.95630004
OS -0.48767746 -38.9572246
OS -0.4959985 -38.95999828
OS -0.50616866 -38.96277196
OS -0.5191125 -38.96554564
OS -0.53390546 -38.96739476
OS -0.55054754 -38.96924388
OS -0.56718962 -38.97016844
OS -0.5745861 -38.97016844
OS -0.58013346 -38.96924388
OS -0.58660538 -38.96924388
OS -0.59400186 -38.96831932
OS -0.61064394 -38.96554564
OS -0.62913514 -38.96092284
OS -0.64947546 -38.95445092
OS -0.66796666 -38.94520532
OS -0.68460874 -38.93318604
OS -0.68645786 -38.93133692
OS -0.69108066 -38.92671412
OS -0.69755258 -38.91839308
OS -0.70494906 -38.90729836
OS -0.71234554 -38.89342996
OS -0.71881746 -38.87771244
OS -0.72344026 -38.85829668
OS -0.72436482 -38.84905108
OS -0.72528938 -38.83795636
OS -0.72528938 -38.83610724
OS -0.72528938 -38.832409
OS -0.72436482 -38.82593708
OS -0.72344026 -38.81761604
OS -0.72159114 -38.80744588
OS -0.71881746 -38.79727572
OS -0.71511922 -38.786181
OS -0.71049642 -38.77601084
OS -0.70957186 -38.77508628
OS -0.70772274 -38.77138804
OS -0.7040245 -38.76584068
OS -0.6994017 -38.75936876
OS -0.69385434 -38.75197228
OS -0.68645786 -38.7445758
OS -0.67906138 -38.73717932
OS -0.66981578 -38.7307074
OS -0.66889122 -38.72978284
OS -0.66519298 -38.72793372
OS -0.66057018 -38.72423548
OS -0.6531737 -38.72053724
OS -0.64485266 -38.716839
OS -0.6346825 -38.7122162
OS -0.62451234 -38.70851796
OS -0.61249306 -38.70481972
OS -0.6115685 -38.70481972
OS -0.60787026 -38.70389516
OS -0.6023229 -38.70204604
OS -0.59492642 -38.70112148
OS -0.58568082 -38.69927236
OS -0.57366154 -38.69742324
OS -0.55979314 -38.69464956
OS -0.54315106 -38.69280044
OS -0.5422265 -38.69280044
OS -0.53852826 -38.69187588
OS -0.53390546 -38.69187588
OS -0.52743354 -38.69095132
OS -0.52003706 -38.69002676
OS -0.51079146 -38.68817764
OS -0.5006213 -38.68725308
OS -0.48952658 -38.68540396
OS -0.46733714 -38.68078116
OS -0.44329858 -38.67615836
OS -0.4220337 -38.670611
OS -0.41186354 -38.66783732
OS -0.40261794 -38.66506364
OS -0.40261794 -38.66413908
OS -0.40261794 -38.66228996
OS -0.40169338 -38.6567426
OS -0.40169338 -38.65027068
OS -0.40169338 -38.64657244
OS -0.40169338 -38.64472332
OS -0.40169338 -38.64379876
OS -0.40169338 -38.6428742
OS -0.40169338 -38.63732684
OS -0.40261794 -38.62808124
OS -0.40446706 -38.61791108
OS -0.40724074 -38.60681636
OS -0.41186354 -38.59572164
OS -0.4174109 -38.58555148
OS -0.42480738 -38.57723044
OS -0.42573194 -38.57630588
OS -0.43035474 -38.57260764
OS -0.43775122 -38.5689094
OS -0.44699682 -38.56336204
OS -0.45994066 -38.55873924
OS -0.47473362 -38.55411644
OS -0.49322482 -38.55134276
OS -0.5144897 -38.5504182
OS -0.5237353 -38.5504182
OS -0.5329809 -38.55134276
OS -0.54592474 -38.55319188
OS -0.55886858 -38.555041
OS -0.57273698 -38.55873924
OS -0.58568082 -38.56336204
OS -0.59677554 -38.56983396
OS -0.5977001 -38.57075852
OS -0.60139834 -38.5735322
OS -0.60602114 -38.578155
OS -0.6115685 -38.58555148
OS -0.61711586 -38.59479708
OS -0.62358778 -38.60681636
OS -0.62913514 -38.62160932
OS -0.6346825 -38.6382514
OS -0.71142098 -38.62808124
OS -0.71142098 -38.62715668
OS -0.71049642 -38.62623212
OS -0.71049642 -38.62345844
OS -0.70957186 -38.6197602
OS -0.70679818 -38.61143916
OS -0.70309994 -38.59941988
OS -0.69847714 -38.5874006
OS -0.69292978 -38.57445676
OS -0.6855333 -38.56151292
OS -0.67721226 -38.54949364
OS -0.6762877 -38.54856908
OS -0.67258946 -38.54487084
OS -0.6670421 -38.53932348
OS -0.65964562 -38.531927
OS -0.64947546 -38.52453052
OS -0.63745618 -38.51713404
OS -0.62358778 -38.508813
OS -0.60787026 -38.50234108
OS -0.6069457 -38.50234108
OS -0.60602114 -38.50141652
OS -0.60324746 -38.50049196
OS -0.59954922 -38.4995674
OS -0.59030362 -38.49679372
OS -0.57735978 -38.49402004
OS -0.56256682 -38.49124636
OS -0.54407562 -38.48847268
OS -0.52465986 -38.48662356
OS -0.50247042 -38.485699
OS -0.49230026 -38.485699
OS -0.4821301 -38.48662356
OE
OB -0.82051906 -38.95999828 I
OS -0.89910666 -38.95999828
OS -0.89910666 -38.32020276
OS -0.82051906 -38.32020276
OS -0.82051906 -38.95999828
OE
OB -3.38339938 -38.48662356 I
OS -3.37692746 -38.48662356
OS -3.37045554 -38.48754812
OS -3.35473802 -38.4903218
OS -3.33809594 -38.4949446
OS -3.3205293 -38.50234108
OS -3.30296266 -38.51158668
OS -3.2881697 -38.52453052
OS -3.28632058 -38.52637964
OS -3.28262234 -38.531927
OS -3.27615042 -38.54024804
OS -3.27337674 -38.54671996
OS -3.2696785 -38.55319188
OS -3.26598026 -38.56151292
OS -3.26320658 -38.56983396
OS -3.25950834 -38.57907956
OS -3.25673466 -38.59017428
OS -3.25488554 -38.601269
OS -3.25303642 -38.61421284
OS -3.2511873 -38.62715668
OS -3.2511873 -38.64194964
OS -3.2511873 -38.95999828
OS -3.3297749 -38.95999828
OS -3.3297749 -38.66876188
OS -3.3297749 -38.66783732
OS -3.3297749 -38.66691276
OS -3.3297749 -38.6613654
OS -3.3297749 -38.65304436
OS -3.33069946 -38.6428742
OS -3.33162402 -38.63177948
OS -3.33254858 -38.62068476
OS -3.3343977 -38.60959004
OS -3.33717138 -38.601269
OS -3.33717138 -38.60034444
OS -3.3390205 -38.59757076
OS -3.34086962 -38.59387252
OS -3.3436433 -38.58924972
OS -3.34734154 -38.58370236
OS -3.35196434 -38.578155
OS -3.3575117 -38.57260764
OS -3.36490818 -38.56706028
OS -3.36583274 -38.56613572
OS -3.36860642 -38.56521116
OS -3.37230466 -38.56336204
OS -3.37877658 -38.56058836
OS -3.3852485 -38.55781468
OS -3.39356954 -38.55596556
OS -3.40189058 -38.555041
OS -3.41206074 -38.55411644
OS -3.41668354 -38.55411644
OS -3.42038178 -38.555041
OS -3.42962738 -38.55596556
OS -3.4407221 -38.55781468
OS -3.45366594 -38.56243748
OS -3.46753434 -38.56798484
OS -3.48140274 -38.57630588
OS -3.49434658 -38.5874006
OS -3.49527114 -38.58924972
OS -3.49896938 -38.59387252
OS -3.50451674 -38.601269
OS -3.5100641 -38.61236372
OS -3.51653602 -38.62715668
OS -3.52115882 -38.64472332
OS -3.52485706 -38.6659882
OS -3.52670618 -38.69095132
OS -3.52670618 -38.95999828
OS -3.60529378 -38.95999828
OS -3.60529378 -38.65951628
OS -3.60529378 -38.65859172
OS -3.60529378 -38.6567426
OS -3.60529378 -38.65489348
OS -3.60529378 -38.65119524
OS -3.60621834 -38.64102508
OS -3.60806746 -38.62993036
OS -3.60991658 -38.61698652
OS -3.61361482 -38.60404268
OS -3.61823762 -38.5920234
OS -3.62470954 -38.58092868
OS -3.6256341 -38.58000412
OS -3.62840778 -38.57630588
OS -3.63303058 -38.57260764
OS -3.6395025 -38.56706028
OS -3.64782354 -38.56243748
OS -3.65891826 -38.55781468
OS -3.6718621 -38.555041
OS -3.68757962 -38.55411644
OS -3.69312698 -38.55411644
OS -3.6995989 -38.555041
OS -3.70699538 -38.55596556
OS -3.71624098 -38.55873924
OS -3.7273357 -38.56151292
OS -3.73750586 -38.56613572
OS -3.74860058 -38.57168308
OS -3.74952514 -38.57260764
OS -3.75322338 -38.57538132
OS -3.75784618 -38.57907956
OS -3.7643181 -38.58462692
OS -3.77079002 -38.5920234
OS -3.77726194 -38.601269
OS -3.78373386 -38.61143916
OS -3.78928122 -38.62345844
OS -3.79020578 -38.62530756
OS -3.79113034 -38.62993036
OS -3.79297946 -38.63732684
OS -3.79575314 -38.647497
OS -3.79852682 -38.6613654
OS -3.80037594 -38.67800748
OS -3.8013005 -38.69742324
OS -3.80222506 -38.71961268
OS -3.80222506 -38.95999828
OS -3.88081266 -38.95999828
OS -3.88081266 -38.49586916
OS -3.8105461 -38.49586916
OS -3.8105461 -38.56243748
OS -3.80962154 -38.56058836
OS -3.80684786 -38.55689012
OS -3.8013005 -38.5504182
OS -3.79482858 -38.54302172
OS -3.78650754 -38.53377612
OS -3.77633738 -38.52453052
OS -3.76524266 -38.51528492
OS -3.75229882 -38.50696388
OS -3.7504497 -38.50603932
OS -3.7458269 -38.50326564
OS -3.73843042 -38.50049196
OS -3.72826026 -38.49586916
OS -3.71624098 -38.49217092
OS -3.70237258 -38.48939724
OS -3.68665506 -38.48662356
OS -3.67001298 -38.485699
OS -3.66169194 -38.485699
OS -3.65152178 -38.48662356
OS -3.64042706 -38.48847268
OS -3.62655866 -38.49124636
OS -3.61269026 -38.4949446
OS -3.59882186 -38.50049196
OS -3.58587802 -38.50788844
OS -3.5840289 -38.508813
OS -3.58033066 -38.51158668
OS -3.5747833 -38.51620948
OS -3.56738682 -38.52360596
OS -3.55999034 -38.531927
OS -3.5516693 -38.54209716
OS -3.54427282 -38.55411644
OS -3.53872546 -38.56798484
OS -3.5378009 -38.56706028
OS -3.53595178 -38.5642866
OS -3.5331781 -38.56058836
OS -3.5285553 -38.555041
OS -3.52300794 -38.54856908
OS -3.51653602 -38.54209716
OS -3.50913954 -38.53470068
OS -3.49989394 -38.52637964
OS -3.48972378 -38.51898316
OS -3.47955362 -38.51158668
OS -3.46753434 -38.50511476
OS -3.4545905 -38.49864284
OS -3.4407221 -38.49309548
OS -3.42592914 -38.48939724
OS -3.41113618 -38.48662356
OS -3.3944941 -38.485699
OS -3.38802218 -38.485699
OS -3.38339938 -38.48662356
OE
OB -5.16872474 -38.48662356 I
OS -5.1604037 -38.48754812
OS -5.1511581 -38.48939724
OS -5.14098794 -38.49124636
OS -5.12896866 -38.49309548
OS -5.10400554 -38.50141652
OS -5.0910617 -38.50603932
OS -5.07811786 -38.51251124
OS -5.06517402 -38.51898316
OS -5.05223018 -38.52822876
OS -5.0402109 -38.53747436
OS -5.02819162 -38.54856908
OS -5.02726706 -38.54949364
OS -5.02541794 -38.55134276
OS -5.02264426 -38.555041
OS -5.01894602 -38.5596638
OS -5.01432322 -38.56613572
OS -5.00877586 -38.57445676
OS -5.0032285 -38.58370236
OS -4.99768114 -38.59387252
OS -4.99213378 -38.60496724
OS -4.98658642 -38.61883564
OS -4.98103906 -38.63270404
OS -4.97641626 -38.64842156
OS -4.97271802 -38.66506364
OS -4.96994434 -38.68263028
OS -4.96809522 -38.70112148
OS -4.96717066 -38.7214618
OS -4.96717066 -38.72238636
OS -4.96717066 -38.72516004
OS -4.96717066 -38.72978284
OS -4.96717066 -38.73625476
OS -4.96809522 -38.74365124
OS -4.96901978 -38.75289684
OS -4.96901978 -38.76214244
OS -4.9708689 -38.7723126
OS -4.97364258 -38.7954266
OS -4.97918994 -38.8185406
OS -4.98566186 -38.8416546
OS -4.99490746 -38.86291948
OS -4.99490746 -38.86384404
OS -4.99583202 -38.8647686
OS -4.99768114 -38.86754228
OS -4.99953026 -38.87124052
OS -5.00600218 -38.88048612
OS -5.01432322 -38.89158084
OS -5.02541794 -38.90452468
OS -5.03928634 -38.91746852
OS -5.05500386 -38.93041236
OS -5.07349506 -38.94243164
OS -5.07441962 -38.94243164
OS -5.07534418 -38.9433562
OS -5.07811786 -38.94520532
OS -5.08274066 -38.94705444
OS -5.08736346 -38.94890356
OS -5.09291082 -38.95075268
OS -5.10677922 -38.95630004
OS -5.12249674 -38.96092284
OS -5.1419125 -38.96554564
OS -5.16225282 -38.96924388
OS -5.18444226 -38.97016844
OS -5.19368786 -38.97016844
OS -5.20108434 -38.96924388
OS -5.20940538 -38.96831932
OS -5.21865098 -38.9664702
OS -5.2297457 -38.96462108
OS -5.24084042 -38.96277196
OS -5.26580354 -38.95537548
OS -5.27967194 -38.94982812
OS -5.29261578 -38.94428076
OS -5.30555962 -38.93688428
OS -5.31850346 -38.92856324
OS -5.33052274 -38.91931764
OS -5.34254202 -38.90822292
OS -5.34346658 -38.90729836
OS -5.3453157 -38.90544924
OS -5.34808938 -38.901751
OS -5.35178762 -38.89620364
OS -5.35641042 -38.88973172
OS -5.36103322 -38.88233524
OS -5.36658058 -38.87308964
OS -5.37212794 -38.86199492
OS -5.3776753 -38.84997564
OS -5.38322266 -38.83610724
OS -5.38784546 -38.82131428
OS -5.39246826 -38.80559676
OS -5.3961665 -38.78803012
OS -5.39894018 -38.76953892
OS -5.4007893 -38.7491986
OS -5.40171386 -38.72793372
OS -5.40171386 -38.7260846
OS -5.40171386 -38.72238636
OS -5.4007893 -38.71591444
OS -5.4007893 -38.70666884
OS -5.39986474 -38.69649868
OS -5.39801562 -38.68355484
OS -5.3961665 -38.670611
OS -5.39246826 -38.65581804
OS -5.38877002 -38.64102508
OS -5.38414722 -38.62530756
OS -5.37859986 -38.60866548
OS -5.37120338 -38.59294796
OS -5.3638069 -38.578155
OS -5.35363674 -38.56336204
OS -5.34346658 -38.54949364
OS -5.33052274 -38.53747436
OS -5.32959818 -38.5365498
OS -5.32774906 -38.53562524
OS -5.32405082 -38.53285156
OS -5.31942802 -38.52915332
OS -5.31388066 -38.52545508
OS -5.30648418 -38.52083228
OS -5.2990877 -38.51620948
OS -5.2898421 -38.51158668
OS -5.27967194 -38.50696388
OS -5.26857722 -38.50234108
OS -5.2436141 -38.49402004
OS -5.21495274 -38.48754812
OS -5.20015978 -38.48662356
OS -5.18444226 -38.485699
OS -5.17519666 -38.485699
OS -5.16872474 -38.48662356
OE
OB -4.78318322 -38.49586916 I
OS -4.70367106 -38.49586916
OS -4.70367106 -38.55689012
OS -4.78318322 -38.55689012
OS -4.78318322 -38.82963532
OS -4.78318322 -38.83148444
OS -4.78318322 -38.83518268
OS -4.78318322 -38.84073004
OS -4.78225866 -38.84720196
OS -4.7813341 -38.86199492
OS -4.78040954 -38.86846684
OS -4.77948498 -38.87308964
OS -4.77856042 -38.87493876
OS -4.77578674 -38.878637
OS -4.7720885 -38.8832598
OS -4.76561658 -38.8878826
OS -4.76376746 -38.88880716
OS -4.75914466 -38.89065628
OS -4.75082362 -38.8925054
OS -4.73880434 -38.89342996
OS -4.72955874 -38.89342996
OS -4.72493594 -38.8925054
OS -4.71846402 -38.8925054
OS -4.71106754 -38.89158084
OS -4.70367106 -38.89065628
OS -4.6935009 -38.95999828
OS -4.69535002 -38.95999828
OS -4.69904826 -38.96092284
OS -4.70552018 -38.9618474
OS -4.71384122 -38.96277196
OS -4.72308682 -38.96462108
OS -4.73325698 -38.96554564
OS -4.7535973 -38.9664702
OS -4.76099378 -38.9664702
OS -4.76839026 -38.96554564
OS -4.77763586 -38.96462108
OS -4.78873058 -38.96369652
OS -4.7998253 -38.96092284
OS -4.80999546 -38.95814916
OS -4.82016562 -38.95352636
OS -4.82109018 -38.9526018
OS -4.82386386 -38.95075268
OS -4.8275621 -38.947979
OS -4.83310946 -38.9433562
OS -4.83773226 -38.9387334
OS -4.84327962 -38.93226148
OS -4.84882698 -38.92578956
OS -4.85252522 -38.91746852
OS -4.85252522 -38.91654396
OS -4.85437434 -38.91284572
OS -4.8552989 -38.9063738
OS -4.85714802 -38.8971282
OS -4.85899714 -38.88510892
OS -4.8599217 -38.87771244
OS -4.8599217 -38.8693914
OS -4.86084626 -38.85922124
OS -4.86177082 -38.84905108
OS -4.86177082 -38.83795636
OS -4.86177082 -38.82501252
OS -4.86177082 -38.55689012
OS -4.9200181 -38.55689012
OS -4.9200181 -38.49586916
OS -4.86177082 -38.49586916
OS -4.86177082 -38.38122372
OS -4.78318322 -38.33407116
OS -4.78318322 -38.49586916
OE
OB -5.79280274 -38.54856908 I
OS -5.79187818 -38.54764452
OS -5.79095362 -38.5457954
OS -5.78817994 -38.54302172
OS -5.78355714 -38.53839892
OS -5.77893434 -38.53377612
OS -5.77338698 -38.52822876
OS -5.7659905 -38.5226814
OS -5.75859402 -38.51713404
OS -5.74010282 -38.50511476
OS -5.71883794 -38.49586916
OS -5.70681866 -38.49124636
OS -5.69387482 -38.48847268
OS -5.68000642 -38.48662356
OS -5.66613802 -38.485699
OS -5.65874154 -38.485699
OS -5.6504205 -38.48662356
OS -5.64025034 -38.48754812
OS -5.62823106 -38.4903218
OS -5.61436266 -38.49309548
OS -5.5995697 -38.49771828
OS -5.5857013 -38.50326564
OS -5.58385218 -38.5041902
OS -5.57922938 -38.50603932
OS -5.5718329 -38.51066212
OS -5.56351186 -38.51620948
OS -5.5533417 -38.5226814
OS -5.54317154 -38.53100244
OS -5.53207682 -38.5411726
OS -5.52283122 -38.55226732
OS -5.52190666 -38.55319188
OS -5.51913298 -38.55781468
OS -5.51451018 -38.5642866
OS -5.50896282 -38.57260764
OS -5.5024909 -38.58370236
OS -5.49601898 -38.5966462
OS -5.48954706 -38.61143916
OS -5.4839997 -38.62715668
OS -5.4839997 -38.62808124
OS -5.48307514 -38.6290058
OS -5.48215058 -38.63177948
OS -5.48122602 -38.63455316
OS -5.4793769 -38.64379876
OS -5.47660322 -38.65581804
OS -5.47382954 -38.66968644
OS -5.47105586 -38.68540396
OS -5.4701313 -38.7029706
OS -5.46920674 -38.7214618
OS -5.46920674 -38.72238636
OS -5.46920674 -38.72700916
OS -5.46920674 -38.73255652
OS -5.4701313 -38.74087756
OS -5.47105586 -38.75104772
OS -5.47198042 -38.76214244
OS -5.47382954 -38.77508628
OS -5.47660322 -38.78895468
OS -5.4839997 -38.8185406
OS -5.4886225 -38.83425812
OS -5.49416986 -38.84905108
OS -5.50064178 -38.8647686
OS -5.50896282 -38.878637
OS -5.51820842 -38.8925054
OS -5.52837858 -38.90544924
OS -5.52930314 -38.9063738
OS -5.53115226 -38.90822292
OS -5.53392594 -38.9109966
OS -5.53854874 -38.9156194
OS -5.54502066 -38.9202422
OS -5.55149258 -38.92578956
OS -5.55888906 -38.93133692
OS -5.56813466 -38.93780884
OS -5.57830482 -38.9433562
OS -5.58847498 -38.94982812
OS -5.6134381 -38.95999828
OS -5.62638194 -38.96462108
OS -5.64025034 -38.96739476
OS -5.6550433 -38.96924388
OS -5.66983626 -38.97016844
OS -5.6735345 -38.97016844
OS -5.6781573 -38.96924388
OS -5.68370466 -38.96924388
OS -5.69017658 -38.96831932
OS -5.69849762 -38.9664702
OS -5.71698882 -38.9618474
OS -5.72715898 -38.95814916
OS -5.73732914 -38.95352636
OS -5.74842386 -38.947979
OS -5.75859402 -38.94150708
OS -5.76968874 -38.93318604
OS -5.7798589 -38.92394044
OS -5.7891045 -38.91377028
OS -5.7983501 -38.901751
OS -5.7983501 -38.95999828
OS -5.87139034 -38.95999828
OS -5.87139034 -38.32020276
OS -5.79280274 -38.32020276
OS -5.79280274 -38.54856908
OE
OB -5.97031826 -38.42745172 I
OS -5.99158314 -38.54671996
OS -6.04058482 -38.54671996
OS -6.06000058 -38.42745172
OS -6.06000058 -38.32020276
OS -5.97031826 -38.32020276
OS -5.97031826 -38.42745172
OE
OB -4.17389818 -38.48662356 I
OS -4.16557714 -38.48754812
OS -4.15633154 -38.48939724
OS -4.14616138 -38.49124636
OS -4.1341421 -38.49309548
OS -4.10917898 -38.50141652
OS -4.09623514 -38.50603932
OS -4.0832913 -38.51251124
OS -4.07034746 -38.51898316
OS -4.05740362 -38.52822876
OS -4.04538434 -38.53747436
OS -4.03336506 -38.54856908
OS -4.0324405 -38.54949364
OS -4.03059138 -38.55134276
OS -4.0278177 -38.555041
OS -4.02411946 -38.5596638
OS -4.01949666 -38.56613572
OS -4.0139493 -38.57445676
OS -4.00840194 -38.58370236
OS -4.00285458 -38.59387252
OS -3.99730722 -38.60496724
OS -3.99175986 -38.61883564
OS -3.9862125 -38.63270404
OS -3.9815897 -38.64842156
OS -3.97789146 -38.66506364
OS -3.97511778 -38.68263028
OS -3.97326866 -38.70112148
OS -3.9723441 -38.7214618
OS -3.9723441 -38.72238636
OS -3.9723441 -38.72516004
OS -3.9723441 -38.72978284
OS -3.9723441 -38.73625476
OS -3.97326866 -38.74365124
OS -3.97419322 -38.75289684
OS -3.97419322 -38.76214244
OS -3.97604234 -38.7723126
OS -3.97881602 -38.7954266
OS -3.98436338 -38.8185406
OS -3.9908353 -38.8416546
OS -4.0000809 -38.86291948
OS -4.0000809 -38.86384404
OS -4.00100546 -38.8647686
OS -4.00285458 -38.86754228
OS -4.0047037 -38.87124052
OS -4.01117562 -38.88048612
OS -4.01949666 -38.89158084
OS -4.03059138 -38.90452468
OS -4.04445978 -38.91746852
OS -4.0601773 -38.93041236
OS -4.0786685 -38.94243164
OS -4.07959306 -38.94243164
OS -4.08051762 -38.9433562
OS -4.0832913 -38.94520532
OS -4.0879141 -38.94705444
OS -4.0925369 -38.94890356
OS -4.09808426 -38.95075268
OS -4.11195266 -38.95630004
OS -4.12767018 -38.96092284
OS -4.14708594 -38.96554564
OS -4.16742626 -38.96924388
OS -4.1896157 -38.97016844
OS -4.1988613 -38.97016844
OS -4.20625778 -38.96924388
OS -4.21457882 -38.96831932
OS -4.22382442 -38.9664702
OS -4.23491914 -38.96462108
OS -4.24601386 -38.96277196
OS -4.27097698 -38.95537548
OS -4.28484538 -38.94982812
OS -4.29778922 -38.94428076
OS -4.31073306 -38.93688428
OS -4.3236769 -38.92856324
OS -4.33569618 -38.91931764
OS -4.34771546 -38.90822292
OS -4.34864002 -38.90729836
OS -4.35048914 -38.90544924
OS -4.35326282 -38.901751
OS -4.35696106 -38.89620364
OS -4.36158386 -38.88973172
OS -4.36620666 -38.88233524
OS -4.37175402 -38.87308964
OS -4.37730138 -38.86199492
OS -4.38284874 -38.84997564
OS -4.3883961 -38.83610724
OS -4.3930189 -38.82131428
OS -4.3976417 -38.80559676
OS -4.40133994 -38.78803012
OS -4.40411362 -38.76953892
OS -4.40596274 -38.7491986
OS -4.4068873 -38.72793372
OS -4.4068873 -38.7260846
OS -4.4068873 -38.72238636
OS -4.40596274 -38.71591444
OS -4.40596274 -38.70666884
OS -4.40503818 -38.69649868
OS -4.40318906 -38.68355484
OS -4.40133994 -38.670611
OS -4.3976417 -38.65581804
OS -4.39394346 -38.64102508
OS -4.38932066 -38.62530756
OS -4.3837733 -38.60866548
OS -4.37637682 -38.59294796
OS -4.36898034 -38.578155
OS -4.35881018 -38.56336204
OS -4.34864002 -38.54949364
OS -4.33569618 -38.53747436
OS -4.33477162 -38.5365498
OS -4.3329225 -38.53562524
OS -4.32922426 -38.53285156
OS -4.32460146 -38.52915332
OS -4.3190541 -38.52545508
OS -4.31165762 -38.52083228
OS -4.30426114 -38.51620948
OS -4.29501554 -38.51158668
OS -4.28484538 -38.50696388
OS -4.27375066 -38.50234108
OS -4.24878754 -38.49402004
OS -4.22012618 -38.48754812
OS -4.20533322 -38.48662356
OS -4.1896157 -38.485699
OS -4.1803701 -38.485699
OS -4.17389818 -38.48662356
OE
OB -4.53447658 -38.49586916 I
OS -4.45496442 -38.49586916
OS -4.45496442 -38.55689012
OS -4.53447658 -38.55689012
OS -4.53447658 -38.82963532
OS -4.53447658 -38.83148444
OS -4.53447658 -38.83518268
OS -4.53447658 -38.84073004
OS -4.53355202 -38.84720196
OS -4.53262746 -38.86199492
OS -4.5317029 -38.86846684
OS -4.53077834 -38.87308964
OS -4.52985378 -38.87493876
OS -4.5270801 -38.878637
OS -4.52338186 -38.8832598
OS -4.51690994 -38.8878826
OS -4.51506082 -38.88880716
OS -4.51043802 -38.89065628
OS -4.50211698 -38.8925054
OS -4.4900977 -38.89342996
OS -4.4808521 -38.89342996
OS -4.4762293 -38.8925054
OS -4.46975738 -38.8925054
OS -4.4623609 -38.89158084
OS -4.45496442 -38.89065628
OS -4.44479426 -38.95999828
OS -4.44664338 -38.95999828
OS -4.45034162 -38.96092284
OS -4.45681354 -38.9618474
OS -4.46513458 -38.96277196
OS -4.47438018 -38.96462108
OS -4.48455034 -38.96554564
OS -4.50489066 -38.9664702
OS -4.51228714 -38.9664702
OS -4.51968362 -38.96554564
OS -4.52892922 -38.96462108
OS -4.54002394 -38.96369652
OS -4.55111866 -38.96092284
OS -4.56128882 -38.95814916
OS -4.57145898 -38.95352636
OS -4.57238354 -38.9526018
OS -4.57515722 -38.95075268
OS -4.57885546 -38.947979
OS -4.58440282 -38.9433562
OS -4.58902562 -38.9387334
OS -4.59457298 -38.93226148
OS -4.60012034 -38.92578956
OS -4.60381858 -38.91746852
OS -4.60381858 -38.91654396
OS -4.6056677 -38.91284572
OS -4.60659226 -38.9063738
OS -4.60844138 -38.8971282
OS -4.6102905 -38.88510892
OS -4.61121506 -38.87771244
OS -4.61121506 -38.8693914
OS -4.61213962 -38.85922124
OS -4.61306418 -38.84905108
OS -4.61306418 -38.83795636
OS -4.61306418 -38.82501252
OS -4.61306418 -38.55689012
OS -4.67131146 -38.55689012
OS -4.67131146 -38.49586916
OS -4.61306418 -38.49586916
OS -4.61306418 -38.38122372
OS -4.53447658 -38.33407116
OS -4.53447658 -38.49586916
OE
OB -2.44959378 -38.5504182 H
OS -2.45514114 -38.5504182
OS -2.45976394 -38.55134276
OS -2.4699341 -38.55226732
OS -2.4838025 -38.55596556
OS -2.49952002 -38.56151292
OS -2.5161621 -38.5689094
OS -2.53187962 -38.58000412
OS -2.54020066 -38.5874006
OS -2.54759714 -38.59479708
OS -2.54759714 -38.59572164
OS -2.54944626 -38.5966462
OS -2.55129538 -38.59941988
OS -2.55406906 -38.60311812
OS -2.55684274 -38.60774092
OS -2.55961642 -38.61328828
OS -2.56331466 -38.62068476
OS -2.5670129 -38.62808124
OS -2.57071114 -38.63732684
OS -2.57440938 -38.64657244
OS -2.57718306 -38.65766716
OS -2.57995674 -38.66968644
OS -2.58273042 -38.68263028
OS -2.58457954 -38.69649868
OS -2.5855041 -38.7122162
OS -2.58642866 -38.72793372
OS -2.58642866 -38.72885828
OS -2.58642866 -38.73163196
OS -2.58642866 -38.73625476
OS -2.5855041 -38.74272668
OS -2.5855041 -38.75012316
OS -2.58457954 -38.7584442
OS -2.58180586 -38.77785996
OS -2.57718306 -38.8000494
OS -2.56978658 -38.82223884
OS -2.56054098 -38.84350372
OS -2.55406906 -38.85274932
OS -2.54759714 -38.86199492
OS -2.54667258 -38.86199492
OS -2.54574802 -38.86384404
OS -2.54020066 -38.86846684
OS -2.53187962 -38.87586332
OS -2.5207849 -38.8832598
OS -2.5069165 -38.89158084
OS -2.49027442 -38.89897732
OS -2.47085866 -38.90360012
OS -2.4606885 -38.90452468
OS -2.44959378 -38.90544924
OS -2.44404642 -38.90544924
OS -2.43942362 -38.90452468
OS -2.42925346 -38.90267556
OS -2.41538506 -38.89990188
OS -2.4005921 -38.89435452
OS -2.38395002 -38.88695804
OS -2.3682325 -38.87586332
OS -2.35991146 -38.86846684
OS -2.35251498 -38.86107036
OS -2.35159042 -38.8601458
OS -2.35066586 -38.85922124
OS -2.34881674 -38.85644756
OS -2.34604306 -38.85274932
OS -2.34326938 -38.84812652
OS -2.33957114 -38.84257916
OS -2.3358729 -38.83518268
OS -2.33217466 -38.8277862
OS -2.32847642 -38.8185406
OS -2.32570274 -38.80837044
OS -2.3220045 -38.79727572
OS -2.31923082 -38.78525644
OS -2.31645714 -38.77138804
OS -2.31460802 -38.75751964
OS -2.3127589 -38.74180212
OS -2.3127589 -38.72516004
OS -2.3127589 -38.72423548
OS -2.3127589 -38.7214618
OS -2.3127589 -38.716839
OS -2.31368346 -38.71129164
OS -2.31368346 -38.70389516
OS -2.31460802 -38.69557412
OS -2.3173817 -38.67615836
OS -2.3220045 -38.65581804
OS -2.32940098 -38.6336286
OS -2.33957114 -38.61328828
OS -2.3451185 -38.60311812
OS -2.35251498 -38.59479708
OS -2.35251498 -38.59387252
OS -2.3543641 -38.59294796
OS -2.35991146 -38.5874006
OS -2.3682325 -38.58092868
OS -2.37932722 -38.57260764
OS -2.39319562 -38.5642866
OS -2.4098377 -38.55689012
OS -2.4283289 -38.55226732
OS -2.43849906 -38.55134276
OS -2.44959378 -38.5504182
OE
OB -5.6642889 -38.5504182 H
OS -5.6781573 -38.5504182
OS -5.68185554 -38.55134276
OS -5.6920257 -38.55319188
OS -5.70404498 -38.55596556
OS -5.71791338 -38.56151292
OS -5.73270634 -38.56983396
OS -5.74010282 -38.57445676
OS -5.7474993 -38.58092868
OS -5.75489578 -38.5874006
OS -5.76229226 -38.59572164
OS -5.76229226 -38.5966462
OS -5.76414138 -38.59757076
OS -5.7659905 -38.60034444
OS -5.76783962 -38.60404268
OS -5.7706133 -38.60866548
OS -5.77431154 -38.61421284
OS -5.77708522 -38.62068476
OS -5.78078346 -38.62808124
OS -5.7844817 -38.63732684
OS -5.78725538 -38.64657244
OS -5.79095362 -38.65766716
OS -5.7937273 -38.66876188
OS -5.79557642 -38.68170572
OS -5.79742554 -38.69557412
OS -5.79927466 -38.70944252
OS -5.79927466 -38.72516004
OS -5.79927466 -38.7260846
OS -5.79927466 -38.72885828
OS -5.79927466 -38.73348108
OS -5.79927466 -38.73902844
OS -5.7983501 -38.74550036
OS -5.7983501 -38.7538214
OS -5.79650098 -38.77138804
OS -5.7937273 -38.7908038
OS -5.79002906 -38.81114412
OS -5.7844817 -38.82963532
OS -5.78078346 -38.83795636
OS -5.77708522 -38.84535284
OS -5.77708522 -38.8462774
OS -5.7752361 -38.84812652
OS -5.77338698 -38.8509002
OS -5.7706133 -38.85459844
OS -5.76229226 -38.8647686
OS -5.75027298 -38.87493876
OS -5.73640458 -38.88603348
OS -5.71883794 -38.89620364
OS -5.70959234 -38.89990188
OS -5.69849762 -38.90267556
OS -5.68832746 -38.90452468
OS -5.67630818 -38.90544924
OS -5.67168538 -38.90544924
OS -5.66798714 -38.90452468
OS -5.65781698 -38.90267556
OS -5.6457977 -38.89990188
OS -5.6319293 -38.89435452
OS -5.61713634 -38.88695804
OS -5.60234338 -38.87586332
OS -5.5949469 -38.86846684
OS -5.58755042 -38.86107036
OS -5.58755042 -38.8601458
OS -5.5857013 -38.85922124
OS -5.58385218 -38.85644756
OS -5.58200306 -38.85274932
OS -5.57830482 -38.84812652
OS -5.57553114 -38.84257916
OS -5.5718329 -38.83518268
OS -5.56813466 -38.8277862
OS -5.56536098 -38.8185406
OS -5.56166274 -38.809295
OS -5.5579645 -38.79820028
OS -5.55519082 -38.786181
OS -5.5533417 -38.77323716
OS -5.55149258 -38.75936876
OS -5.54964346 -38.74365124
OS -5.54964346 -38.72793372
OS -5.54964346 -38.72700916
OS -5.54964346 -38.72423548
OS -5.54964346 -38.71961268
OS -5.55056802 -38.71314076
OS -5.55056802 -38.70574428
OS -5.55149258 -38.69649868
OS -5.55426626 -38.67708292
OS -5.5579645 -38.65581804
OS -5.56443642 -38.63270404
OS -5.57368202 -38.61236372
OS -5.57922938 -38.60219356
OS -5.5857013 -38.59387252
OS -5.5857013 -38.59294796
OS -5.58755042 -38.5920234
OS -5.59217322 -38.5874006
OS -5.5995697 -38.58000412
OS -5.60973986 -38.57168308
OS -5.6226837 -38.5642866
OS -5.63747666 -38.55689012
OS -5.6550433 -38.55226732
OS -5.6642889 -38.5504182
OE
OB -5.18444226 -38.5504182 H
OS -5.18998962 -38.5504182
OS -5.19461242 -38.55134276
OS -5.20478258 -38.55226732
OS -5.21865098 -38.55596556
OS -5.2343685 -38.56151292
OS -5.25101058 -38.5689094
OS -5.2667281 -38.58000412
OS -5.27504914 -38.5874006
OS -5.28244562 -38.59479708
OS -5.28244562 -38.59572164
OS -5.28429474 -38.5966462
OS -5.28614386 -38.59941988
OS -5.28891754 -38.60311812
OS -5.29169122 -38.60774092
OS -5.2944649 -38.61328828
OS -5.29816314 -38.62068476
OS -5.30186138 -38.62808124
OS -5.30555962 -38.63732684
OS -5.30925786 -38.64657244
OS -5.31203154 -38.65766716
OS -5.31480522 -38.66968644
OS -5.3175789 -38.68263028
OS -5.31942802 -38.69649868
OS -5.32035258 -38.7122162
OS -5.32127714 -38.72793372
OS -5.32127714 -38.72885828
OS -5.32127714 -38.73163196
OS -5.32127714 -38.73625476
OS -5.32035258 -38.74272668
OS -5.32035258 -38.75012316
OS -5.31942802 -38.7584442
OS -5.31665434 -38.77785996
OS -5.31203154 -38.8000494
OS -5.30463506 -38.82223884
OS -5.29538946 -38.84350372
OS -5.28891754 -38.85274932
OS -5.28244562 -38.86199492
OS -5.28152106 -38.86199492
OS -5.2805965 -38.86384404
OS -5.27504914 -38.86846684
OS -5.2667281 -38.87586332
OS -5.25563338 -38.8832598
OS -5.24176498 -38.89158084
OS -5.2251229 -38.89897732
OS -5.20570714 -38.90360012
OS -5.19553698 -38.90452468
OS -5.18444226 -38.90544924
OS -5.1788949 -38.90544924
OS -5.1742721 -38.90452468
OS -5.16410194 -38.90267556
OS -5.15023354 -38.89990188
OS -5.13544058 -38.89435452
OS -5.1187985 -38.88695804
OS -5.10308098 -38.87586332
OS -5.09475994 -38.86846684
OS -5.08736346 -38.86107036
OS -5.0864389 -38.8601458
OS -5.08551434 -38.85922124
OS -5.08366522 -38.85644756
OS -5.08089154 -38.85274932
OS -5.07811786 -38.84812652
OS -5.07441962 -38.84257916
OS -5.07072138 -38.83518268
OS -5.06702314 -38.8277862
OS -5.0633249 -38.8185406
OS -5.06055122 -38.80837044
OS -5.05685298 -38.79727572
OS -5.0540793 -38.78525644
OS -5.05130562 -38.77138804
OS -5.0494565 -38.75751964
OS -5.04760738 -38.74180212
OS -5.04760738 -38.72516004
OS -5.04760738 -38.72423548
OS -5.04760738 -38.7214618
OS -5.04760738 -38.716839
OS -5.04853194 -38.71129164
OS -5.04853194 -38.70389516
OS -5.0494565 -38.69557412
OS -5.05223018 -38.67615836
OS -5.05685298 -38.65581804
OS -5.06424946 -38.6336286
OS -5.07441962 -38.61328828
OS -5.07996698 -38.60311812
OS -5.08736346 -38.59479708
OS -5.08736346 -38.59387252
OS -5.08921258 -38.59294796
OS -5.09475994 -38.5874006
OS -5.10308098 -38.58092868
OS -5.1141757 -38.57260764
OS -5.1280441 -38.5642866
OS -5.14468618 -38.55689012
OS -5.16317738 -38.55226732
OS -5.17334754 -38.55134276
OS -5.18444226 -38.5504182
OE
OB -1.50191978 -38.5504182 H
OS -1.50746714 -38.5504182
OS -1.51116538 -38.55134276
OS -1.52133554 -38.55226732
OS -1.53335482 -38.555041
OS -1.54814778 -38.5596638
OS -1.5638653 -38.56613572
OS -1.57865826 -38.57538132
OS -1.59345122 -38.5874006
OS -1.59530034 -38.58924972
OS -1.59899858 -38.59387252
OS -1.6054705 -38.60219356
OS -1.61194242 -38.61328828
OS -1.6193389 -38.62623212
OS -1.62581082 -38.6428742
OS -1.63135818 -38.66228996
OS -1.63413186 -38.68355484
OS -1.3743305 -38.68355484
OS -1.3743305 -38.68263028
OS -1.3743305 -38.68078116
OS -1.37525506 -38.67800748
OS -1.37525506 -38.67430924
OS -1.37710418 -38.66321452
OS -1.37987786 -38.65119524
OS -1.38450066 -38.63640228
OS -1.38912346 -38.62253388
OS -1.39651994 -38.60866548
OS -1.40484098 -38.5966462
OS -1.40484098 -38.59572164
OS -1.4066901 -38.59479708
OS -1.4113129 -38.58924972
OS -1.41963394 -38.58185324
OS -1.43072866 -38.5735322
OS -1.44459706 -38.56521116
OS -1.46123914 -38.55781468
OS -1.4806549 -38.55226732
OS -1.49082506 -38.55134276
OS -1.50191978 -38.5504182
OE
OB -4.1896157 -38.5504182 H
OS -4.19516306 -38.5504182
OS -4.19978586 -38.55134276
OS -4.20995602 -38.55226732
OS -4.22382442 -38.55596556
OS -4.23954194 -38.56151292
OS -4.25618402 -38.5689094
OS -4.27190154 -38.58000412
OS -4.28022258 -38.5874006
OS -4.28761906 -38.59479708
OS -4.28761906 -38.59572164
OS -4.28946818 -38.5966462
OS -4.2913173 -38.59941988
OS -4.29409098 -38.60311812
OS -4.29686466 -38.60774092
OS -4.29963834 -38.61328828
OS -4.30333658 -38.62068476
OS -4.30703482 -38.62808124
OS -4.31073306 -38.63732684
OS -4.3144313 -38.64657244
OS -4.31720498 -38.65766716
OS -4.31997866 -38.66968644
OS -4.32275234 -38.68263028
OS -4.32460146 -38.69649868
OS -4.32552602 -38.7122162
OS -4.32645058 -38.72793372
OS -4.32645058 -38.72885828
OS -4.32645058 -38.73163196
OS -4.32645058 -38.73625476
OS -4.32552602 -38.74272668
OS -4.32552602 -38.75012316
OS -4.32460146 -38.7584442
OS -4.32182778 -38.77785996
OS -4.31720498 -38.8000494
OS -4.3098085 -38.82223884
OS -4.3005629 -38.84350372
OS -4.29409098 -38.85274932
OS -4.28761906 -38.86199492
OS -4.2866945 -38.86199492
OS -4.28576994 -38.86384404
OS -4.28022258 -38.86846684
OS -4.27190154 -38.87586332
OS -4.26080682 -38.8832598
OS -4.24693842 -38.89158084
OS -4.23029634 -38.89897732
OS -4.21088058 -38.90360012
OS -4.20071042 -38.90452468
OS -4.1896157 -38.90544924
OS -4.18406834 -38.90544924
OS -4.17944554 -38.90452468
OS -4.16927538 -38.90267556
OS -4.15540698 -38.89990188
OS -4.14061402 -38.89435452
OS -4.12397194 -38.88695804
OS -4.10825442 -38.87586332
OS -4.09993338 -38.86846684
OS -4.0925369 -38.86107036
OS -4.09161234 -38.8601458
OS -4.09068778 -38.85922124
OS -4.08883866 -38.85644756
OS -4.08606498 -38.85274932
OS -4.0832913 -38.84812652
OS -4.07959306 -38.84257916
OS -4.07589482 -38.83518268
OS -4.07219658 -38.8277862
OS -4.06849834 -38.8185406
OS -4.06572466 -38.80837044
OS -4.06202642 -38.79727572
OS -4.05925274 -38.78525644
OS -4.05647906 -38.77138804
OS -4.05462994 -38.75751964
OS -4.05278082 -38.74180212
OS -4.05278082 -38.72516004
OS -4.05278082 -38.72423548
OS -4.05278082 -38.7214618
OS -4.05278082 -38.716839
OS -4.05370538 -38.71129164
OS -4.05370538 -38.70389516
OS -4.05462994 -38.69557412
OS -4.05740362 -38.67615836
OS -4.06202642 -38.65581804
OS -4.0694229 -38.6336286
OS -4.07959306 -38.61328828
OS -4.08514042 -38.60311812
OS -4.0925369 -38.59479708
OS -4.0925369 -38.59387252
OS -4.09438602 -38.59294796
OS -4.09993338 -38.5874006
OS -4.10825442 -38.58092868
OS -4.11934914 -38.57260764
OS -4.13321754 -38.5642866
OS -4.14985962 -38.55689012
OS -4.16835082 -38.55226732
OS -4.17852098 -38.55134276
OS -4.1896157 -38.5504182
OE
OB -0.40169338 -38.72700916 H
OS -0.40261794 -38.72700916
OS -0.4035425 -38.72793372
OS -0.40631618 -38.72885828
OS -0.41001442 -38.72978284
OS -0.41463722 -38.73163196
OS -0.42018458 -38.73348108
OS -0.4266565 -38.7353302
OS -0.43405298 -38.73717932
OS -0.44237402 -38.739953
OS -0.45254418 -38.74180212
OS -0.46271434 -38.7445758
OS -0.47473362 -38.74734948
OS -0.48767746 -38.75012316
OS -0.5006213 -38.75289684
OS -0.51541426 -38.75474596
OS -0.53113178 -38.75751964
OS -0.5329809 -38.75751964
OS -0.53852826 -38.7584442
OS -0.54777386 -38.76029332
OS -0.55794402 -38.76214244
OS -0.56903874 -38.76399156
OS -0.58013346 -38.76676524
OS -0.59030362 -38.76953892
OS -0.59954922 -38.77323716
OS -0.60047378 -38.77323716
OS -0.60324746 -38.77508628
OS -0.6069457 -38.7769354
OS -0.61064394 -38.77970908
OS -0.62173866 -38.78710556
OS -0.63098426 -38.79820028
OS -0.63098426 -38.79912484
OS -0.63283338 -38.80097396
OS -0.63375794 -38.8046722
OS -0.63560706 -38.809295
OS -0.63745618 -38.81484236
OS -0.6393053 -38.82038972
OS -0.64022986 -38.8277862
OS -0.64115442 -38.83518268
OS -0.64115442 -38.83610724
OS -0.64115442 -38.84073004
OS -0.64022986 -38.8462774
OS -0.63838074 -38.85367388
OS -0.63560706 -38.86199492
OS -0.63098426 -38.87031596
OS -0.6254369 -38.87956156
OS -0.61804042 -38.8878826
OS -0.61711586 -38.88880716
OS -0.61341762 -38.89065628
OS -0.60787026 -38.89435452
OS -0.60047378 -38.89805276
OS -0.59030362 -38.901751
OS -0.57828434 -38.90544924
OS -0.56441594 -38.90729836
OS -0.54777386 -38.90822292
OS -0.54037738 -38.90822292
OS -0.53113178 -38.90729836
OS -0.52096162 -38.90544924
OS -0.50801778 -38.90360012
OS -0.49507394 -38.89990188
OS -0.48120554 -38.89527908
OS -0.46733714 -38.88880716
OS -0.46548802 -38.8878826
OS -0.46178978 -38.88510892
OS -0.45531786 -38.88048612
OS -0.44792138 -38.8740142
OS -0.43960034 -38.86661772
OS -0.43035474 -38.85737212
OS -0.42295826 -38.8462774
OS -0.41556178 -38.83425812
OS -0.41463722 -38.83333356
OS -0.41371266 -38.82963532
OS -0.41186354 -38.8231634
OS -0.40908986 -38.81484236
OS -0.40631618 -38.80374764
OS -0.40446706 -38.7908038
OS -0.4035425 -38.77508628
OS -0.40261794 -38.75659508
OS -0.40169338 -38.72700916
OE
SE
S P 0
OB -4.66714078 -36.5016923 I
OS -4.65465922 -36.5016923
OS -4.62553558 -36.50307914
OS -4.5950251 -36.50723966
OS -4.56174094 -36.51140018
OS -4.53123046 -36.51833438
OS -4.51597522 -36.5224949
OS -4.50349366 -36.52665542
OS -4.50210682 -36.52665542
OS -4.50071998 -36.52804226
OS -4.49239894 -36.53220278
OS -4.47991738 -36.53775014
OS -4.46466214 -36.54745802
OS -4.44802006 -36.55993958
OS -4.42999114 -36.57658166
OS -4.41334906 -36.59599742
OS -4.39670698 -36.61818686
OS -4.39670698 -36.6195737
OS -4.39532014 -36.62096054
OS -4.38977278 -36.62928158
OS -4.38422542 -36.64314998
OS -4.37590438 -36.6611789
OS -4.36897018 -36.6819815
OS -4.36203598 -36.70694462
OS -4.35787546 -36.73329458
OS -4.35648862 -36.76241822
OS -4.35648862 -36.76380506
OS -4.35648862 -36.76657874
OS -4.35648862 -36.7721261
OS -4.35787546 -36.7790603
OS -4.35787546 -36.78876818
OS -4.3592623 -36.79847606
OS -4.36480966 -36.82205234
OS -4.3731307 -36.84978914
OS -4.38422542 -36.87891278
OS -4.4008675 -36.90803642
OS -4.41196222 -36.92190482
OS -4.42305694 -36.93577322
OS -4.42444378 -36.93716006
OS -4.42583062 -36.9385469
OS -4.42999114 -36.94270742
OS -4.4355385 -36.94686794
OS -4.4424727 -36.9524153
OS -4.45079374 -36.95796266
OS -4.46188846 -36.96489686
OS -4.47298318 -36.9732179
OS -4.48685158 -36.9801521
OS -4.50210682 -36.9870863
OS -4.5187489 -36.99540734
OS -4.53677782 -37.00234154
OS -4.55758042 -37.0078889
OS -4.57838302 -37.0148231
OS -4.6019593 -37.01898362
OS -4.62692242 -37.02314414
OS -4.62414874 -37.02453098
OS -4.61860138 -37.02730466
OS -4.61028034 -37.03285202
OS -4.59918562 -37.03839938
OS -4.5742225 -37.05365462
OS -4.56174094 -37.0633625
OS -4.55064622 -37.07168354
OS -4.54787254 -37.07445722
OS -4.54093834 -37.08139142
OS -4.52984362 -37.09248614
OS -4.51597522 -37.10635454
OS -4.50071998 -37.1257703
OS -4.48269106 -37.1465729
OS -4.46466214 -37.17153602
OS -4.44524638 -37.19927282
OS -4.28021242 -37.45999874
OS -4.43831218 -37.45999874
OS -4.56451462 -37.26029378
OS -4.56451462 -37.25890694
OS -4.5672883 -37.25613326
OS -4.57006198 -37.25197274
OS -4.5742225 -37.24642538
OS -4.58393038 -37.23117014
OS -4.59641194 -37.21175438
OS -4.61166718 -37.19095178
OS -4.62692242 -37.16876234
OS -4.64217766 -37.14795974
OS -4.65604606 -37.12854398
OS -4.6574329 -37.12715714
OS -4.66159342 -37.12160978
OS -4.66852762 -37.11328874
OS -4.6782355 -37.10358086
OS -4.6990381 -37.08277826
OS -4.71013282 -37.07307038
OS -4.72122754 -37.06474934
OS -4.72261438 -37.0633625
OS -4.72538806 -37.06197566
OS -4.73093542 -37.05920198
OS -4.73925646 -37.05504146
OS -4.7475775 -37.05088094
OS -4.75728538 -37.04672042
OS -4.77947482 -37.03978622
OS -4.78086166 -37.03978622
OS -4.78363534 -37.03839938
OS -4.7891827 -37.03839938
OS -4.7961169 -37.03701254
OS -4.80582478 -37.0356257
OS -4.8169195 -37.0356257
OS -4.83217474 -37.03423886
OS -4.99582186 -37.03423886
OS -4.99582186 -37.45999874
OS -5.12341114 -37.45999874
OS -5.12341114 -36.50030546
OS -4.6782355 -36.50030546
OS -4.66714078 -36.5016923
OE
OB -1.0100437 -37.45999874 I
OS -1.13208562 -37.45999874
OS -1.13208562 -36.65701838
OS -1.4122273 -37.45999874
OS -1.52594818 -37.45999874
OS -1.80331618 -36.64314998
OS -1.80331618 -37.45999874
OS -1.9253581 -37.45999874
OS -1.9253581 -36.50030546
OS -1.73536102 -36.50030546
OS -1.50791926 -37.1812439
OS -1.50791926 -37.18263074
OS -1.50653242 -37.18540442
OS -1.50514558 -37.18956494
OS -1.5023719 -37.19649914
OS -1.49682454 -37.21314122
OS -1.48989034 -37.23394382
OS -1.48295614 -37.2575201
OS -1.4746351 -37.28109638
OS -1.4677009 -37.30328582
OS -1.46215354 -37.32270158
OS -1.4607667 -37.3199279
OS -1.45937986 -37.3129937
OS -1.45521934 -37.30051214
OS -1.44967198 -37.28387006
OS -1.44273778 -37.26168062
OS -1.4330299 -37.23533066
OS -1.42332202 -37.20482018
OS -1.41084046 -37.16876234
OS -1.18062502 -36.50030546
OS -1.0100437 -36.50030546
OS -1.0100437 -37.45999874
OE
OB -2.02382374 -37.45999874 I
OS -2.1680551 -37.45999874
OS -2.28038914 -37.16876234
OS -2.68257274 -37.16876234
OS -2.78658574 -37.45999874
OS -2.92110922 -37.45999874
OS -2.55498346 -36.50030546
OS -2.41629946 -36.50030546
OS -2.02382374 -37.45999874
OE
OB -3.02928274 -37.45999874 I
OS -3.16103254 -37.45999874
OS -3.66306862 -36.70694462
OS -3.66306862 -37.45999874
OS -3.78511054 -37.45999874
OS -3.78511054 -36.50030546
OS -3.65474758 -36.50030546
OS -3.15132466 -37.25474642
OS -3.15132466 -36.50030546
OS -3.02928274 -36.50030546
OS -3.02928274 -37.45999874
OE
OB -5.3231161 -36.61402634 I
OS -5.89033366 -36.61402634
OS -5.89033366 -36.90664958
OS -5.35917394 -36.90664958
OS -5.35917394 -37.02037046
OS -5.89033366 -37.02037046
OS -5.89033366 -37.34627786
OS -5.30092666 -37.34627786
OS -5.30092666 -37.45999874
OS -6.01792294 -37.45999874
OS -6.01792294 -36.50030546
OS -5.3231161 -36.50030546
OS -5.3231161 -36.61402634
OE
OB -0.10721086 -36.61402634 I
OS -0.67442842 -36.61402634
OS -0.67442842 -36.90664958
OS -0.1432687 -36.90664958
OS -0.1432687 -37.02037046
OS -0.67442842 -37.02037046
OS -0.67442842 -37.34627786
OS -0.08502142 -37.34627786
OS -0.08502142 -37.45999874
OS -0.8020177 -37.45999874
OS -0.8020177 -36.50030546
OS -0.10721086 -36.50030546
OS -0.10721086 -36.61402634
OE
OB -8.43241138 -37.34627786 I
OS -7.95949894 -37.34627786
OS -7.95949894 -37.45999874
OS -8.56000066 -37.45999874
OS -8.56000066 -36.50030546
OS -8.43241138 -36.50030546
OS -8.43241138 -37.34627786
OE
OB -6.51718534 -37.05365462 I
OS -6.51718534 -37.45999874
OS -6.64477462 -37.45999874
OS -6.64477462 -37.05365462
OS -7.0150609 -36.50030546
OS -6.86112166 -36.50030546
OS -6.67251142 -36.79154186
OS -6.67251142 -36.7929287
OS -6.66973774 -36.79570238
OS -6.66696406 -36.7998629
OS -6.66419038 -36.80541026
OS -6.65864302 -36.81234446
OS -6.65309566 -36.8206655
OS -6.6406141 -36.8414681
OS -6.62535886 -36.86643122
OS -6.60871678 -36.89416802
OS -6.59068786 -36.92329166
OS -6.57404578 -36.95380214
OS -6.57404578 -36.9524153
OS -6.57265894 -36.94964162
OS -6.56988526 -36.9454811
OS -6.56572474 -36.93993374
OS -6.56156422 -36.93299954
OS -6.55601686 -36.9246785
OS -6.5435353 -36.9038759
OS -6.52828006 -36.87891278
OS -6.51025114 -36.84978914
OS -6.48944854 -36.81789182
OS -6.4672591 -36.78322082
OS -6.28280938 -36.50030546
OS -6.1344175 -36.50030546
OS -6.51718534 -37.05365462
OE
OB -7.01644774 -37.45999874 I
OS -7.1606791 -37.45999874
OS -7.27301314 -37.16876234
OS -7.67519674 -37.16876234
OS -7.77920974 -37.45999874
OS -7.91373322 -37.45999874
OS -7.54760746 -36.50030546
OS -7.40892346 -36.50030546
OS -7.01644774 -37.45999874
OE
OB -7.48103914 -36.60015794 H
OS -7.48103914 -36.60154478
OS -7.48242598 -36.60431846
OS -7.48242598 -36.60986582
OS -7.48519966 -36.61541318
OS -7.4865865 -36.62512106
OS -7.48936018 -36.63482894
OS -7.49490754 -36.65840522
OS -7.50184174 -36.68614202
OS -7.51154962 -36.7166525
OS -7.5212575 -36.74993666
OS -7.53373906 -36.78460766
OS -7.63775206 -37.06474934
OS -7.3132315 -37.06474934
OS -7.41308398 -36.80124974
OS -7.41308398 -36.7998629
OS -7.41447082 -36.79570238
OS -7.4172445 -36.78876818
OS -7.42001818 -36.78044714
OS -7.4241787 -36.77073926
OS -7.42833922 -36.7582577
OS -7.43249974 -36.7443893
OS -7.4380471 -36.7305209
OS -7.44914182 -36.69862358
OS -7.46023654 -36.66533942
OS -7.47133126 -36.63205526
OS -7.48103914 -36.60015794
OE
OB -4.69349074 -36.60709214 H
OS -4.99582186 -36.60709214
OS -4.99582186 -36.9246785
OS -4.71013282 -36.9246785
OS -4.69349074 -36.92329166
OS -4.67407498 -36.92190482
OS -4.65188554 -36.92051798
OS -4.6296961 -36.9177443
OS -4.60750666 -36.91358378
OS -4.5880909 -36.90803642
OS -4.58531722 -36.90664958
OS -4.57976986 -36.9038759
OS -4.57144882 -36.89971538
OS -4.5603541 -36.89416802
OS -4.54787254 -36.88584698
OS -4.53539098 -36.8761391
OS -4.52290942 -36.86365754
OS -4.51320154 -36.84978914
OS -4.5118147 -36.8484023
OS -4.50904102 -36.84285494
OS -4.5048805 -36.8345339
OS -4.49933314 -36.82343918
OS -4.49517262 -36.81095762
OS -4.4910121 -36.79708922
OS -4.48823842 -36.78044714
OS -4.48685158 -36.76380506
OS -4.48685158 -36.76241822
OS -4.48685158 -36.76103138
OS -4.48823842 -36.75271034
OS -4.48962526 -36.74022878
OS -4.49239894 -36.7235867
OS -4.49933314 -36.70694462
OS -4.50765418 -36.68752886
OS -4.52013574 -36.66949994
OS -4.53677782 -36.65147102
OS -4.5395515 -36.65008418
OS -4.5464857 -36.64453682
OS -4.55758042 -36.63760262
OS -4.57560934 -36.62928158
OS -4.59641194 -36.62096054
OS -4.62414874 -36.61402634
OS -4.65604606 -36.60847898
OS -4.69349074 -36.60709214
OE
OB -2.48841514 -36.60015794 H
OS -2.48841514 -36.60154478
OS -2.48980198 -36.60431846
OS -2.48980198 -36.60986582
OS -2.49257566 -36.61541318
OS -2.4939625 -36.62512106
OS -2.49673618 -36.63482894
OS -2.50228354 -36.65840522
OS -2.50921774 -36.68614202
OS -2.51892562 -36.7166525
OS -2.5286335 -36.74993666
OS -2.54111506 -36.78460766
OS -2.64512806 -37.06474934
OS -2.3206075 -37.06474934
OS -2.42045998 -36.80124974
OS -2.42045998 -36.7998629
OS -2.42184682 -36.79570238
OS -2.4246205 -36.78876818
OS -2.42739418 -36.78044714
OS -2.4315547 -36.77073926
OS -2.43571522 -36.7582577
OS -2.43987574 -36.7443893
OS -2.4454231 -36.7305209
OS -2.45651782 -36.69862358
OS -2.46761254 -36.66533942
OS -2.47870726 -36.63205526
OS -2.48841514 -36.60015794
OE
SE
S P 0
OB 0.21403564 39.15890568 I
OS 0.22790404 39.15983024
OS 0.49047908 39.15983024
OS 0.49047908 38.52003472
OS 0.40541956 38.52003472
OS 0.40541956 38.77983608
OS 0.24177244 38.77983608
OS 0.21773388 38.78076064
OS 0.19461988 38.78260976
OS 0.17427956 38.78538344
OS 0.15578836 38.78908168
OS 0.13822172 38.79277992
OS 0.12342876 38.79740272
OS 0.10956036 38.80295008
OS 0.09754108 38.80849744
OS 0.08737092 38.81312024
OS 0.07812532 38.8186676
OS 0.07072884 38.8232904
OS 0.06518148 38.8279132
OS 0.06055868 38.83068688
OS 0.057785 38.83346056
OS 0.05593588 38.83530968
OS 0.05501132 38.83623424
OS 0.04576572 38.84732896
OS 0.03744468 38.85842368
OS 0.03097276 38.8695184
OS 0.02450084 38.88153768
OS 0.01895348 38.89355696
OS 0.01525524 38.90465168
OS 0.00878332 38.92591656
OS 0.0069342 38.93608672
OS 0.00508508 38.94533232
OS 0.00416052 38.95365336
OS 0.00323596 38.96012528
OS 0.0023114 38.9665972
OS 0.0023114 38.97029544
OS 0.0023114 38.97306912
OS 0.0023114 38.97399368
OS 0.00323596 38.99156032
OS 0.00508508 39.0082024
OS 0.00878332 39.02299536
OS 0.011557 39.0359392
OS 0.01525524 39.04703392
OS 0.01895348 39.05535496
OS 0.0208026 39.05997776
OS 0.02172716 39.06182688
OS 0.02912364 39.07569528
OS 0.03836924 39.08771456
OS 0.04669028 39.09880928
OS 0.05501132 39.10713032
OS 0.0624078 39.11360224
OS 0.06795516 39.1191496
OS 0.0716534 39.12192328
OS 0.07350252 39.12284784
OS 0.0855218 39.13024432
OS 0.0993902 39.13671624
OS 0.11233404 39.1422636
OS 0.12435332 39.1468864
OS 0.13544804 39.14966008
OS 0.14376908 39.1515092
OS 0.150241 39.15335832
OS 0.15209012 39.15335832
OS 0.16595852 39.15520744
OS 0.18167604 39.15705656
OS 0.19831812 39.15798112
OS 0.21403564 39.15890568
OE
OB -0.40357044 38.74562736 I
OS -0.40357044 39.15983024
OS -0.3397758 39.15983024
OS -0.04669028 38.74562736
OS -0.04669028 38.67351168
OS -0.32498284 38.67351168
OS -0.32498284 38.52003472
OS -0.40357044 38.52003472
OS -0.40357044 38.67351168
OS -0.49047908 38.67351168
OS -0.49047908 38.74562736
OS -0.40357044 38.74562736
OE
OB -0.32498284 39.03224096 H
OS -0.32498284 38.74562736
OS -0.12342876 38.74562736
OS -0.32498284 39.03224096
OE
OB 0.22235668 39.08401632 H
OS 0.2057146 39.08309176
OS 0.1918462 39.0821672
OS 0.18075148 39.08124264
OS 0.173355 39.07939352
OS 0.16780764 39.07846896
OS 0.1641094 39.0775444
OS 0.16318484 39.0775444
OS 0.15116556 39.0729216
OS 0.1409954 39.06737424
OS 0.1317498 39.06182688
OS 0.12342876 39.05535496
OS 0.1178814 39.04888304
OS 0.1132586 39.04426024
OS 0.11048492 39.040562
OS 0.10956036 39.03963744
OS 0.10308844 39.02854272
OS 0.09754108 39.017448
OS 0.09384284 39.00542872
OS 0.09199372 38.99525856
OS 0.0901446 38.98601296
OS 0.08922004 38.97769192
OS 0.08922004 38.97306912
OS 0.08922004 38.97214456
OS 0.08922004 38.97122
OS 0.09106916 38.95180424
OS 0.0947674 38.93516216
OS 0.10031476 38.9203692
OS 0.10678668 38.90834992
OS 0.1132586 38.89910432
OS 0.11880596 38.89170784
OS 0.1225042 38.8880096
OS 0.12435332 38.88616048
OS 0.13082524 38.88061312
OS 0.13914628 38.87599032
OS 0.15671292 38.86859384
OS 0.17612868 38.86304648
OS 0.19554444 38.85934824
OS 0.21311108 38.85749912
OS 0.22050756 38.85657456
OS 0.22697948 38.85657456
OS 0.2334514 38.85565
OS 0.40541956 38.85565
OS 0.40541956 39.08401632
OS 0.22235668 39.08401632
OE
SE
S P 0
OB 0.21773388 2.33952034 I
OS 0.23160228 2.3404449
OS 0.49417732 2.3404449
OS 0.49417732 1.70064938
OS 0.4091178 1.70064938
OS 0.4091178 1.96045074
OS 0.24547068 1.96045074
OS 0.22143212 1.9613753
OS 0.19831812 1.96322442
OS 0.1779778 1.9659981
OS 0.1594866 1.96969634
OS 0.14191996 1.97339458
OS 0.127127 1.97801738
OS 0.1132586 1.98356474
OS 0.10123932 1.9891121
OS 0.09106916 1.9937349
OS 0.08182356 1.99928226
OS 0.07442708 2.00390506
OS 0.06887972 2.00852786
OS 0.06425692 2.01130154
OS 0.06148324 2.01407522
OS 0.05963412 2.01592434
OS 0.05870956 2.0168489
OS 0.04946396 2.02794362
OS 0.04114292 2.03903834
OS 0.034671 2.05013306
OS 0.02819908 2.06215234
OS 0.02265172 2.07417162
OS 0.01895348 2.08526634
OS 0.01248156 2.10653122
OS 0.01063244 2.11670138
OS 0.00878332 2.12594698
OS 0.00785876 2.13426802
OS 0.0069342 2.14073994
OS 0.00600964 2.14721186
OS 0.00600964 2.1509101
OS 0.00600964 2.15368378
OS 0.00600964 2.15460834
OS 0.0069342 2.17217498
OS 0.00878332 2.18881706
OS 0.01248156 2.20361002
OS 0.01525524 2.21655386
OS 0.01895348 2.22764858
OS 0.02265172 2.23596962
OS 0.02450084 2.24059242
OS 0.0254254 2.24244154
OS 0.03282188 2.25630994
OS 0.04206748 2.26832922
OS 0.05038852 2.27942394
OS 0.05870956 2.28774498
OS 0.06610604 2.2942169
OS 0.0716534 2.29976426
OS 0.07535164 2.30253794
OS 0.07720076 2.3034625
OS 0.08922004 2.31085898
OS 0.10308844 2.3173309
OS 0.11603228 2.32287826
OS 0.12805156 2.32750106
OS 0.13914628 2.33027474
OS 0.14746732 2.33212386
OS 0.15393924 2.33397298
OS 0.15578836 2.33397298
OS 0.16965676 2.3358221
OS 0.18537428 2.33767122
OS 0.20201636 2.33859578
OS 0.21773388 2.33952034
OE
OB -0.46366684 2.2572345 I
OS -0.46366684 2.33212386
OS -0.1456182 2.33212386
OS -0.08367268 2.0029805
OS -0.15763748 1.99281034
OS -0.1641094 2.0029805
OS -0.17243044 2.01130154
OS -0.17982692 2.01962258
OS -0.1872234 2.0260945
OS -0.19461988 2.0307173
OS -0.20016724 2.0353401
OS -0.20386548 2.03718922
OS -0.20479004 2.03811378
OS -0.21680932 2.04366114
OS -0.2288286 2.04828394
OS -0.23992332 2.05105762
OS -0.25101804 2.0538313
OS -0.26026364 2.05475586
OS -0.26766012 2.05568042
OS -0.28522676 2.05568042
OS -0.29632148 2.0538313
OS -0.31573724 2.0492085
OS -0.33237932 2.04273658
OS -0.34717228 2.03626466
OS -0.358267 2.02886818
OS -0.36658804 2.02239626
OS -0.37121084 2.01777346
OS -0.37305996 2.0168489
OS -0.37305996 2.01592434
OS -0.3860038 2.00020682
OS -0.3952494 1.98356474
OS -0.40172132 1.9659981
OS -0.40634412 1.94843146
OS -0.4091178 1.9336385
OS -0.41004236 1.92716658
OS -0.41004236 1.92161922
OS -0.41096692 1.91699642
OS -0.41096692 1.91329818
OS -0.41096692 1.91144906
OS -0.41096692 1.9105245
OS -0.41096692 1.89758066
OS -0.4091178 1.88556138
OS -0.404495 1.86244738
OS -0.39802308 1.84303162
OS -0.39155116 1.8273141
OS -0.38415468 1.81437026
OS -0.37768276 1.8042001
OS -0.37490908 1.80142642
OS -0.37305996 1.79865274
OS -0.3721354 1.79772818
OS -0.37121084 1.79680362
OS -0.36381436 1.78940714
OS -0.35641788 1.78293522
OS -0.3397758 1.7718405
OS -0.32405828 1.76444402
OS -0.30834076 1.75982122
OS -0.29539692 1.75612298
OS -0.2843022 1.75519842
OS -0.28060396 1.75427386
OS -0.2750566 1.75427386
OS -0.25748996 1.75519842
OS -0.24177244 1.75889666
OS -0.22790404 1.76351946
OS -0.21680932 1.76906682
OS -0.20663916 1.77461418
OS -0.19924268 1.77923698
OS -0.19554444 1.78293522
OS -0.19369532 1.78385978
OS -0.1826006 1.79680362
OS -0.173355 1.81067202
OS -0.16595852 1.82638954
OS -0.16041116 1.84025794
OS -0.15671292 1.85412634
OS -0.15393924 1.8642965
OS -0.15301468 1.8689193
OS -0.15209012 1.87169298
OS -0.15209012 1.8735421
OS -0.15209012 1.87446666
OS -0.06980428 1.86799474
OS -0.0716534 1.85320178
OS -0.07442708 1.83933338
OS -0.08274812 1.8134457
OS -0.09291828 1.79125626
OS -0.09846564 1.7810861
OS -0.104013 1.77276506
OS -0.1086358 1.76444402
OS -0.11418316 1.75704754
OS -0.11880596 1.75150018
OS -0.12342876 1.74687738
OS -0.127127 1.74317914
OS -0.12897612 1.7394809
OS -0.13082524 1.73855634
OS -0.1317498 1.73763178
OS -0.14284452 1.72931074
OS -0.15393924 1.72191426
OS -0.16595852 1.71544234
OS -0.1779778 1.70989498
OS -0.2010918 1.70157394
OS -0.2242058 1.69602658
OS -0.23437596 1.6932529
OS -0.24454612 1.69232834
OS -0.25286716 1.69140378
OS -0.26026364 1.69047922
OS -0.26673556 1.68955466
OS -0.2750566 1.68955466
OS -0.29447236 1.69047922
OS -0.31296356 1.6932529
OS -0.3305302 1.69695114
OS -0.34624772 1.70157394
OS -0.36104068 1.70804586
OS -0.37490908 1.71451778
OS -0.38785292 1.7209897
OS -0.39894764 1.72838618
OS -0.4091178 1.73578266
OS -0.4183634 1.74225458
OS -0.42575988 1.74965106
OS -0.4322318 1.75519842
OS -0.4368546 1.75982122
OS -0.44055284 1.76351946
OS -0.44240196 1.76629314
OS -0.44332652 1.7672177
OS -0.45257212 1.77923698
OS -0.4599686 1.79218082
OS -0.46736508 1.8042001
OS -0.47291244 1.81714394
OS -0.48215804 1.84210706
OS -0.4877054 1.86614562
OS -0.48955452 1.87631578
OS -0.49140364 1.88648594
OS -0.4923282 1.89480698
OS -0.49325276 1.90220346
OS -0.49417732 1.90867538
OS -0.49417732 1.91329818
OS -0.49417732 1.91607186
OS -0.49417732 1.91699642
OS -0.49325276 1.9336385
OS -0.49140364 1.94935602
OS -0.48862996 1.96507354
OS -0.48493172 1.97894194
OS -0.48030892 1.99188578
OS -0.47568612 2.00482962
OS -0.47013876 2.01592434
OS -0.46551596 2.0260945
OS -0.4599686 2.0353401
OS -0.45442124 2.04366114
OS -0.44979844 2.05013306
OS -0.44517564 2.05660498
OS -0.4414774 2.06122778
OS -0.43870372 2.06400146
OS -0.4368546 2.06585058
OS -0.43593004 2.06677514
OS -0.42483532 2.0769453
OS -0.4137406 2.0861909
OS -0.40172132 2.09358738
OS -0.38970204 2.1000593
OS -0.37768276 2.10653122
OS -0.36566348 2.11115402
OS -0.34347404 2.11762594
OS -0.33330388 2.12039962
OS -0.32405828 2.12224874
OS -0.31573724 2.1231733
OS -0.30834076 2.12409786
OS -0.3027934 2.12502242
OS -0.28245308 2.12502242
OS -0.27135836 2.1231733
OS -0.24916892 2.1185505
OS -0.2288286 2.11207858
OS -0.2103374 2.1046821
OS -0.19554444 2.09728562
OS -0.18907252 2.09358738
OS -0.18352516 2.0908137
OS -0.17890236 2.08804002
OS -0.17612868 2.0861909
OS -0.17427956 2.08526634
OS -0.173355 2.08434178
OS -0.20756372 2.2572345
OS -0.46366684 2.2572345
OE
OB 0.22605492 2.26463098 H
OS 0.20941284 2.26370642
OS 0.19554444 2.26278186
OS 0.18444972 2.2618573
OS 0.17705324 2.26000818
OS 0.17150588 2.25908362
OS 0.16780764 2.25815906
OS 0.16688308 2.25815906
OS 0.1548638 2.25353626
OS 0.14469364 2.2479889
OS 0.13544804 2.24244154
OS 0.127127 2.23596962
OS 0.12157964 2.2294977
OS 0.11695684 2.2248749
OS 0.11418316 2.22117666
OS 0.1132586 2.2202521
OS 0.10678668 2.20915738
OS 0.10123932 2.19806266
OS 0.09754108 2.18604338
OS 0.09569196 2.17587322
OS 0.09384284 2.16662762
OS 0.09291828 2.15830658
OS 0.09291828 2.15368378
OS 0.09291828 2.15275922
OS 0.09291828 2.15183466
OS 0.0947674 2.1324189
OS 0.09846564 2.11577682
OS 0.104013 2.10098386
OS 0.11048492 2.08896458
OS 0.11695684 2.07971898
OS 0.1225042 2.0723225
OS 0.12620244 2.06862426
OS 0.12805156 2.06677514
OS 0.13452348 2.06122778
OS 0.14284452 2.05660498
OS 0.16041116 2.0492085
OS 0.17982692 2.04366114
OS 0.19924268 2.0399629
OS 0.21680932 2.03811378
OS 0.2242058 2.03718922
OS 0.23067772 2.03718922
OS 0.23714964 2.03626466
OS 0.4091178 2.03626466
OS 0.4091178 2.26463098
OS 0.22605492 2.26463098
OE
SE
S P 0
OB 2.29342188 45.22313282 I
OS 2.30729028 45.22405738
OS 2.56986532 45.22405738
OS 2.56986532 44.58426186
OS 2.4848058 44.58426186
OS 2.4848058 44.84406322
OS 2.32115868 44.84406322
OS 2.29712012 44.84498778
OS 2.27400612 44.8468369
OS 2.2536658 44.84961058
OS 2.2351746 44.85330882
OS 2.21760796 44.85700706
OS 2.202815 44.86162986
OS 2.1889466 44.86717722
OS 2.17692732 44.87272458
OS 2.16675716 44.87734738
OS 2.15751156 44.88289474
OS 2.15011508 44.88751754
OS 2.14456772 44.89214034
OS 2.13994492 44.89491402
OS 2.13717124 44.8976877
OS 2.13532212 44.89953682
OS 2.13439756 44.90046138
OS 2.12515196 44.9115561
OS 2.11683092 44.92265082
OS 2.110359 44.93374554
OS 2.10388708 44.94576482
OS 2.09833972 44.9577841
OS 2.09464148 44.96887882
OS 2.08816956 44.9901437
OS 2.08632044 45.00031386
OS 2.08447132 45.00955946
OS 2.08354676 45.0178805
OS 2.0826222 45.02435242
OS 2.08169764 45.03082434
OS 2.08169764 45.03452258
OS 2.08169764 45.03729626
OS 2.08169764 45.03822082
OS 2.0826222 45.05578746
OS 2.08447132 45.07242954
OS 2.08816956 45.0872225
OS 2.09094324 45.10016634
OS 2.09464148 45.11126106
OS 2.09833972 45.1195821
OS 2.10018884 45.1242049
OS 2.1011134 45.12605402
OS 2.10850988 45.13992242
OS 2.11775548 45.1519417
OS 2.12607652 45.16303642
OS 2.13439756 45.17135746
OS 2.14179404 45.17782938
OS 2.1473414 45.18337674
OS 2.15103964 45.18615042
OS 2.15288876 45.18707498
OS 2.16490804 45.19447146
OS 2.17877644 45.20094338
OS 2.19172028 45.20649074
OS 2.20373956 45.21111354
OS 2.21483428 45.21388722
OS 2.22315532 45.21573634
OS 2.22962724 45.21758546
OS 2.23147636 45.21758546
OS 2.24534476 45.21943458
OS 2.26106228 45.2212837
OS 2.27770436 45.22220826
OS 2.29342188 45.22313282
OE
OB 1.76642268 45.2259065 I
OS 1.77197004 45.22683106
OS 1.77936652 45.22683106
OS 1.79785772 45.2259065
OS 1.81542436 45.22405738
OS 1.83206644 45.22035914
OS 1.84778396 45.21573634
OS 1.86165236 45.20926442
OS 1.87552076 45.20371706
OS 1.88754004 45.19632058
OS 1.89863476 45.18984866
OS 1.90788036 45.18337674
OS 1.91712596 45.17598026
OS 1.92452244 45.1704329
OS 1.9300698 45.16488554
OS 1.9346926 45.15933818
OS 1.93839084 45.15563994
OS 1.94023996 45.15379082
OS 1.94116452 45.15286626
OS 1.9531838 45.13622418
OS 1.96335396 45.11680842
OS 1.97259956 45.0964681
OS 1.9809206 45.07520322
OS 1.98739252 45.05301378
OS 1.99293988 45.03082434
OS 1.99756268 45.00771034
OS 2.00126092 44.98644546
OS 2.0040346 44.96518058
OS 2.00588372 44.94576482
OS 2.00773284 44.92819818
OS 2.0086574 44.91340522
OS 2.0086574 44.90046138
OS 2.00958196 44.89121578
OS 2.00958196 44.88751754
OS 2.00958196 44.88474386
OS 2.00958196 44.8838193
OS 2.00958196 44.88289474
OS 2.0086574 44.85330882
OS 2.00680828 44.82557202
OS 2.0040346 44.79968434
OS 1.9994118 44.77564578
OS 1.994789 44.7543809
OS 1.9901662 44.73496514
OS 1.98461884 44.7173985
OS 1.97814692 44.70168098
OS 1.97259956 44.68873714
OS 1.9670522 44.67671786
OS 1.9624294 44.66747226
OS 1.95688204 44.65915122
OS 1.9531838 44.6526793
OS 1.95041012 44.64898106
OS 1.948561 44.64620738
OS 1.94763644 44.64528282
OS 1.93561716 44.63233898
OS 1.92267332 44.62124426
OS 1.90972948 44.61199866
OS 1.89678564 44.60367762
OS 1.88291724 44.59628114
OS 1.8699734 44.59073378
OS 1.85702956 44.58611098
OS 1.84408572 44.58241274
OS 1.832991 44.57963906
OS 1.82189628 44.57686538
OS 1.81265068 44.57501626
OS 1.80432964 44.5740917
OS 1.79693316 44.5740917
OS 1.79231036 44.57316714
OS 1.78768756 44.57316714
OS 1.76642268 44.5740917
OS 1.74700692 44.57778994
OS 1.72944028 44.58148818
OS 1.71372276 44.58703554
OS 1.70170348 44.59165834
OS 1.69245788 44.59628114
OS 1.68875964 44.5972057
OS 1.68598596 44.59905482
OS 1.6850614 44.59997938
OS 1.68413684 44.59997938
OS 1.66841932 44.6110741
OS 1.65362636 44.62401794
OS 1.64160708 44.63696178
OS 1.63143692 44.64990562
OS 1.62311588 44.6619249
OS 1.61756852 44.6711705
OS 1.6157194 44.67486874
OS 1.61387028 44.67764242
OS 1.61294572 44.67856698
OS 1.61294572 44.67949154
OS 1.60370012 44.6989073
OS 1.5972282 44.71924762
OS 1.5926054 44.73773882
OS 1.58983172 44.75530546
OS 1.58705804 44.77009842
OS 1.58705804 44.77564578
OS 1.58613348 44.78119314
OS 1.58613348 44.78581594
OS 1.58613348 44.78858962
OS 1.58613348 44.79043874
OS 1.58613348 44.7913633
OS 1.58705804 44.80800538
OS 1.58890716 44.8237229
OS 1.59168084 44.83944042
OS 1.59445452 44.85330882
OS 1.59907732 44.86625266
OS 1.60370012 44.8791965
OS 1.60832292 44.89029122
OS 1.61387028 44.90046138
OS 1.61941764 44.90970698
OS 1.62404044 44.91802802
OS 1.62866324 44.92449994
OS 1.63328604 44.93097186
OS 1.63605972 44.93559466
OS 1.6388334 44.93836834
OS 1.64068252 44.94021746
OS 1.64160708 44.94114202
OS 1.65177724 44.95131218
OS 1.66287196 44.96055778
OS 1.67489124 44.96795426
OS 1.68598596 44.97442618
OS 1.69708068 44.9808981
OS 1.7081754 44.9855209
OS 1.72944028 44.99199282
OS 1.73868588 44.9947665
OS 1.74793148 44.99661562
OS 1.75532796 44.99754018
OS 1.76272444 44.99846474
OS 1.7682718 44.9993893
OS 1.77566828 44.9993893
OS 1.79231036 44.99846474
OS 1.80802788 44.99569106
OS 1.82282084 44.99291738
OS 1.83576468 44.98921914
OS 1.8468594 44.98459634
OS 1.85518044 44.98182266
OS 1.8607278 44.97904898
OS 1.86165236 44.97812442
OS 1.86257692 44.97812442
OS 1.87736988 44.96887882
OS 1.89031372 44.95870866
OS 1.902333 44.9485385
OS 1.9115786 44.93744378
OS 1.91989964 44.92819818
OS 1.92637156 44.9208017
OS 1.9300698 44.91525434
OS 1.93099436 44.91432978
OS 1.93099436 44.93097186
OS 1.9300698 44.94761394
OS 1.92914524 44.9624069
OS 1.92729612 44.97719986
OS 1.92637156 44.9901437
OS 1.92452244 45.00216298
OS 1.92267332 45.0132577
OS 1.91989964 45.02342786
OS 1.91805052 45.03267346
OS 1.9162014 45.04006994
OS 1.91435228 45.04654186
OS 1.91342772 45.05208922
OS 1.9115786 45.05578746
OS 1.91065404 45.05856114
OS 1.90972948 45.06041026
OS 1.90972948 45.06133482
OS 1.90048388 45.07982602
OS 1.89123828 45.0964681
OS 1.88106812 45.10941194
OS 1.87182252 45.12050666
OS 1.86350148 45.12975226
OS 1.85702956 45.13622418
OS 1.85240676 45.13992242
OS 1.85055764 45.14084698
OS 1.83946292 45.14824346
OS 1.8283682 45.15286626
OS 1.81727348 45.1565645
OS 1.80617876 45.15933818
OS 1.79785772 45.1611873
OS 1.79046124 45.16211186
OS 1.78398932 45.16211186
OS 1.76734724 45.16026274
OS 1.75162972 45.1565645
OS 1.73868588 45.15101714
OS 1.7266666 45.14546978
OS 1.717421 45.13899786
OS 1.71094908 45.1334505
OS 1.70725084 45.12975226
OS 1.70540172 45.12790314
OS 1.6989298 45.1195821
OS 1.69245788 45.10941194
OS 1.68691052 45.09831722
OS 1.68321228 45.0872225
OS 1.67951404 45.07705234
OS 1.67674036 45.0687313
OS 1.6758158 45.06318394
OS 1.67489124 45.06225938
OS 1.67489124 45.06133482
OS 1.59630364 45.06780674
OS 1.601851 45.09369442
OS 1.61017204 45.11680842
OS 1.61941764 45.13714874
OS 1.6295878 45.15379082
OS 1.63975796 45.16673466
OS 1.6434562 45.17228202
OS 1.648079 45.17690482
OS 1.65085268 45.1796785
OS 1.65362636 45.18245218
OS 1.65455092 45.18337674
OS 1.65547548 45.1843013
OS 1.66472108 45.19169778
OS 1.67489124 45.1981697
OS 1.69523156 45.20926442
OS 1.71557188 45.2166609
OS 1.73498764 45.2212837
OS 1.75255428 45.22498194
OS 1.75995076 45.2259065
OS 1.76642268 45.2259065
OE
OB 2.30174292 45.14824346 H
OS 2.28510084 45.1473189
OS 2.27123244 45.14639434
OS 2.26013772 45.14546978
OS 2.25274124 45.14362066
OS 2.24719388 45.1426961
OS 2.24349564 45.14177154
OS 2.24257108 45.14177154
OS 2.2305518 45.13714874
OS 2.22038164 45.13160138
OS 2.21113604 45.12605402
OS 2.202815 45.1195821
OS 2.19726764 45.11311018
OS 2.19264484 45.10848738
OS 2.18987116 45.10478914
OS 2.1889466 45.10386458
OS 2.18247468 45.09276986
OS 2.17692732 45.08167514
OS 2.17322908 45.06965586
OS 2.17137996 45.0594857
OS 2.16953084 45.0502401
OS 2.16860628 45.04191906
OS 2.16860628 45.03729626
OS 2.16860628 45.0363717
OS 2.16860628 45.03544714
OS 2.1704554 45.01603138
OS 2.17415364 44.9993893
OS 2.179701 44.98459634
OS 2.18617292 44.97257706
OS 2.19264484 44.96333146
OS 2.1981922 44.95593498
OS 2.20189044 44.95223674
OS 2.20373956 44.95038762
OS 2.21021148 44.94484026
OS 2.21853252 44.94021746
OS 2.23609916 44.93282098
OS 2.25551492 44.92727362
OS 2.27493068 44.92357538
OS 2.29249732 44.92172626
OS 2.2998938 44.9208017
OS 2.30636572 44.9208017
OS 2.31283764 44.91987714
OS 2.4848058 44.91987714
OS 2.4848058 45.14824346
OS 2.30174292 45.14824346
OE
OB 1.7913858 44.9300473 H
OS 1.77197004 44.92819818
OS 1.7544034 44.92357538
OS 1.73961044 44.91802802
OS 1.7266666 44.91063154
OS 1.71649644 44.90323506
OS 1.70909996 44.8976877
OS 1.70447716 44.8930649
OS 1.70262804 44.89121578
OS 1.69060876 44.87549826
OS 1.68136316 44.85885618
OS 1.67489124 44.84128954
OS 1.671193 44.82464746
OS 1.66841932 44.8098545
OS 1.66749476 44.80338258
OS 1.66749476 44.79783522
OS 1.6665702 44.79321242
OS 1.6665702 44.78951418
OS 1.6665702 44.78766506
OS 1.6665702 44.7867405
OS 1.66841932 44.76177738
OS 1.67211756 44.7405125
OS 1.67766492 44.7220213
OS 1.68413684 44.70630378
OS 1.69153332 44.6942845
OS 1.69708068 44.6850389
OS 1.70077892 44.67949154
OS 1.70262804 44.67856698
OS 1.70262804 44.67764242
OS 1.70909996 44.67024594
OS 1.71649644 44.66469858
OS 1.7312894 44.65452842
OS 1.74608236 44.6480565
OS 1.7590262 44.64250914
OS 1.77104548 44.63973546
OS 1.78029108 44.6388109
OS 1.78398932 44.63788634
OS 1.78861212 44.63788634
OS 1.80155596 44.6388109
OS 1.81357524 44.64066002
OS 1.82466996 44.64435826
OS 1.83391556 44.6480565
OS 1.8422366 44.65083018
OS 1.84870852 44.65452842
OS 1.85240676 44.65637754
OS 1.85425588 44.6573021
OS 1.8653506 44.66562314
OS 1.8745962 44.67394418
OS 1.88291724 44.68411434
OS 1.88938916 44.69243538
OS 1.89493652 44.70075642
OS 1.89863476 44.70722834
OS 1.90140844 44.71185114
OS 1.902333 44.71370026
OS 1.90788036 44.72756866
OS 1.9115786 44.74143706
OS 1.91527684 44.7543809
OS 1.91712596 44.76640018
OS 1.91805052 44.77657034
OS 1.91897508 44.78489138
OS 1.91897508 44.78951418
OS 1.91897508 44.7913633
OS 1.91712596 44.81355274
OS 1.91342772 44.8329685
OS 1.9069558 44.85053514
OS 1.90048388 44.86440354
OS 1.89401196 44.87642282
OS 1.88754004 44.88474386
OS 1.8838418 44.88936666
OS 1.88199268 44.89121578
OS 1.86719972 44.90415962
OS 1.85240676 44.91340522
OS 1.83668924 44.9208017
OS 1.82282084 44.9254245
OS 1.809877 44.92819818
OS 1.8006314 44.92912274
OS 1.79693316 44.9300473
OS 1.7913858 44.9300473
OE
SE
S P 0
OB 4.37809386 34.61266636 I
OS 4.37809386 35.04905868
OS 4.46315338 35.04905868
OS 4.46315338 34.60804356
OS 4.46315338 34.5886278
OS 4.4650025 34.57198572
OS 4.46592706 34.55811732
OS 4.46777618 34.5470226
OS 4.4696253 34.53870156
OS 4.47054986 34.53222964
OS 4.47239898 34.5285314
OS 4.47239898 34.52760684
OS 4.47609722 34.51836124
OS 4.48072002 34.51096476
OS 4.48626738 34.50449284
OS 4.49089018 34.49802092
OS 4.49643754 34.49432268
OS 4.50013578 34.49062444
OS 4.50290946 34.48877532
OS 4.50383402 34.48785076
OS 4.51307962 34.48322796
OS 4.52232522 34.47952972
OS 4.53157082 34.4776806
OS 4.53989186 34.47583148
OS 4.5482129 34.47490692
OS 4.55376026 34.47398236
OS 4.55930762 34.47398236
OS 4.57410058 34.47490692
OS 4.58796898 34.47860516
OS 4.5990637 34.4823034
OS 4.60923386 34.48785076
OS 4.61663034 34.49247356
OS 4.6221777 34.49709636
OS 4.62587594 34.49987004
OS 4.6268005 34.5007946
OS 4.6314233 34.50634196
OS 4.63512154 34.51281388
OS 4.6406689 34.52760684
OS 4.64621626 34.54424892
OS 4.64898994 34.560891
OS 4.65176362 34.57660852
OS 4.65176362 34.58308044
OS 4.65268818 34.5886278
OS 4.65361274 34.59417516
OS 4.65361274 34.5978734
OS 4.65361274 34.59972252
OS 4.65361274 34.60064708
OS 4.73035122 34.58955236
OS 4.73035122 34.57198572
OS 4.72942666 34.5562682
OS 4.72665298 34.54055068
OS 4.72480386 34.52668228
OS 4.72110562 34.51373844
OS 4.71740738 34.50264372
OS 4.71370914 34.491549
OS 4.7100109 34.4823034
OS 4.7053881 34.47398236
OS 4.70168986 34.46658588
OS 4.69799162 34.46011396
OS 4.69429338 34.45549116
OS 4.6915197 34.45179292
OS 4.68967058 34.44809468
OS 4.68874602 34.44717012
OS 4.68782146 34.44624556
OS 4.67857586 34.43792452
OS 4.66933026 34.43052804
OS 4.6591601 34.42405612
OS 4.64806538 34.41850876
OS 4.6268005 34.41018772
OS 4.60646018 34.40464036
OS 4.58704442 34.40094212
OS 4.57964794 34.40001756
OS 4.57225146 34.399093
OS 4.5667041 34.39816844
OS 4.55838306 34.39816844
OS 4.53804274 34.399093
OS 4.51955154 34.40186668
OS 4.50290946 34.40556492
OS 4.4881165 34.41018772
OS 4.47609722 34.41388596
OS 4.46777618 34.4175842
OS 4.46222882 34.42035788
OS 4.4603797 34.42128244
OS 4.44558674 34.43052804
OS 4.4326429 34.44162276
OS 4.42247274 34.45271748
OS 4.41322714 34.46288764
OS 4.40675522 34.4730578
OS 4.40213242 34.48045428
OS 4.39935874 34.48600164
OS 4.39843418 34.4869262
OS 4.39843418 34.48785076
OS 4.39196226 34.50634196
OS 4.3864149 34.52575772
OS 4.38271666 34.5470226
OS 4.38086754 34.56736292
OS 4.37901842 34.58492956
OS 4.37901842 34.59232604
OS 4.37809386 34.59972252
OS 4.37809386 34.60526988
OS 4.37809386 34.60896812
OS 4.37809386 34.6117418
OS 4.37809386 34.61266636
OE
OB 4.03230842 35.0509078 I
OS 4.03785578 35.05183236
OS 4.04525226 35.05183236
OS 4.06374346 35.0509078
OS 4.0813101 35.04905868
OS 4.09795218 35.04536044
OS 4.1136697 35.04073764
OS 4.1275381 35.03426572
OS 4.1414065 35.02871836
OS 4.15342578 35.02132188
OS 4.1645205 35.01484996
OS 4.1737661 35.00837804
OS 4.1830117 35.00098156
OS 4.19040818 34.9954342
OS 4.19595554 34.98988684
OS 4.20057834 34.98433948
OS 4.20427658 34.98064124
OS 4.2061257 34.97879212
OS 4.20705026 34.97786756
OS 4.21906954 34.96122548
OS 4.2292397 34.94180972
OS 4.2384853 34.9214694
OS 4.24680634 34.90020452
OS 4.25327826 34.87801508
OS 4.25882562 34.85582564
OS 4.26344842 34.83271164
OS 4.26714666 34.81144676
OS 4.26992034 34.79018188
OS 4.27176946 34.77076612
OS 4.27361858 34.75319948
OS 4.27454314 34.73840652
OS 4.27454314 34.72546268
OS 4.2754677 34.71621708
OS 4.2754677 34.71251884
OS 4.2754677 34.70974516
OS 4.2754677 34.7088206
OS 4.2754677 34.70789604
OS 4.27454314 34.67831012
OS 4.27269402 34.65057332
OS 4.26992034 34.62468564
OS 4.26529754 34.60064708
OS 4.26067474 34.5793822
OS 4.25605194 34.55996644
OS 4.25050458 34.5423998
OS 4.24403266 34.52668228
OS 4.2384853 34.51373844
OS 4.23293794 34.50171916
OS 4.22831514 34.49247356
OS 4.22276778 34.48415252
OS 4.21906954 34.4776806
OS 4.21629586 34.47398236
OS 4.21444674 34.47120868
OS 4.21352218 34.47028412
OS 4.2015029 34.45734028
OS 4.18855906 34.44624556
OS 4.17561522 34.43699996
OS 4.16267138 34.42867892
OS 4.14880298 34.42128244
OS 4.13585914 34.41573508
OS 4.1229153 34.41111228
OS 4.10997146 34.40741404
OS 4.09887674 34.40464036
OS 4.08778202 34.40186668
OS 4.07853642 34.40001756
OS 4.07021538 34.399093
OS 4.0628189 34.399093
OS 4.0581961 34.39816844
OS 4.0535733 34.39816844
OS 4.03230842 34.399093
OS 4.01289266 34.40279124
OS 3.99532602 34.40648948
OS 3.9796085 34.41203684
OS 3.96758922 34.41665964
OS 3.95834362 34.42128244
OS 3.95464538 34.422207
OS 3.9518717 34.42405612
OS 3.95094714 34.42498068
OS 3.95002258 34.42498068
OS 3.93430506 34.4360754
OS 3.9195121 34.44901924
OS 3.90749282 34.46196308
OS 3.89732266 34.47490692
OS 3.88900162 34.4869262
OS 3.88345426 34.4961718
OS 3.88160514 34.49987004
OS 3.87975602 34.50264372
OS 3.87883146 34.50356828
OS 3.87883146 34.50449284
OS 3.86958586 34.5239086
OS 3.86311394 34.54424892
OS 3.85849114 34.56274012
OS 3.85571746 34.58030676
OS 3.85294378 34.59509972
OS 3.85294378 34.60064708
OS 3.85201922 34.60619444
OS 3.85201922 34.61081724
OS 3.85201922 34.61359092
OS 3.85201922 34.61544004
OS 3.85201922 34.6163646
OS 3.85294378 34.63300668
OS 3.8547929 34.6487242
OS 3.85756658 34.66444172
OS 3.86034026 34.67831012
OS 3.86496306 34.69125396
OS 3.86958586 34.7041978
OS 3.87420866 34.71529252
OS 3.87975602 34.72546268
OS 3.88530338 34.73470828
OS 3.88992618 34.74302932
OS 3.89454898 34.74950124
OS 3.89917178 34.75597316
OS 3.90194546 34.76059596
OS 3.90471914 34.76336964
OS 3.90656826 34.76521876
OS 3.90749282 34.76614332
OS 3.91766298 34.77631348
OS 3.9287577 34.78555908
OS 3.94077698 34.79295556
OS 3.9518717 34.79942748
OS 3.96296642 34.8058994
OS 3.97406114 34.8105222
OS 3.99532602 34.81699412
OS 4.00457162 34.8197678
OS 4.01381722 34.82161692
OS 4.0212137 34.82254148
OS 4.02861018 34.82346604
OS 4.03415754 34.8243906
OS 4.04155402 34.8243906
OS 4.0581961 34.82346604
OS 4.07391362 34.82069236
OS 4.08870658 34.81791868
OS 4.10165042 34.81422044
OS 4.11274514 34.80959764
OS 4.12106618 34.80682396
OS 4.12661354 34.80405028
OS 4.1275381 34.80312572
OS 4.12846266 34.80312572
OS 4.14325562 34.79388012
OS 4.15619946 34.78370996
OS 4.16821874 34.7735398
OS 4.17746434 34.76244508
OS 4.18578538 34.75319948
OS 4.1922573 34.745803
OS 4.19595554 34.74025564
OS 4.1968801 34.73933108
OS 4.1968801 34.75597316
OS 4.19595554 34.77261524
OS 4.19503098 34.7874082
OS 4.19318186 34.80220116
OS 4.1922573 34.815145
OS 4.19040818 34.82716428
OS 4.18855906 34.838259
OS 4.18578538 34.84842916
OS 4.18393626 34.85767476
OS 4.18208714 34.86507124
OS 4.18023802 34.87154316
OS 4.17931346 34.87709052
OS 4.17746434 34.88078876
OS 4.17653978 34.88356244
OS 4.17561522 34.88541156
OS 4.17561522 34.88633612
OS 4.16636962 34.90482732
OS 4.15712402 34.9214694
OS 4.14695386 34.93441324
OS 4.13770826 34.94550796
OS 4.12938722 34.95475356
OS 4.1229153 34.96122548
OS 4.1182925 34.96492372
OS 4.11644338 34.96584828
OS 4.10534866 34.97324476
OS 4.09425394 34.97786756
OS 4.08315922 34.9815658
OS 4.0720645 34.98433948
OS 4.06374346 34.9861886
OS 4.05634698 34.98711316
OS 4.04987506 34.98711316
OS 4.03323298 34.98526404
OS 4.01751546 34.9815658
OS 4.00457162 34.97601844
OS 3.99255234 34.97047108
OS 3.98330674 34.96399916
OS 3.97683482 34.9584518
OS 3.97313658 34.95475356
OS 3.97128746 34.95290444
OS 3.96481554 34.9445834
OS 3.95834362 34.93441324
OS 3.95279626 34.92331852
OS 3.94909802 34.9122238
OS 3.94539978 34.90205364
OS 3.9426261 34.8937326
OS 3.94170154 34.88818524
OS 3.94077698 34.88726068
OS 3.94077698 34.88633612
OS 3.86218938 34.89280804
OS 3.86773674 34.91869572
OS 3.87605778 34.94180972
OS 3.88530338 34.96215004
OS 3.89547354 34.97879212
OS 3.9056437 34.99173596
OS 3.90934194 34.99728332
OS 3.91396474 35.00190612
OS 3.91673842 35.0046798
OS 3.9195121 35.00745348
OS 3.92043666 35.00837804
OS 3.92136122 35.0093026
OS 3.93060682 35.01669908
OS 3.94077698 35.023171
OS 3.9611173 35.03426572
OS 3.98145762 35.0416622
OS 4.00087338 35.046285
OS 4.01844002 35.04998324
OS 4.0258365 35.0509078
OS 4.03230842 35.0509078
OE
OB 4.05727154 34.7550486 H
OS 4.03785578 34.75319948
OS 4.02028914 34.74857668
OS 4.00549618 34.74302932
OS 3.99255234 34.73563284
OS 3.98238218 34.72823636
OS 3.9749857 34.722689
OS 3.9703629 34.7180662
OS 3.96851378 34.71621708
OS 3.9564945 34.70049956
OS 3.9472489 34.68385748
OS 3.94077698 34.66629084
OS 3.93707874 34.64964876
OS 3.93430506 34.6348558
OS 3.9333805 34.62838388
OS 3.9333805 34.62283652
OS 3.93245594 34.61821372
OS 3.93245594 34.61451548
OS 3.93245594 34.61266636
OS 3.93245594 34.6117418
OS 3.93430506 34.58677868
OS 3.9380033 34.5655138
OS 3.94355066 34.5470226
OS 3.95002258 34.53130508
OS 3.95741906 34.5192858
OS 3.96296642 34.5100402
OS 3.96666466 34.50449284
OS 3.96851378 34.50356828
OS 3.96851378 34.50264372
OS 3.9749857 34.49524724
OS 3.98238218 34.48969988
OS 3.99717514 34.47952972
OS 4.0119681 34.4730578
OS 4.02491194 34.46751044
OS 4.03693122 34.46473676
OS 4.04617682 34.4638122
OS 4.04987506 34.46288764
OS 4.05449786 34.46288764
OS 4.0674417 34.4638122
OS 4.07946098 34.46566132
OS 4.0905557 34.46935956
OS 4.0998013 34.4730578
OS 4.10812234 34.47583148
OS 4.11459426 34.47952972
OS 4.1182925 34.48137884
OS 4.12014162 34.4823034
OS 4.13123634 34.49062444
OS 4.14048194 34.49894548
OS 4.14880298 34.50911564
OS 4.1552749 34.51743668
OS 4.16082226 34.52575772
OS 4.1645205 34.53222964
OS 4.16729418 34.53685244
OS 4.16821874 34.53870156
OS 4.1737661 34.55256996
OS 4.17746434 34.56643836
OS 4.18116258 34.5793822
OS 4.1830117 34.59140148
OS 4.18393626 34.60157164
OS 4.18486082 34.60989268
OS 4.18486082 34.61451548
OS 4.18486082 34.6163646
OS 4.1830117 34.63855404
OS 4.17931346 34.6579698
OS 4.17284154 34.67553644
OS 4.16636962 34.68940484
OS 4.1598977 34.70142412
OS 4.15342578 34.70974516
OS 4.14972754 34.71436796
OS 4.14787842 34.71621708
OS 4.13308546 34.72916092
OS 4.1182925 34.73840652
OS 4.10257498 34.745803
OS 4.08870658 34.7504258
OS 4.07576274 34.75319948
OS 4.06651714 34.75412404
OS 4.0628189 34.7550486
OS 4.05727154 34.7550486
OE
SE
S P 0
OB 5.34142188 45.2189723 I
OS 5.35529028 45.21989686
OS 5.61786532 45.21989686
OS 5.61786532 44.58010134
OS 5.5328058 44.58010134
OS 5.5328058 44.8399027
OS 5.36915868 44.8399027
OS 5.34512012 44.84082726
OS 5.32200612 44.84267638
OS 5.3016658 44.84545006
OS 5.2831746 44.8491483
OS 5.26560796 44.85284654
OS 5.250815 44.85746934
OS 5.2369466 44.8630167
OS 5.22492732 44.86856406
OS 5.21475716 44.87318686
OS 5.20551156 44.87873422
OS 5.19811508 44.88335702
OS 5.19256772 44.88797982
OS 5.18794492 44.8907535
OS 5.18517124 44.89352718
OS 5.18332212 44.8953763
OS 5.18239756 44.89630086
OS 5.17315196 44.90739558
OS 5.16483092 44.9184903
OS 5.158359 44.92958502
OS 5.15188708 44.9416043
OS 5.14633972 44.95362358
OS 5.14264148 44.9647183
OS 5.13616956 44.98598318
OS 5.13432044 44.99615334
OS 5.13247132 45.00539894
OS 5.13154676 45.01371998
OS 5.1306222 45.0201919
OS 5.12969764 45.02666382
OS 5.12969764 45.03036206
OS 5.12969764 45.03313574
OS 5.12969764 45.0340603
OS 5.1306222 45.05162694
OS 5.13247132 45.06826902
OS 5.13616956 45.08306198
OS 5.13894324 45.09600582
OS 5.14264148 45.10710054
OS 5.14633972 45.11542158
OS 5.14818884 45.12004438
OS 5.1491134 45.1218935
OS 5.15650988 45.1357619
OS 5.16575548 45.14778118
OS 5.17407652 45.1588759
OS 5.18239756 45.16719694
OS 5.18979404 45.17366886
OS 5.1953414 45.17921622
OS 5.19903964 45.1819899
OS 5.20088876 45.18291446
OS 5.21290804 45.19031094
OS 5.22677644 45.19678286
OS 5.23972028 45.20233022
OS 5.25173956 45.20695302
OS 5.26283428 45.2097267
OS 5.27115532 45.21157582
OS 5.27762724 45.21342494
OS 5.27947636 45.21342494
OS 5.29334476 45.21527406
OS 5.30906228 45.21712318
OS 5.32570436 45.21804774
OS 5.34142188 45.2189723
OE
OB 4.63413348 45.1496303 I
OS 4.63413348 45.21157582
OS 5.04833636 45.21157582
OS 5.04833636 45.1357619
OS 4.73491052 45.1357619
OS 4.75709996 45.10894966
OS 4.77836484 45.0802883
OS 4.79685604 45.0525515
OS 4.81442268 45.02573926
OS 4.82181916 45.01371998
OS 4.82829108 45.00262526
OS 4.834763 44.9924551
OS 4.8393858 44.98413406
OS 4.84308404 44.97673758
OS 4.84585772 44.97211478
OS 4.84770684 44.96841654
OS 4.8486314 44.96749198
OS 4.8671226 44.93050958
OS 4.88376468 44.89352718
OS 4.89763308 44.8583939
OS 4.90318044 44.84267638
OS 4.9087278 44.82695886
OS 4.91427516 44.81309046
OS 4.9179734 44.80014662
OS 4.92167164 44.7890519
OS 4.92444532 44.7798063
OS 4.927219 44.77148526
OS 4.92906812 44.7659379
OS 4.92999268 44.76223966
OS 4.92999268 44.7613151
OS 4.93923828 44.72340814
OS 4.94293652 44.70491694
OS 4.9457102 44.68827486
OS 4.94848388 44.67255734
OS 4.95125756 44.65683982
OS 4.95310668 44.64389598
OS 4.9549558 44.63095214
OS 4.95588036 44.61985742
OS 4.95680492 44.60968726
OS 4.95772948 44.60044166
OS 4.95772948 44.59304518
OS 4.95865404 44.58749782
OS 4.95865404 44.58379958
OS 4.95865404 44.5810259
OS 4.95865404 44.58010134
OS 4.87821732 44.58010134
OS 4.87544364 44.61523462
OS 4.87082084 44.64759422
OS 4.86619804 44.67718014
OS 4.86342436 44.69104854
OS 4.86065068 44.70399238
OS 4.85880156 44.7150871
OS 4.85602788 44.72525726
OS 4.85417876 44.73450286
OS 4.85232964 44.74189934
OS 4.85048052 44.7474467
OS 4.84955596 44.7520695
OS 4.8486314 44.75484318
OS 4.8486314 44.75576774
OS 4.834763 44.7982975
OS 4.81997004 44.83805358
OS 4.81257356 44.85746934
OS 4.80517708 44.87596054
OS 4.79685604 44.89260262
OS 4.78945956 44.9092447
OS 4.78298764 44.92403766
OS 4.77651572 44.9369815
OS 4.77096836 44.94807622
OS 4.76634556 44.95824638
OS 4.76172276 44.96656742
OS 4.75894908 44.97211478
OS 4.75709996 44.97581302
OS 4.7561754 44.97673758
OS 4.74508068 44.99615334
OS 4.73398596 45.0155691
OS 4.72289124 45.03313574
OS 4.71179652 45.04977782
OS 4.70162636 45.06457078
OS 4.6914562 45.07936374
OS 4.68128604 45.09230758
OS 4.672965 45.1034023
OS 4.66464396 45.11449702
OS 4.65724748 45.12374262
OS 4.649851 45.1311391
OS 4.64430364 45.13761102
OS 4.6406054 45.14315838
OS 4.63690716 45.14685662
OS 4.63505804 45.14870574
OS 4.63413348 45.1496303
OE
OB 5.34974292 45.14408294 H
OS 5.33310084 45.14315838
OS 5.31923244 45.14223382
OS 5.30813772 45.14130926
OS 5.30074124 45.13946014
OS 5.29519388 45.13853558
OS 5.29149564 45.13761102
OS 5.29057108 45.13761102
OS 5.2785518 45.13298822
OS 5.26838164 45.12744086
OS 5.25913604 45.1218935
OS 5.250815 45.11542158
OS 5.24526764 45.10894966
OS 5.24064484 45.10432686
OS 5.23787116 45.10062862
OS 5.2369466 45.09970406
OS 5.23047468 45.08860934
OS 5.22492732 45.07751462
OS 5.22122908 45.06549534
OS 5.21937996 45.05532518
OS 5.21753084 45.04607958
OS 5.21660628 45.03775854
OS 5.21660628 45.03313574
OS 5.21660628 45.03221118
OS 5.21660628 45.03128662
OS 5.2184554 45.01187086
OS 5.22215364 44.99522878
OS 5.227701 44.98043582
OS 5.23417292 44.96841654
OS 5.24064484 44.95917094
OS 5.2461922 44.95177446
OS 5.24989044 44.94807622
OS 5.25173956 44.9462271
OS 5.25821148 44.94067974
OS 5.26653252 44.93605694
OS 5.28409916 44.92866046
OS 5.30351492 44.9231131
OS 5.32293068 44.91941486
OS 5.34049732 44.91756574
OS 5.3478938 44.91664118
OS 5.35436572 44.91664118
OS 5.36083764 44.91571662
OS 5.5328058 44.91571662
OS 5.5328058 45.14408294
OS 5.34974292 45.14408294
OE
SE
S P 0
OB 7.8804516 41.60661986 I
OS 7.88599896 41.60754442
OS 7.89432 41.60754442
OS 7.90911296 41.60661986
OS 7.92390592 41.6056953
OS 7.9497936 41.60014794
OS 7.96181288 41.5964497
OS 7.9729076 41.59275146
OS 7.98307776 41.58812866
OS 7.99232336 41.58350586
OS 7.99971984 41.57888306
OS 8.00711632 41.57426026
OS 8.01358824 41.57056202
OS 8.01821104 41.56686378
OS 8.02190928 41.5640901
OS 8.02468296 41.56131642
OS 8.02653208 41.56039186
OS 8.02745664 41.5594673
OS 8.03577768 41.5502217
OS 8.04409872 41.5409761
OS 8.05057064 41.53080594
OS 8.056118 41.52063578
OS 8.0653636 41.50122002
OS 8.07091096 41.48272882
OS 8.0746092 41.4670113
OS 8.07553376 41.45961482
OS 8.07645832 41.45406746
OS 8.07738288 41.4485201
OS 8.07738288 41.44482186
OS 8.07738288 41.44297274
OS 8.07738288 41.44204818
OS 8.07645832 41.4254061
OS 8.07368464 41.40968858
OS 8.0699864 41.39582018
OS 8.0653636 41.3838009
OS 8.06166536 41.3745553
OS 8.05796712 41.36715882
OS 8.05519344 41.36346058
OS 8.05426888 41.36161146
OS 8.04409872 41.35051674
OS 8.033004 41.34034658
OS 8.02098472 41.33110098
OS 8.00896544 41.3237045
OS 7.99787072 41.31815714
OS 7.98954968 41.3144589
OS 7.98585144 41.31260978
OS 7.98307776 41.31168522
OS 7.9821532 41.31076066
OS 7.98122864 41.31076066
OS 8.00249352 41.30428874
OS 8.02006016 41.2959677
OS 8.03577768 41.28579754
OS 8.04872152 41.27655194
OS 8.05889168 41.26730634
OS 8.06628816 41.25990986
OS 8.0699864 41.25528706
OS 8.07183552 41.2543625
OS 8.07183552 41.25343794
OS 8.08200568 41.23679586
OS 8.09032672 41.21922922
OS 8.09587408 41.20258714
OS 8.09957232 41.18594506
OS 8.10142144 41.1711521
OS 8.102346 41.16468018
OS 8.102346 41.15913282
OS 8.10327056 41.15543458
OS 8.10327056 41.15173634
OS 8.10327056 41.14988722
OS 8.10327056 41.14896266
OS 8.102346 41.1341697
OS 8.10049688 41.11937674
OS 8.0977232 41.10550834
OS 8.09402496 41.09163994
OS 8.08477936 41.06852594
OS 8.08015656 41.05743122
OS 8.0746092 41.04818562
OS 8.06906184 41.03894002
OS 8.06443904 41.03154354
OS 8.05889168 41.02507162
OS 8.05519344 41.01952426
OS 8.0514952 41.01490146
OS 8.04872152 41.01212778
OS 8.0468724 41.01027866
OS 8.04594784 41.0093541
OS 8.03485312 40.99918394
OS 8.02283384 40.9908629
OS 8.00989 40.98346642
OS 7.99694616 40.9769945
OS 7.98492688 40.9723717
OS 7.97198304 40.9677489
OS 7.94701992 40.96127698
OS 7.9359252 40.9585033
OS 7.92575504 40.95665418
OS 7.91650944 40.95572962
OS 7.9081884 40.95480506
OS 7.90171648 40.9538805
OS 7.89247088 40.9538805
OS 7.87490424 40.95480506
OS 7.85918672 40.95665418
OS 7.8434692 40.95942786
OS 7.82867624 40.96220154
OS 7.8157324 40.96682434
OS 7.80278856 40.97144714
OS 7.79076928 40.97606994
OS 7.78059912 40.9816173
OS 7.77135352 40.98716466
OS 7.76303248 40.99178746
OS 7.75656056 40.99641026
OS 7.75008864 41.00103306
OS 7.74546584 41.00380674
OS 7.74269216 41.00658042
OS 7.74084304 41.00842954
OS 7.73991848 41.0093541
OS 7.72974832 41.02044882
OS 7.72050272 41.03154354
OS 7.71310624 41.04263826
OS 7.70663432 41.05465754
OS 7.7001624 41.06575226
OS 7.6955396 41.07777154
OS 7.68906768 41.09903642
OS 7.686294 41.10920658
OS 7.68444488 41.11845218
OS 7.68352032 41.12677322
OS 7.68259576 41.13324514
OS 7.6816712 41.1387925
OS 7.6816712 41.1434153
OS 7.6816712 41.14618898
OS 7.6816712 41.14711354
OS 7.68259576 41.16837842
OS 7.686294 41.18779418
OS 7.69184136 41.20536082
OS 7.69738872 41.22015378
OS 7.70293608 41.23217306
OS 7.70848344 41.24141866
OS 7.71218168 41.24696602
OS 7.71310624 41.24789058
OS 7.71310624 41.24881514
OS 7.72605008 41.2636081
OS 7.73991848 41.27655194
OS 7.75471144 41.2867221
OS 7.76857984 41.2959677
OS 7.78152368 41.30243962
OS 7.7926184 41.30706242
OS 7.79631664 41.30891154
OS 7.79909032 41.3098361
OS 7.80093944 41.31076066
OS 7.801864 41.31076066
OS 7.78522192 41.31815714
OS 7.77135352 41.32647818
OS 7.75933424 41.33479922
OS 7.74916408 41.34312026
OS 7.7417676 41.35051674
OS 7.73622024 41.3560641
OS 7.732522 41.35976234
OS 7.73159744 41.36161146
OS 7.7232764 41.3745553
OS 7.71772904 41.38749914
OS 7.71310624 41.40044298
OS 7.71033256 41.41338682
OS 7.70848344 41.42355698
OS 7.70755888 41.43187802
OS 7.70755888 41.43742538
OS 7.70755888 41.43834994
OS 7.70755888 41.4392745
OS 7.70848344 41.45221834
OS 7.709408 41.46423762
OS 7.71587992 41.48735162
OS 7.72420096 41.50769194
OS 7.73344656 41.52525858
OS 7.74269216 41.53912698
OS 7.74731496 41.54467434
OS 7.7510132 41.5502217
OS 7.75471144 41.55391994
OS 7.75748512 41.55669362
OS 7.75840968 41.55761818
OS 7.75933424 41.55854274
OS 7.7695044 41.56686378
OS 7.77967456 41.57518482
OS 7.79076928 41.58165674
OS 7.801864 41.5872041
OS 7.82405344 41.59552514
OS 7.84624288 41.6010725
OS 7.85548848 41.60384618
OS 7.86473408 41.60477074
OS 7.87305512 41.6056953
OS 7.8804516 41.60661986
OE
OB 8.38988416 41.60384618 I
OS 8.40375256 41.60477074
OS 8.6663276 41.60477074
OS 8.6663276 40.96497522
OS 8.58126808 40.96497522
OS 8.58126808 41.22477658
OS 8.41762096 41.22477658
OS 8.3935824 41.22570114
OS 8.3704684 41.22755026
OS 8.35012808 41.23032394
OS 8.33163688 41.23402218
OS 8.31407024 41.23772042
OS 8.29927728 41.24234322
OS 8.28540888 41.24789058
OS 8.2733896 41.25343794
OS 8.26321944 41.25806074
OS 8.25397384 41.2636081
OS 8.24657736 41.2682309
OS 8.24103 41.2728537
OS 8.2364072 41.27562738
OS 8.23363352 41.27840106
OS 8.2317844 41.28025018
OS 8.23085984 41.28117474
OS 8.22161424 41.29226946
OS 8.2132932 41.30336418
OS 8.20682128 41.3144589
OS 8.20034936 41.32647818
OS 8.194802 41.33849746
OS 8.19110376 41.34959218
OS 8.18463184 41.37085706
OS 8.18278272 41.38102722
OS 8.1809336 41.39027282
OS 8.18000904 41.39859386
OS 8.17908448 41.40506578
OS 8.17815992 41.4115377
OS 8.17815992 41.41523594
OS 8.17815992 41.41800962
OS 8.17815992 41.41893418
OS 8.17908448 41.43650082
OS 8.1809336 41.4531429
OS 8.18463184 41.46793586
OS 8.18740552 41.4808797
OS 8.19110376 41.49197442
OS 8.194802 41.50029546
OS 8.19665112 41.50491826
OS 8.19757568 41.50676738
OS 8.20497216 41.52063578
OS 8.21421776 41.53265506
OS 8.2225388 41.54374978
OS 8.23085984 41.55207082
OS 8.23825632 41.55854274
OS 8.24380368 41.5640901
OS 8.24750192 41.56686378
OS 8.24935104 41.56778834
OS 8.26137032 41.57518482
OS 8.27523872 41.58165674
OS 8.28818256 41.5872041
OS 8.30020184 41.5918269
OS 8.31129656 41.59460058
OS 8.3196176 41.5964497
OS 8.32608952 41.59829882
OS 8.32793864 41.59829882
OS 8.34180704 41.60014794
OS 8.35752456 41.60199706
OS 8.37416664 41.60292162
OS 8.38988416 41.60384618
OE
OB 7.89247088 41.54282522 H
OS 7.87675336 41.54190066
OS 7.8619604 41.53820242
OS 7.84994112 41.53357962
OS 7.8388464 41.52803226
OS 7.83052536 41.5224849
OS 7.82405344 41.5178621
OS 7.81943064 41.51416386
OS 7.81850608 41.5132393
OS 7.80833592 41.50122002
OS 7.80093944 41.48920074
OS 7.79539208 41.47718146
OS 7.79169384 41.46608674
OS 7.78984472 41.45591658
OS 7.7879956 41.44759554
OS 7.7879956 41.44204818
OS 7.7879956 41.44112362
OS 7.7879956 41.44019906
OS 7.78892016 41.4254061
OS 7.7926184 41.4115377
OS 7.7972412 41.39951842
OS 7.80278856 41.38934826
OS 7.80833592 41.38102722
OS 7.81295872 41.37547986
OS 7.81665696 41.37085706
OS 7.81758152 41.3699325
OS 7.82867624 41.3606869
OS 7.84162008 41.35329042
OS 7.85363936 41.34866762
OS 7.86565864 41.34496938
OS 7.87675336 41.34312026
OS 7.8850744 41.3421957
OS 7.89062176 41.34127114
OS 7.89247088 41.34127114
OS 7.90911296 41.3421957
OS 7.92390592 41.34589394
OS 7.93684976 41.35051674
OS 7.94794448 41.3560641
OS 7.95626552 41.3606869
OS 7.96273744 41.3653097
OS 7.96736024 41.36900794
OS 7.9682848 41.3699325
OS 7.9775304 41.38102722
OS 7.98492688 41.39397106
OS 7.98954968 41.40599034
OS 7.99324792 41.41800962
OS 7.99509704 41.42817978
OS 7.9960216 41.43650082
OS 7.99694616 41.44204818
OS 7.99694616 41.44297274
OS 7.99694616 41.4438973
OS 7.9960216 41.45869026
OS 7.99232336 41.4716341
OS 7.98770056 41.48365338
OS 7.9821532 41.49382354
OS 7.9775304 41.50214458
OS 7.9729076 41.5086165
OS 7.96920936 41.51231474
OS 7.9682848 41.5132393
OS 7.95626552 41.52340946
OS 7.94424624 41.53080594
OS 7.9313024 41.53542874
OS 7.91928312 41.53912698
OS 7.9081884 41.5409761
OS 7.89986736 41.54282522
OS 7.89247088 41.54282522
OE
OB 8.3982052 41.52895682 H
OS 8.38156312 41.52803226
OS 8.36769472 41.5271077
OS 8.3566 41.52618314
OS 8.34920352 41.52433402
OS 8.34365616 41.52340946
OS 8.33995792 41.5224849
OS 8.33903336 41.5224849
OS 8.32701408 41.5178621
OS 8.31684392 41.51231474
OS 8.30759832 41.50676738
OS 8.29927728 41.50029546
OS 8.29372992 41.49382354
OS 8.28910712 41.48920074
OS 8.28633344 41.4855025
OS 8.28540888 41.48457794
OS 8.27893696 41.47348322
OS 8.2733896 41.4623885
OS 8.26969136 41.45036922
OS 8.26784224 41.44019906
OS 8.26599312 41.43095346
OS 8.26506856 41.42263242
OS 8.26506856 41.41800962
OS 8.26506856 41.41708506
OS 8.26506856 41.4161605
OS 8.26691768 41.39674474
OS 8.27061592 41.38010266
OS 8.27616328 41.3653097
OS 8.2826352 41.35329042
OS 8.28910712 41.34404482
OS 8.29465448 41.33664834
OS 8.29835272 41.3329501
OS 8.30020184 41.33110098
OS 8.30667376 41.32555362
OS 8.3149948 41.32093082
OS 8.33256144 41.31353434
OS 8.3519772 41.30798698
OS 8.37139296 41.30428874
OS 8.3889596 41.30243962
OS 8.39635608 41.30151506
OS 8.402828 41.30151506
OS 8.40929992 41.3005905
OS 8.58126808 41.3005905
OS 8.58126808 41.52895682
OS 8.3982052 41.52895682
OE
OB 7.89524456 41.2774765 H
OS 7.87490424 41.27562738
OS 7.85641304 41.27192914
OS 7.83977096 41.26545722
OS 7.82590256 41.2589853
OS 7.81480784 41.25158882
OS 7.8064868 41.2451169
OS 7.801864 41.24141866
OS 7.80001488 41.23956954
OS 7.78707104 41.22477658
OS 7.77782544 41.20905906
OS 7.77135352 41.19334154
OS 7.76673072 41.17947314
OS 7.76395704 41.16560474
OS 7.76303248 41.15543458
OS 7.76210792 41.15173634
OS 7.76210792 41.14896266
OS 7.76210792 41.14711354
OS 7.76210792 41.14618898
OS 7.76395704 41.12677322
OS 7.76765528 41.10828202
OS 7.7741272 41.0925645
OS 7.78059912 41.07962066
OS 7.78707104 41.0694505
OS 7.79354296 41.06112946
OS 7.7972412 41.05650666
OS 7.79909032 41.05465754
OS 7.81388328 41.04263826
OS 7.82867624 41.03339266
OS 7.84439376 41.0278453
OS 7.85918672 41.0232225
OS 7.87213056 41.02044882
OS 7.88322528 41.01952426
OS 7.88692352 41.0185997
OS 7.89247088 41.0185997
OS 7.90541472 41.01952426
OS 7.91835856 41.02137338
OS 7.93037784 41.02414706
OS 7.940548 41.02692074
OS 7.94886904 41.02969442
OS 7.95534096 41.0324681
OS 7.9590392 41.03431722
OS 7.96088832 41.03524178
OS 7.97198304 41.04263826
OS 7.98122864 41.05003474
OS 7.98954968 41.05835578
OS 7.9960216 41.06667682
OS 8.00156896 41.07314874
OS 8.0052672 41.0786961
OS 8.00711632 41.0833189
OS 8.00804088 41.08424346
OS 8.01266368 41.09626274
OS 8.01636192 41.10735746
OS 8.0191356 41.11845218
OS 8.02098472 41.12862234
OS 8.02190928 41.13694338
OS 8.02283384 41.1434153
OS 8.02283384 41.14711354
OS 8.02283384 41.14896266
OS 8.02098472 41.16837842
OS 8.01728648 41.18594506
OS 8.01173912 41.20166258
OS 8.00434264 41.21553098
OS 7.99787072 41.22570114
OS 7.99232336 41.23402218
OS 7.98862512 41.23864498
OS 7.986776 41.2404941
OS 7.9729076 41.25251338
OS 7.95719008 41.26175898
OS 7.94239712 41.2682309
OS 7.92760416 41.2728537
OS 7.91466032 41.27562738
OS 7.90449016 41.27655194
OS 7.90079192 41.2774765
OS 7.89524456 41.2774765
OE
SE
S P 0
OB 8.5619082 1.93766694 I
OS 8.5619082 2.37405926
OS 8.64696772 2.37405926
OS 8.64696772 1.93304414
OS 8.64696772 1.91362838
OS 8.64881684 1.8969863
OS 8.6497414 1.8831179
OS 8.65159052 1.87202318
OS 8.65343964 1.86370214
OS 8.6543642 1.85723022
OS 8.65621332 1.85353198
OS 8.65621332 1.85260742
OS 8.65991156 1.84336182
OS 8.66453436 1.83596534
OS 8.67008172 1.82949342
OS 8.67470452 1.8230215
OS 8.68025188 1.81932326
OS 8.68395012 1.81562502
OS 8.6867238 1.8137759
OS 8.68764836 1.81285134
OS 8.69689396 1.80822854
OS 8.70613956 1.8045303
OS 8.71538516 1.80268118
OS 8.7237062 1.80083206
OS 8.73202724 1.7999075
OS 8.7375746 1.79898294
OS 8.74312196 1.79898294
OS 8.75791492 1.7999075
OS 8.77178332 1.80360574
OS 8.78287804 1.80730398
OS 8.7930482 1.81285134
OS 8.80044468 1.81747414
OS 8.80599204 1.82209694
OS 8.80969028 1.82487062
OS 8.81061484 1.82579518
OS 8.81523764 1.83134254
OS 8.81893588 1.83781446
OS 8.82448324 1.85260742
OS 8.8300306 1.8692495
OS 8.83280428 1.88589158
OS 8.83557796 1.9016091
OS 8.83557796 1.90808102
OS 8.83650252 1.91362838
OS 8.83742708 1.91917574
OS 8.83742708 1.92287398
OS 8.83742708 1.9247231
OS 8.83742708 1.92564766
OS 8.91416556 1.91455294
OS 8.91416556 1.8969863
OS 8.913241 1.88126878
OS 8.91046732 1.86555126
OS 8.9086182 1.85168286
OS 8.90491996 1.83873902
OS 8.90122172 1.8276443
OS 8.89752348 1.81654958
OS 8.89382524 1.80730398
OS 8.88920244 1.79898294
OS 8.8855042 1.79158646
OS 8.88180596 1.78511454
OS 8.87810772 1.78049174
OS 8.87533404 1.7767935
OS 8.87348492 1.77309526
OS 8.87256036 1.7721707
OS 8.8716358 1.77124614
OS 8.8623902 1.7629251
OS 8.8531446 1.75552862
OS 8.84297444 1.7490567
OS 8.83187972 1.74350934
OS 8.81061484 1.7351883
OS 8.79027452 1.72964094
OS 8.77085876 1.7259427
OS 8.76346228 1.72501814
OS 8.7560658 1.72409358
OS 8.75051844 1.72316902
OS 8.7421974 1.72316902
OS 8.72185708 1.72409358
OS 8.70336588 1.72686726
OS 8.6867238 1.7305655
OS 8.67193084 1.7351883
OS 8.65991156 1.73888654
OS 8.65159052 1.74258478
OS 8.64604316 1.74535846
OS 8.64419404 1.74628302
OS 8.62940108 1.75552862
OS 8.61645724 1.76662334
OS 8.60628708 1.77771806
OS 8.59704148 1.78788822
OS 8.59056956 1.79805838
OS 8.58594676 1.80545486
OS 8.58317308 1.81100222
OS 8.58224852 1.81192678
OS 8.58224852 1.81285134
OS 8.5757766 1.83134254
OS 8.57022924 1.8507583
OS 8.566531 1.87202318
OS 8.56468188 1.8923635
OS 8.56283276 1.90993014
OS 8.56283276 1.91732662
OS 8.5619082 1.9247231
OS 8.5619082 1.93027046
OS 8.5619082 1.9339687
OS 8.5619082 1.93674238
OS 8.5619082 1.93766694
OE
OB 8.23553852 2.37590838 I
OS 8.24570868 2.37683294
OS 8.26882268 2.37683294
OS 8.28176652 2.37498382
OS 8.30672964 2.37036102
OS 8.32799452 2.36296454
OS 8.34648572 2.35556806
OS 8.35480676 2.35094526
OS 8.36127868 2.34724702
OS 8.3677506 2.34354878
OS 8.3723734 2.33985054
OS 8.37607164 2.33707686
OS 8.37884532 2.33522774
OS 8.38069444 2.33430318
OS 8.381619 2.33337862
OS 8.39918564 2.31581198
OS 8.41305404 2.29639622
OS 8.42414876 2.2760559
OS 8.43339436 2.25571558
OS 8.43894172 2.23814894
OS 8.4417154 2.23075246
OS 8.44356452 2.22428054
OS 8.44448908 2.21873318
OS 8.44541364 2.21503494
OS 8.4463382 2.21226126
OS 8.4463382 2.2113367
OS 8.3677506 2.1974683
OS 8.36405236 2.21780862
OS 8.358505 2.23537526
OS 8.35203308 2.25016822
OS 8.34556116 2.2621875
OS 8.33908924 2.2714331
OS 8.33354188 2.27790502
OS 8.32984364 2.28252782
OS 8.32891908 2.28345238
OS 8.3168998 2.29269798
OS 8.30395596 2.30009446
OS 8.29193668 2.30471726
OS 8.2799174 2.3084155
OS 8.26882268 2.31026462
OS 8.26050164 2.31211374
OS 8.25310516 2.31211374
OS 8.23646308 2.31118918
OS 8.22167012 2.30749094
OS 8.20872628 2.30286814
OS 8.19763156 2.29824534
OS 8.18931052 2.29269798
OS 8.1828386 2.28807518
OS 8.1782158 2.28437694
OS 8.17729124 2.28345238
OS 8.16712108 2.27235766
OS 8.1597246 2.26033838
OS 8.1551018 2.2483191
OS 8.15140356 2.23722438
OS 8.14955444 2.22705422
OS 8.14770532 2.21965774
OS 8.14770532 2.21411038
OS 8.14770532 2.21318582
OS 8.14770532 2.21226126
OS 8.14770532 2.2020911
OS 8.14955444 2.1928455
OS 8.15417724 2.17712798
OS 8.16064916 2.16325958
OS 8.16804564 2.1512403
OS 8.17544212 2.14291926
OS 8.18191404 2.13644734
OS 8.18653684 2.1327491
OS 8.1874614 2.13182454
OS 8.18838596 2.13182454
OS 8.20410348 2.1235035
OS 8.21889644 2.11703158
OS 8.23461396 2.11240878
OS 8.24848236 2.1096351
OS 8.26050164 2.10778598
OS 8.2706718 2.10593686
OS 8.28269108 2.10593686
OS 8.28638932 2.10686142
OS 8.29101212 2.10686142
OS 8.30025772 2.03751942
OS 8.28823844 2.0402931
OS 8.27714372 2.04214222
OS 8.26789812 2.04399134
OS 8.25957708 2.0449159
OS 8.25310516 2.04584046
OS 8.24478412 2.04584046
OS 8.22536836 2.04399134
OS 8.20780172 2.0402931
OS 8.1920842 2.03474574
OS 8.17914036 2.02827382
OS 8.1689702 2.0218019
OS 8.16157372 2.01625454
OS 8.15695092 2.0125563
OS 8.1551018 2.01070718
OS 8.14308252 1.99683878
OS 8.13383692 1.98204582
OS 8.127365 1.96725286
OS 8.12366676 1.9524599
OS 8.12089308 1.94044062
OS 8.11996852 1.93027046
OS 8.11904396 1.92657222
OS 8.11904396 1.92379854
OS 8.11904396 1.92194942
OS 8.11904396 1.92102486
OS 8.12089308 1.90068454
OS 8.12551588 1.88219334
OS 8.13106324 1.86647582
OS 8.13845972 1.85260742
OS 8.1458562 1.8415127
OS 8.15140356 1.83319166
OS 8.15602636 1.8276443
OS 8.15787548 1.82579518
OS 8.17266844 1.81285134
OS 8.18838596 1.80360574
OS 8.20410348 1.79713382
OS 8.21889644 1.79251102
OS 8.23184028 1.78973734
OS 8.24201044 1.78881278
OS 8.24570868 1.78788822
OS 8.25125604 1.78788822
OS 8.26789812 1.78881278
OS 8.28361564 1.79251102
OS 8.29748404 1.79713382
OS 8.30857876 1.80268118
OS 8.31782436 1.80730398
OS 8.32522084 1.81192678
OS 8.32891908 1.81562502
OS 8.3307682 1.81654958
OS 8.34186292 1.82949342
OS 8.35110852 1.84428638
OS 8.35942956 1.8600039
OS 8.36590148 1.87664598
OS 8.37052428 1.89051438
OS 8.3723734 1.8969863
OS 8.37329796 1.90253366
OS 8.37422252 1.90715646
OS 8.37514708 1.9108547
OS 8.37607164 1.91270382
OS 8.37607164 1.91362838
OS 8.45465924 1.90345822
OS 8.45281012 1.88866526
OS 8.45003644 1.87479686
OS 8.4417154 1.84890918
OS 8.43154524 1.82671974
OS 8.42599788 1.81747414
OS 8.42045052 1.80822854
OS 8.41490316 1.7999075
OS 8.4093558 1.79343558
OS 8.404733 1.78696366
OS 8.4001102 1.78234086
OS 8.39733652 1.77864262
OS 8.39456284 1.77586894
OS 8.39271372 1.77401982
OS 8.39178916 1.77309526
OS 8.38069444 1.76477422
OS 8.36959972 1.75645318
OS 8.358505 1.74998126
OS 8.34648572 1.7444339
OS 8.32337172 1.7351883
OS 8.30118228 1.72964094
OS 8.29101212 1.72779182
OS 8.28176652 1.7259427
OS 8.27344548 1.72501814
OS 8.266049 1.72409358
OS 8.26050164 1.72316902
OS 8.2521806 1.72316902
OS 8.23461396 1.72409358
OS 8.21889644 1.7259427
OS 8.20317892 1.72871638
OS 8.18838596 1.73241462
OS 8.17451756 1.73703742
OS 8.16249828 1.74166022
OS 8.150479 1.74720758
OS 8.14030884 1.75275494
OS 8.13013868 1.75737774
OS 8.12181764 1.7629251
OS 8.11442116 1.7675479
OS 8.1088738 1.7721707
OS 8.104251 1.77586894
OS 8.10055276 1.77864262
OS 8.09870364 1.78049174
OS 8.09777908 1.7814163
OS 8.08668436 1.79251102
OS 8.07743876 1.8045303
OS 8.06911772 1.81654958
OS 8.06172124 1.82856886
OS 8.05617388 1.83966358
OS 8.05062652 1.85168286
OS 8.04323004 1.8738723
OS 8.04138092 1.88404246
OS 8.0395318 1.89328806
OS 8.03768268 1.9016091
OS 8.03675812 1.90900558
OS 8.03583356 1.91455294
OS 8.03583356 1.91917574
OS 8.03583356 1.92194942
OS 8.03583356 1.92287398
OS 8.03675812 1.94506342
OS 8.04045636 1.96540374
OS 8.04600372 1.98297038
OS 8.05155108 1.99776334
OS 8.05709844 2.00978262
OS 8.0626458 2.01902822
OS 8.06634404 2.02457558
OS 8.0672686 2.0264247
OS 8.08021244 2.0402931
OS 8.09408084 2.05231238
OS 8.1088738 2.06155798
OS 8.12366676 2.06895446
OS 8.1366106 2.07450182
OS 8.14678076 2.07820006
OS 8.150479 2.07912462
OS 8.15325268 2.08004918
OS 8.1551018 2.08097374
OS 8.15602636 2.08097374
OS 8.14030884 2.08929478
OS 8.127365 2.09761582
OS 8.11627028 2.10686142
OS 8.10702468 2.11518246
OS 8.0996282 2.12257894
OS 8.09408084 2.12905086
OS 8.09130716 2.1327491
OS 8.0903826 2.13459822
OS 8.08298612 2.14754206
OS 8.07743876 2.1604859
OS 8.07281596 2.17342974
OS 8.07004228 2.18544902
OS 8.06819316 2.19561918
OS 8.0672686 2.20301566
OS 8.0672686 2.20856302
OS 8.0672686 2.21041214
OS 8.06819316 2.22612966
OS 8.07096684 2.24184718
OS 8.07466508 2.25571558
OS 8.07928788 2.26773486
OS 8.08391068 2.27790502
OS 8.08760892 2.28622606
OS 8.0903826 2.29084886
OS 8.09130716 2.29269798
OS 8.10055276 2.30656638
OS 8.11164748 2.31858566
OS 8.1227422 2.32875582
OS 8.13383692 2.33800142
OS 8.14308252 2.34447334
OS 8.15140356 2.3500207
OS 8.15695092 2.35279438
OS 8.15787548 2.35371894
OS 8.15880004 2.35371894
OS 8.17544212 2.36111542
OS 8.1920842 2.36666278
OS 8.20872628 2.37128558
OS 8.22351924 2.37405926
OS 8.23553852 2.37590838
OE
SE
S P 0
OB 11.43788416 41.63813364 I
OS 11.45175256 41.6390582
OS 11.7143276 41.6390582
OS 11.7143276 40.99926268
OS 11.62926808 40.99926268
OS 11.62926808 41.25906404
OS 11.46562096 41.25906404
OS 11.4415824 41.2599886
OS 11.4184684 41.26183772
OS 11.39812808 41.2646114
OS 11.37963688 41.26830964
OS 11.36207024 41.27200788
OS 11.34727728 41.27663068
OS 11.33340888 41.28217804
OS 11.3213896 41.2877254
OS 11.31121944 41.2923482
OS 11.30197384 41.29789556
OS 11.29457736 41.30251836
OS 11.28903 41.30714116
OS 11.2844072 41.30991484
OS 11.28163352 41.31268852
OS 11.2797844 41.31453764
OS 11.27885984 41.3154622
OS 11.26961424 41.32655692
OS 11.2612932 41.33765164
OS 11.25482128 41.34874636
OS 11.24834936 41.36076564
OS 11.242802 41.37278492
OS 11.23910376 41.38387964
OS 11.23263184 41.40514452
OS 11.23078272 41.41531468
OS 11.2289336 41.42456028
OS 11.22800904 41.43288132
OS 11.22708448 41.43935324
OS 11.22615992 41.44582516
OS 11.22615992 41.4495234
OS 11.22615992 41.45229708
OS 11.22615992 41.45322164
OS 11.22708448 41.47078828
OS 11.2289336 41.48743036
OS 11.23263184 41.50222332
OS 11.23540552 41.51516716
OS 11.23910376 41.52626188
OS 11.242802 41.53458292
OS 11.24465112 41.53920572
OS 11.24557568 41.54105484
OS 11.25297216 41.55492324
OS 11.26221776 41.56694252
OS 11.2705388 41.57803724
OS 11.27885984 41.58635828
OS 11.28625632 41.5928302
OS 11.29180368 41.59837756
OS 11.29550192 41.60115124
OS 11.29735104 41.6020758
OS 11.30937032 41.60947228
OS 11.32323872 41.6159442
OS 11.33618256 41.62149156
OS 11.34820184 41.62611436
OS 11.35929656 41.62888804
OS 11.3676176 41.63073716
OS 11.37408952 41.63258628
OS 11.37593864 41.63258628
OS 11.38980704 41.6344354
OS 11.40552456 41.63628452
OS 11.42216664 41.63720908
OS 11.43788416 41.63813364
OE
OB 10.93862176 41.64090732 I
OS 10.94324456 41.64183188
OS 10.94971648 41.64183188
OS 10.965434 41.64090732
OS 10.98022696 41.6390582
OS 10.99501992 41.63628452
OS 11.00796376 41.63258628
OS 11.03292688 41.62241612
OS 11.0440216 41.61779332
OS 11.0532672 41.61224596
OS 11.0625128 41.60577404
OS 11.06990928 41.60115124
OS 11.07730576 41.59560388
OS 11.08285312 41.59098108
OS 11.08747592 41.58728284
OS 11.0902496 41.58450916
OS 11.09209872 41.58266004
OS 11.09302328 41.58173548
OS 11.10319344 41.57064076
OS 11.11151448 41.55769692
OS 11.11983552 41.54567764
OS 11.12630744 41.5327338
OS 11.1318548 41.5188654
OS 11.1364776 41.50592156
OS 11.14294952 41.481883
OS 11.1457232 41.46986372
OS 11.14757232 41.45969356
OS 11.14849688 41.4495234
OS 11.14942144 41.44120236
OS 11.150346 41.43473044
OS 11.150346 41.43010764
OS 11.150346 41.4264094
OS 11.150346 41.42548484
OS 11.14942144 41.4079182
OS 11.14757232 41.39220068
OS 11.1457232 41.37648316
OS 11.14202496 41.3616902
OS 11.13740216 41.34874636
OS 11.13277936 41.33580252
OS 11.12815656 41.3247078
OS 11.1226092 41.31453764
OS 11.1179864 41.30529204
OS 11.1133636 41.296971
OS 11.1087408 41.29049908
OS 11.104118 41.28402716
OS 11.10041976 41.27940436
OS 11.09857064 41.27663068
OS 11.09672152 41.27478156
OS 11.09579696 41.273857
OS 11.0856268 41.26368684
OS 11.07453208 41.2553658
OS 11.06343736 41.24704476
OS 11.05141808 41.24057284
OS 11.04032336 41.23502548
OS 11.02922864 41.23040268
OS 11.00796376 41.22393076
OS 10.99871816 41.22115708
OS 10.98947256 41.21930796
OS 10.98207608 41.2183834
OS 10.9746796 41.21745884
OS 10.96913224 41.21653428
OS 10.96173576 41.21653428
OS 10.94416912 41.21745884
OS 10.92752704 41.22023252
OS 10.91273408 41.22393076
OS 10.89886568 41.22855356
OS 10.88869552 41.2322518
OS 10.88037448 41.23595004
OS 10.87482712 41.23872372
OS 10.872978 41.23964828
OS 10.85818504 41.24889388
OS 10.8452412 41.25906404
OS 10.83414648 41.2692342
OS 10.82490088 41.2784798
OS 10.81842896 41.2877254
OS 10.8128816 41.29419732
OS 10.80918336 41.29882012
OS 10.8082588 41.30066924
OS 10.8082588 41.29327276
OS 10.8082588 41.28864996
OS 10.8082588 41.28587628
OS 10.8082588 41.28495172
OS 10.80918336 41.26646052
OS 10.81010792 41.24889388
OS 10.81195704 41.23317636
OS 10.81380616 41.2183834
OS 10.81657984 41.20636412
OS 10.81842896 41.19711852
OS 10.81935352 41.19342028
OS 10.81935352 41.1906466
OS 10.82027808 41.18972204
OS 10.82027808 41.18879748
OS 10.82490088 41.1721554
OS 10.82952368 41.15736244
OS 10.83414648 41.1444186
OS 10.83876928 41.13332388
OS 10.84246752 41.12500284
OS 10.84616576 41.11853092
OS 10.84801488 41.11390812
OS 10.84893944 41.11298356
OS 10.85633592 41.1028134
OS 10.8637324 41.09449236
OS 10.87112888 41.08709588
OS 10.87852536 41.08062396
OS 10.88407272 41.0750766
OS 10.88962008 41.07137836
OS 10.89331832 41.06952924
OS 10.89424288 41.06860468
OS 10.90441304 41.06305732
OS 10.91550776 41.05935908
OS 10.92567792 41.0565854
OS 10.93584808 41.05473628
OS 10.94416912 41.05381172
OS 10.95064104 41.05288716
OS 10.95711296 41.05288716
OS 10.97190592 41.05381172
OS 10.98577432 41.0565854
OS 10.9977936 41.06028364
OS 11.00796376 41.06490644
OS 11.01536024 41.06860468
OS 11.02183216 41.07230292
OS 11.0255304 41.0750766
OS 11.02645496 41.07600116
OS 11.03570056 41.08617132
OS 11.04309704 41.0981906
OS 11.04956896 41.11113444
OS 11.05419176 41.12407828
OS 11.05789 41.135173
OS 11.06066368 41.14534316
OS 11.06158824 41.1490414
OS 11.06158824 41.15089052
OS 11.0625128 41.15273964
OS 11.0625128 41.1536642
OS 11.13832672 41.14719228
OS 11.13277936 41.12038004
OS 11.12538288 41.09726604
OS 11.11613728 41.07692572
OS 11.10689168 41.06028364
OS 11.09764608 41.0473398
OS 11.09302328 41.04179244
OS 11.08932504 41.03716964
OS 11.08655136 41.03439596
OS 11.08377768 41.03162228
OS 11.08285312 41.03069772
OS 11.08192856 41.02977316
OS 11.07268296 41.02237668
OS 11.0625128 41.01590476
OS 11.04217248 41.0057346
OS 11.02183216 40.99833812
OS 11.0024164 40.99371532
OS 10.98484976 40.99001708
OS 10.97745328 40.98909252
OS 10.97098136 40.98909252
OS 10.96635856 40.98816796
OS 10.95896208 40.98816796
OS 10.9330744 40.99001708
OS 10.9099604 40.99371532
OS 10.88869552 41.00018724
OS 10.87112888 41.00758372
OS 10.8637324 41.0103574
OS 10.85633592 41.01405564
OS 10.85078856 41.01775388
OS 10.8452412 41.02052756
OS 10.84154296 41.02237668
OS 10.83876928 41.0242258
OS 10.83692016 41.02607492
OS 10.8359956 41.02607492
OS 10.8175044 41.04179244
OS 10.80086232 41.05935908
OS 10.78791848 41.07785028
OS 10.77682376 41.09541692
OS 10.76757816 41.11113444
OS 10.76387992 41.11853092
OS 10.76110624 41.12407828
OS 10.75925712 41.12962564
OS 10.757408 41.13332388
OS 10.75648344 41.135173
OS 10.75648344 41.13609756
OS 10.75186064 41.14996596
OS 10.74723784 41.16568348
OS 10.74076592 41.19711852
OS 10.73614312 41.23040268
OS 10.73336944 41.26183772
OS 10.73152032 41.27570612
OS 10.73059576 41.28957452
OS 10.73059576 41.3015938
OS 10.7296712 41.31176396
OS 10.7296712 41.320085
OS 10.7296712 41.32655692
OS 10.7296712 41.33117972
OS 10.7296712 41.33210428
OS 10.7296712 41.35336916
OS 10.73059576 41.37370948
OS 10.73244488 41.39220068
OS 10.734294 41.40976732
OS 10.73614312 41.42548484
OS 10.73799224 41.4402778
OS 10.74076592 41.4541462
OS 10.7435396 41.46616548
OS 10.74631328 41.47633564
OS 10.7481624 41.48558124
OS 10.75093608 41.49390228
OS 10.7527852 41.5003742
OS 10.75463432 41.504997
OS 10.75648344 41.50869524
OS 10.757408 41.51054436
OS 10.757408 41.51146892
OS 10.76850272 41.53365836
OS 10.780522 41.55307412
OS 10.7943904 41.5697162
OS 10.80640968 41.5835846
OS 10.81842896 41.59375476
OS 10.82767456 41.60115124
OS 10.8313728 41.60392492
OS 10.83414648 41.60577404
OS 10.83507104 41.60762316
OS 10.8359956 41.60762316
OS 10.85541136 41.61871788
OS 10.87482712 41.62703892
OS 10.89424288 41.63351084
OS 10.91180952 41.63720908
OS 10.92752704 41.63998276
OS 10.93399896 41.64090732
OS 10.93862176 41.64090732
OE
OB 10.93030072 41.57711268 H
OS 10.92105512 41.57526356
OS 10.90441304 41.57064076
OS 10.88962008 41.56416884
OS 10.87667624 41.55769692
OS 10.86650608 41.55030044
OS 10.8591096 41.54382852
OS 10.8544868 41.53920572
OS 10.85263768 41.53828116
OS 10.85263768 41.5373566
OS 10.8406184 41.52163908
OS 10.8313728 41.50407244
OS 10.82490088 41.48558124
OS 10.82120264 41.4680146
OS 10.81842896 41.45322164
OS 10.8175044 41.44674972
OS 10.8175044 41.4402778
OS 10.81657984 41.435655
OS 10.81657984 41.43195676
OS 10.81657984 41.43010764
OS 10.81657984 41.42918308
OS 10.81842896 41.40514452
OS 10.8221272 41.38387964
OS 10.82767456 41.366313
OS 10.83414648 41.35152004
OS 10.84154296 41.33950076
OS 10.84709032 41.33117972
OS 10.85078856 41.32563236
OS 10.85263768 41.32378324
OS 10.86650608 41.3108394
OS 10.88129904 41.3015938
OS 10.896092 41.29512188
OS 10.91088496 41.29049908
OS 10.92290424 41.2877254
OS 10.9330744 41.28680084
OS 10.93677264 41.28587628
OS 10.94232 41.28587628
OS 10.96173576 41.2877254
OS 10.9793024 41.29142364
OS 10.99501992 41.29789556
OS 11.00888832 41.30529204
OS 11.01905848 41.31176396
OS 11.02737952 41.31823588
OS 11.03200232 41.32193412
OS 11.03385144 41.32378324
OS 11.04587072 41.3385762
OS 11.05511632 41.35521828
OS 11.06066368 41.37186036
OS 11.06528648 41.38757788
OS 11.06806016 41.40144628
OS 11.06898472 41.40699364
OS 11.06898472 41.412541
OS 11.06990928 41.4171638
OS 11.06990928 41.41993748
OS 11.06990928 41.4217866
OS 11.06990928 41.42271116
OS 11.06806016 41.44674972
OS 11.06436192 41.46893916
OS 11.05789 41.48835492
OS 11.05049352 41.50407244
OS 11.0440216 41.51701628
OS 11.03754968 41.52626188
OS 11.03570056 41.52903556
OS 11.03385144 41.53180924
OS 11.03200232 41.5327338
OS 11.03200232 41.53365836
OS 11.02460584 41.54105484
OS 11.01720936 41.54845132
OS 11.00149184 41.55862148
OS 10.98577432 41.56694252
OS 10.97098136 41.57156532
OS 10.95896208 41.57526356
OS 10.94879192 41.57618812
OS 10.94509368 41.57711268
OS 10.93030072 41.57711268
OE
OB 11.4462052 41.56324428 H
OS 11.42956312 41.56231972
OS 11.41569472 41.56139516
OS 11.4046 41.5604706
OS 11.39720352 41.55862148
OS 11.39165616 41.55769692
OS 11.38795792 41.55677236
OS 11.38703336 41.55677236
OS 11.37501408 41.55214956
OS 11.36484392 41.5466022
OS 11.35559832 41.54105484
OS 11.34727728 41.53458292
OS 11.34172992 41.528111
OS 11.33710712 41.5234882
OS 11.33433344 41.51978996
OS 11.33340888 41.5188654
OS 11.32693696 41.50777068
OS 11.3213896 41.49667596
OS 11.31769136 41.48465668
OS 11.31584224 41.47448652
OS 11.31399312 41.46524092
OS 11.31306856 41.45691988
OS 11.31306856 41.45229708
OS 11.31306856 41.45137252
OS 11.31306856 41.45044796
OS 11.31491768 41.4310322
OS 11.31861592 41.41439012
OS 11.32416328 41.39959716
OS 11.3306352 41.38757788
OS 11.33710712 41.37833228
OS 11.34265448 41.3709358
OS 11.34635272 41.36723756
OS 11.34820184 41.36538844
OS 11.35467376 41.35984108
OS 11.3629948 41.35521828
OS 11.38056144 41.3478218
OS 11.3999772 41.34227444
OS 11.41939296 41.3385762
OS 11.4369596 41.33672708
OS 11.44435608 41.33580252
OS 11.450828 41.33580252
OS 11.45729992 41.33487796
OS 11.62926808 41.33487796
OS 11.62926808 41.56324428
OS 11.4462052 41.56324428
OE
SE
S P 0
OB 12.27348828 19.4825874 I
OS 12.28088476 19.48351196
OS 12.57766852 19.48351196
OS 12.57766852 18.84371644
OS 12.492609 18.84371644
OS 12.492609 19.12755636
OS 12.38351092 19.12755636
OS 12.37334076 19.1266318
OS 12.36594428 19.1266318
OS 12.35947236 19.12570724
OS 12.35484956 19.12478268
OS 12.35115132 19.12478268
OS 12.3493022 19.12385812
OS 12.34837764 19.12385812
OS 12.33358468 19.11923532
OS 12.32711276 19.11646164
OS 12.3215654 19.11368796
OS 12.31601804 19.11091428
OS 12.3123198 19.10906516
OS 12.31047068 19.1081406
OS 12.30954612 19.10721604
OS 12.30214964 19.10166868
OS 12.29475316 19.09519676
OS 12.28088476 19.08132836
OS 12.27441284 19.07485644
OS 12.26979004 19.06930908
OS 12.26701636 19.06561084
OS 12.2660918 19.06468628
OS 12.2568462 19.05174244
OS 12.24667604 19.03787404
OS 12.23650588 19.02308108
OS 12.22633572 19.00921268
OS 12.21801468 18.99626884
OS 12.21154276 18.98609868
OS 12.20876908 18.98240044
OS 12.20691996 18.97962676
OS 12.20507084 18.97777764
OS 12.20507084 18.97685308
OS 12.12093588 18.84371644
OS 12.01553604 18.84371644
OS 12.12555868 19.01753372
OS 12.13850252 19.03602492
OS 12.1505218 19.052667
OS 12.16254108 19.0665354
OS 12.17271124 19.07947924
OS 12.18195684 19.08872484
OS 12.18935332 19.09612132
OS 12.19397612 19.10074412
OS 12.19582524 19.10259324
OS 12.20322172 19.1081406
OS 12.21154276 19.11461252
OS 12.22818484 19.12478268
OS 12.23558132 19.12848092
OS 12.24112868 19.13217916
OS 12.24482692 19.13402828
OS 12.24667604 19.13495284
OS 12.23003396 19.13772652
OS 12.21431644 19.1405002
OS 12.20044804 19.145123
OS 12.18657964 19.14882124
OS 12.17456036 19.15344404
OS 12.16346564 19.1589914
OS 12.15329548 19.1636142
OS 12.14404988 19.168237
OS 12.1366534 19.17378436
OS 12.12925692 19.17840716
OS 12.12370956 19.1821054
OS 12.11908676 19.18580364
OS 12.11538852 19.18857732
OS 12.11261484 19.191351
OS 12.11169028 19.19227556
OS 12.11076572 19.19320012
OS 12.10336924 19.20244572
OS 12.09597276 19.21169132
OS 12.08487804 19.23110708
OS 12.07748156 19.25052284
OS 12.0719342 19.26901404
OS 12.06823596 19.28473156
OS 12.0673114 19.29120348
OS 12.0673114 19.2976754
OS 12.06638684 19.3022982
OS 12.06638684 19.30599644
OS 12.06638684 19.30784556
OS 12.06638684 19.30877012
OS 12.0673114 19.32818588
OS 12.07008508 19.34575252
OS 12.07470788 19.3623946
OS 12.07933068 19.376263
OS 12.08487804 19.38828228
OS 12.08857628 19.39752788
OS 12.09227452 19.40307524
OS 12.09319908 19.4039998
OS 12.09319908 19.40492436
OS 12.1042938 19.41971732
OS 12.11538852 19.43266116
OS 12.1274078 19.44375588
OS 12.13850252 19.45207692
OS 12.14867268 19.45854884
OS 12.15699372 19.46224708
OS 12.16254108 19.46502076
OS 12.16346564 19.46594532
OS 12.1643902 19.46594532
OS 12.17271124 19.468719
OS 12.1828814 19.47149268
OS 12.20322172 19.47611548
OS 12.22541116 19.47888916
OS 12.24575148 19.48166284
OS 12.26516724 19.4825874
OS 12.27348828 19.4825874
OE
OB 11.73816804 19.48536108 I
OS 11.74463996 19.48628564
OS 11.75388556 19.48628564
OS 11.77052764 19.48536108
OS 11.78624516 19.48443652
OS 11.80103812 19.48166284
OS 11.81490652 19.47888916
OS 11.82785036 19.47519092
OS 11.83986964 19.47149268
OS 11.85096436 19.46686988
OS 11.86113452 19.46224708
OS 11.87038012 19.45762428
OS 11.8777766 19.45300148
OS 11.88424852 19.44930324
OS 11.88979588 19.445605
OS 11.89441868 19.44283132
OS 11.89719236 19.44005764
OS 11.89904148 19.43913308
OS 11.89996604 19.43820852
OS 11.90921164 19.42896292
OS 11.91753268 19.41879276
OS 11.92585372 19.40769804
OS 11.93232564 19.39660332
OS 11.94342036 19.37441388
OS 11.95081684 19.35222444
OS 11.95359052 19.34205428
OS 11.9563642 19.33188412
OS 11.95821332 19.32356308
OS 11.96006244 19.3161666
OS 11.960987 19.30969468
OS 11.960987 19.30507188
OS 11.96191156 19.3022982
OS 11.96191156 19.30137364
OS 11.88147484 19.2930526
OS 11.87962572 19.31431748
OS 11.87592748 19.33280868
OS 11.87038012 19.34945076
OS 11.8639082 19.3623946
OS 11.85836084 19.37348932
OS 11.85281348 19.3808858
OS 11.84911524 19.3855086
OS 11.84726612 19.38735772
OS 11.83339772 19.39845244
OS 11.81860476 19.40677348
OS 11.80288724 19.4132454
OS 11.78901884 19.41694364
OS 11.776075 19.41971732
OS 11.76498028 19.42064188
OS 11.76128204 19.42156644
OS 11.75573468 19.42156644
OS 11.73631892 19.42064188
OS 11.71875228 19.41694364
OS 11.70395932 19.41139628
OS 11.69101548 19.40584892
OS 11.68084532 19.399377
OS 11.6743734 19.3947542
OS 11.6697506 19.39105596
OS 11.66790148 19.38920684
OS 11.65680676 19.376263
OS 11.64848572 19.36331916
OS 11.6420138 19.35037532
OS 11.63831556 19.33743148
OS 11.63554188 19.32726132
OS 11.63461732 19.31801572
OS 11.63369276 19.31246836
OS 11.63369276 19.3115438
OS 11.63369276 19.31061924
OS 11.63554188 19.29397716
OS 11.63924012 19.27641052
OS 11.64571204 19.260693
OS 11.65218396 19.24590004
OS 11.65958044 19.23388076
OS 11.66605236 19.2237106
OS 11.66790148 19.22001236
OS 11.6697506 19.21723868
OS 11.67159972 19.21631412
OS 11.67159972 19.21538956
OS 11.6789962 19.2052194
OS 11.6882418 19.19504924
OS 11.69841196 19.18395452
OS 11.70950668 19.1728598
OS 11.73262068 19.15067036
OS 11.75573468 19.12848092
OS 11.76775396 19.11831076
OS 11.77792412 19.10906516
OS 11.78809428 19.10074412
OS 11.79641532 19.09334764
OS 11.80288724 19.08780028
OS 11.8084346 19.08317748
OS 11.81213284 19.0804038
OS 11.8130574 19.07947924
OS 11.8361714 19.06006348
OS 11.85743628 19.04157228
OS 11.87500292 19.0249302
OS 11.88887132 19.0110618
OS 11.9008906 18.99904252
OS 11.90921164 18.99072148
OS 11.91383444 18.98517412
OS 11.91568356 18.98424956
OS 11.91568356 18.983325
OS 11.9286274 18.96760748
OS 11.93879756 18.95281452
OS 11.94804316 18.93802156
OS 11.95543964 18.92507772
OS 11.960987 18.913983
OS 11.96468524 18.90566196
OS 11.96653436 18.9001146
OS 11.96745892 18.89919004
OS 11.96745892 18.89826548
OS 11.97115716 18.88809532
OS 11.97300628 18.87884972
OS 11.9748554 18.86960412
OS 11.97577996 18.86128308
OS 11.97670452 18.8538866
OS 11.97670452 18.84833924
OS 11.97670452 18.844641
OS 11.97670452 18.84371644
OS 11.55233148 18.84371644
OS 11.55233148 18.91953036
OS 11.86760644 18.91953036
OS 11.85651172 18.93524788
OS 11.85096436 18.9417198
OS 11.84634156 18.94819172
OS 11.84171876 18.95373908
OS 11.83802052 18.95743732
OS 11.83524684 18.960211
OS 11.83432228 18.96113556
OS 11.82969948 18.96575836
OS 11.82415212 18.97038116
OS 11.81120828 18.98240044
OS 11.79641532 18.99626884
OS 11.7806978 19.01013724
OS 11.76590484 19.02215652
OS 11.75943292 19.02770388
OS 11.75388556 19.03325124
OS 11.74926276 19.03694948
OS 11.74556452 19.03972316
OS 11.7437154 19.04157228
OS 11.74279084 19.04249684
OS 11.72799788 19.05544068
OS 11.71320492 19.06745996
OS 11.70026108 19.07947924
OS 11.6882418 19.0896494
OS 11.67714708 19.09981956
OS 11.66790148 19.10906516
OS 11.65865588 19.1173862
OS 11.6512594 19.12478268
OS 11.64386292 19.13217916
OS 11.63831556 19.13772652
OS 11.63369276 19.14234932
OS 11.62906996 19.14697212
OS 11.62444716 19.15251948
OS 11.62259804 19.1543686
OS 11.6096542 19.17008612
OS 11.59855948 19.18395452
OS 11.58931388 19.19782292
OS 11.5819174 19.20891764
OS 11.57637004 19.2190878
OS 11.5726718 19.22648428
OS 11.57082268 19.23110708
OS 11.56989812 19.2329562
OS 11.56435076 19.2468246
OS 11.56065252 19.260693
OS 11.55695428 19.27363684
OS 11.55510516 19.28473156
OS 11.5541806 19.29490172
OS 11.55325604 19.3022982
OS 11.55325604 19.306921
OS 11.55325604 19.30877012
OS 11.5541806 19.32263852
OS 11.55602972 19.33558236
OS 11.55787884 19.3485262
OS 11.56157708 19.35962092
OS 11.57082268 19.38181036
OS 11.58006828 19.399377
OS 11.58561564 19.40769804
OS 11.59023844 19.41416996
OS 11.59486124 19.42064188
OS 11.59948404 19.42526468
OS 11.60318228 19.42896292
OS 11.6050314 19.43266116
OS 11.60688052 19.43358572
OS 11.60780508 19.43451028
OS 11.61797524 19.44375588
OS 11.62906996 19.45207692
OS 11.64108924 19.45854884
OS 11.65310852 19.4640962
OS 11.67714708 19.4733418
OS 11.70118564 19.47981372
OS 11.7113558 19.48166284
OS 11.72152596 19.48351196
OS 11.73077156 19.48443652
OS 11.73816804 19.48536108
OE
OB 12.29105492 19.41232084 H
OS 12.2660918 19.41139628
OS 12.24482692 19.40769804
OS 12.22633572 19.40307524
OS 12.21246732 19.39752788
OS 12.20044804 19.39198052
OS 12.19305156 19.38735772
OS 12.18842876 19.38365948
OS 12.18657964 19.38273492
OS 12.17548492 19.37071564
OS 12.16716388 19.35869636
OS 12.16161652 19.34575252
OS 12.15699372 19.3346578
OS 12.1551446 19.32356308
OS 12.15422004 19.31524204
OS 12.15329548 19.30969468
OS 12.15329548 19.30877012
OS 12.15329548 19.30784556
OS 12.15422004 19.29675084
OS 12.15606916 19.28565612
OS 12.15884284 19.27641052
OS 12.16161652 19.26808948
OS 12.16531476 19.260693
OS 12.16808844 19.25514564
OS 12.16993756 19.2514474
OS 12.17086212 19.25052284
OS 12.17733404 19.24127724
OS 12.18565508 19.2329562
OS 12.19397612 19.22648428
OS 12.20229716 19.22093692
OS 12.20969364 19.21723868
OS 12.215241 19.214465
OS 12.21893924 19.21261588
OS 12.22078836 19.21169132
OS 12.2337322 19.20799308
OS 12.24852516 19.2052194
OS 12.26331812 19.20337028
OS 12.27811108 19.20244572
OS 12.29105492 19.20152116
OS 12.30214964 19.2005966
OS 12.492609 19.2005966
OS 12.492609 19.41232084
OS 12.29105492 19.41232084
OE
SE
S P 0
OB 12.2753374 18.33005478 I
OS 12.28273388 18.33097934
OS 12.57951764 18.33097934
OS 12.57951764 17.69118382
OS 12.49445812 17.69118382
OS 12.49445812 17.97502374
OS 12.38536004 17.97502374
OS 12.37518988 17.97409918
OS 12.3677934 17.97409918
OS 12.36132148 17.97317462
OS 12.35669868 17.97225006
OS 12.35300044 17.97225006
OS 12.35115132 17.9713255
OS 12.35022676 17.9713255
OS 12.3354338 17.9667027
OS 12.32896188 17.96392902
OS 12.32341452 17.96115534
OS 12.31786716 17.95838166
OS 12.31416892 17.95653254
OS 12.3123198 17.95560798
OS 12.31139524 17.95468342
OS 12.30399876 17.94913606
OS 12.29660228 17.94266414
OS 12.28273388 17.92879574
OS 12.27626196 17.92232382
OS 12.27163916 17.91677646
OS 12.26886548 17.91307822
OS 12.26794092 17.91215366
OS 12.25869532 17.89920982
OS 12.24852516 17.88534142
OS 12.238355 17.87054846
OS 12.22818484 17.85668006
OS 12.2198638 17.84373622
OS 12.21339188 17.83356606
OS 12.2106182 17.82986782
OS 12.20876908 17.82709414
OS 12.20691996 17.82524502
OS 12.20691996 17.82432046
OS 12.122785 17.69118382
OS 12.01738516 17.69118382
OS 12.1274078 17.8650011
OS 12.14035164 17.8834923
OS 12.15237092 17.90013438
OS 12.1643902 17.91400278
OS 12.17456036 17.92694662
OS 12.18380596 17.93619222
OS 12.19120244 17.9435887
OS 12.19582524 17.9482115
OS 12.19767436 17.95006062
OS 12.20507084 17.95560798
OS 12.21339188 17.9620799
OS 12.23003396 17.97225006
OS 12.23743044 17.9759483
OS 12.2429778 17.97964654
OS 12.24667604 17.98149566
OS 12.24852516 17.98242022
OS 12.23188308 17.9851939
OS 12.21616556 17.98796758
OS 12.20229716 17.99259038
OS 12.18842876 17.99628862
OS 12.17640948 18.00091142
OS 12.16531476 18.00645878
OS 12.1551446 18.01108158
OS 12.145899 18.01570438
OS 12.13850252 18.02125174
OS 12.13110604 18.02587454
OS 12.12555868 18.02957278
OS 12.12093588 18.03327102
OS 12.11723764 18.0360447
OS 12.11446396 18.03881838
OS 12.1135394 18.03974294
OS 12.11261484 18.0406675
OS 12.10521836 18.0499131
OS 12.09782188 18.0591587
OS 12.08672716 18.07857446
OS 12.07933068 18.09799022
OS 12.07378332 18.11648142
OS 12.07008508 18.13219894
OS 12.06916052 18.13867086
OS 12.06916052 18.14514278
OS 12.06823596 18.14976558
OS 12.06823596 18.15346382
OS 12.06823596 18.15531294
OS 12.06823596 18.1562375
OS 12.06916052 18.17565326
OS 12.0719342 18.1932199
OS 12.076557 18.20986198
OS 12.0811798 18.22373038
OS 12.08672716 18.23574966
OS 12.0904254 18.24499526
OS 12.09412364 18.25054262
OS 12.0950482 18.25146718
OS 12.0950482 18.25239174
OS 12.10614292 18.2671847
OS 12.11723764 18.28012854
OS 12.12925692 18.29122326
OS 12.14035164 18.2995443
OS 12.1505218 18.30601622
OS 12.15884284 18.30971446
OS 12.1643902 18.31248814
OS 12.16531476 18.3134127
OS 12.16623932 18.3134127
OS 12.17456036 18.31618638
OS 12.18473052 18.31896006
OS 12.20507084 18.32358286
OS 12.22726028 18.32635654
OS 12.2476006 18.32913022
OS 12.26701636 18.33005478
OS 12.2753374 18.33005478
OE
OB 11.637391 17.91677646 I
OS 11.637391 18.33097934
OS 11.70118564 18.33097934
OS 11.99427116 17.91677646
OS 11.99427116 17.84466078
OS 11.7159786 17.84466078
OS 11.7159786 17.69118382
OS 11.637391 17.69118382
OS 11.637391 17.84466078
OS 11.55048236 17.84466078
OS 11.55048236 17.91677646
OS 11.637391 17.91677646
OE
OB 11.7159786 18.20339006 H
OS 11.7159786 17.91677646
OS 11.91753268 17.91677646
OS 11.7159786 18.20339006
OE
OB 12.29290404 18.25978822 H
OS 12.26794092 18.25886366
OS 12.24667604 18.25516542
OS 12.22818484 18.25054262
OS 12.21431644 18.24499526
OS 12.20229716 18.2394479
OS 12.19490068 18.2348251
OS 12.19027788 18.23112686
OS 12.18842876 18.2302023
OS 12.17733404 18.21818302
OS 12.169013 18.20616374
OS 12.16346564 18.1932199
OS 12.15884284 18.18212518
OS 12.15699372 18.17103046
OS 12.15606916 18.16270942
OS 12.1551446 18.15716206
OS 12.1551446 18.1562375
OS 12.1551446 18.15531294
OS 12.15606916 18.14421822
OS 12.15791828 18.1331235
OS 12.16069196 18.1238779
OS 12.16346564 18.11555686
OS 12.16716388 18.10816038
OS 12.16993756 18.10261302
OS 12.17178668 18.09891478
OS 12.17271124 18.09799022
OS 12.17918316 18.08874462
OS 12.1875042 18.08042358
OS 12.19582524 18.07395166
OS 12.20414628 18.0684043
OS 12.21154276 18.06470606
OS 12.21709012 18.06193238
OS 12.22078836 18.06008326
OS 12.22263748 18.0591587
OS 12.23558132 18.05546046
OS 12.25037428 18.05268678
OS 12.26516724 18.05083766
OS 12.2799602 18.0499131
OS 12.29290404 18.04898854
OS 12.30399876 18.04806398
OS 12.49445812 18.04806398
OS 12.49445812 18.25978822
OS 12.29290404 18.25978822
OE
SE
S P 0
OB 14.33057332 12.72006854 I
OS 14.33704524 12.7209931
OS 14.34629084 12.7209931
OS 14.37680132 12.71914398
OS 14.40638724 12.71452118
OS 14.43227492 12.70897382
OS 14.4442942 12.70527558
OS 14.45538892 12.70157734
OS 14.46555908 12.6978791
OS 14.47480468 12.69418086
OS 14.48220116 12.69140718
OS 14.48959764 12.6886335
OS 14.49422044 12.68585982
OS 14.49791868 12.6840107
OS 14.50069236 12.68308614
OS 14.50161692 12.68216158
OS 14.52658004 12.66644406
OS 14.54784492 12.64795286
OS 14.56633612 12.62946166
OS 14.58205364 12.61097046
OS 14.59407292 12.59432838
OS 14.59869572 12.5869319
OS 14.60239396 12.58045998
OS 14.6060922 12.57583718
OS 14.60794132 12.57213894
OS 14.60886588 12.56936526
OS 14.60979044 12.5684407
OS 14.62273428 12.53977934
OS 14.63197988 12.51019342
OS 14.6384518 12.4806075
OS 14.6430746 12.45379526
OS 14.64492372 12.44177598
OS 14.64584828 12.4297567
OS 14.64677284 12.4205111
OS 14.64677284 12.4112655
OS 14.6476974 12.40479358
OS 14.6476974 12.39924622
OS 14.6476974 12.39554798
OS 14.6476974 12.39462342
OS 14.64584828 12.36133926
OS 14.64215004 12.32897966
OS 14.63752724 12.3003183
OS 14.633829 12.2864499
OS 14.63105532 12.27443062
OS 14.62828164 12.2633359
OS 14.6245834 12.25316574
OS 14.62180972 12.24392014
OS 14.6199606 12.23652366
OS 14.61718692 12.2309763
OS 14.61626236 12.2263535
OS 14.61441324 12.22357982
OS 14.61441324 12.22265526
OS 14.60054484 12.19491846
OS 14.58482732 12.16995534
OS 14.56818524 12.14869046
OS 14.5598642 12.14036942
OS 14.55246772 12.13204838
OS 14.54507124 12.1246519
OS 14.53767476 12.11817998
OS 14.53120284 12.11263262
OS 14.52565548 12.10893438
OS 14.52195724 12.10523614
OS 14.518259 12.10246246
OS 14.51640988 12.1015379
OS 14.51548532 12.10061334
OS 14.50254148 12.09321686
OS 14.48959764 12.08674494
OS 14.46186084 12.07657478
OS 14.43412404 12.0691783
OS 14.4073118 12.0645555
OS 14.39436796 12.06270638
OS 14.38327324 12.06085726
OS 14.37310308 12.0599327
OS 14.36478204 12.0599327
OS 14.35738556 12.05900814
OS 14.3472154 12.05900814
OS 14.3287242 12.0599327
OS 14.31115756 12.06178182
OS 14.29451548 12.06363094
OS 14.27879796 12.06732918
OS 14.264005 12.07195198
OS 14.2501366 12.07657478
OS 14.23719276 12.08119758
OS 14.22517348 12.08674494
OS 14.21500332 12.09136774
OS 14.20483316 12.09599054
OS 14.19743668 12.10061334
OS 14.1900402 12.10523614
OS 14.1854174 12.10893438
OS 14.1807946 12.1107835
OS 14.17894548 12.11263262
OS 14.17802092 12.11355718
OS 14.16507708 12.1246519
OS 14.15398236 12.13574662
OS 14.1438122 12.14869046
OS 14.13364204 12.1616343
OS 14.11699996 12.18752198
OS 14.10405612 12.21340966
OS 14.09850876 12.22542894
OS 14.09388596 12.23652366
OS 14.09018772 12.24669382
OS 14.08741404 12.25501486
OS 14.08464036 12.26241134
OS 14.08279124 12.2679587
OS 14.08186668 12.27165694
OS 14.08186668 12.2725815
OS 14.1669262 12.29384638
OS 14.17062444 12.27905342
OS 14.17524724 12.26518502
OS 14.17987004 12.25224118
OS 14.18449284 12.2402219
OS 14.1900402 12.22912718
OS 14.19558756 12.21988158
OS 14.20205948 12.21063598
OS 14.20760684 12.20231494
OS 14.21222964 12.19491846
OS 14.217777 12.1893711
OS 14.2223998 12.18382374
OS 14.22609804 12.17920094
OS 14.22979628 12.17642726
OS 14.23256996 12.17365358
OS 14.23349452 12.17272902
OS 14.23441908 12.17180446
OS 14.24366468 12.16440798
OS 14.25383484 12.15886062
OS 14.27417516 12.14869046
OS 14.29359092 12.14129398
OS 14.31300668 12.13667118
OS 14.32964876 12.13297294
OS 14.33612068 12.13204838
OS 14.3425926 12.13204838
OS 14.34813996 12.13112382
OS 14.35461188 12.13112382
OS 14.37587676 12.13204838
OS 14.39621708 12.13574662
OS 14.41470828 12.14036942
OS 14.43135036 12.14591678
OS 14.4442942 12.15146414
OS 14.44984156 12.15423782
OS 14.45446436 12.15608694
OS 14.4581626 12.15793606
OS 14.46093628 12.15978518
OS 14.4627854 12.16070974
OS 14.46370996 12.16070974
OS 14.4812766 12.17365358
OS 14.49606956 12.18752198
OS 14.5090134 12.2032395
OS 14.51918356 12.21803246
OS 14.5275046 12.2309763
OS 14.53305196 12.24207102
OS 14.53490108 12.24669382
OS 14.5367502 12.2494675
OS 14.53767476 12.25131662
OS 14.53767476 12.25224118
OS 14.54507124 12.27627974
OS 14.5506186 12.3003183
OS 14.5552414 12.32435686
OS 14.55801508 12.3465463
OS 14.55893964 12.35671646
OS 14.5598642 12.36596206
OS 14.5598642 12.3742831
OS 14.56078876 12.38075502
OS 14.56078876 12.38630238
OS 14.56078876 12.39092518
OS 14.56078876 12.39369886
OS 14.56078876 12.39462342
OS 14.5598642 12.41866198
OS 14.55801508 12.44085142
OS 14.55431684 12.46119174
OS 14.5506186 12.47968294
OS 14.54784492 12.49540046
OS 14.5459958 12.50187238
OS 14.54414668 12.50741974
OS 14.54322212 12.51204254
OS 14.54229756 12.51481622
OS 14.541373 12.51666534
OS 14.541373 12.5175899
OS 14.5321274 12.53885478
OS 14.52195724 12.55827054
OS 14.51086252 12.57398806
OS 14.49884324 12.58785646
OS 14.48867308 12.59895118
OS 14.48035204 12.60634766
OS 14.47388012 12.61097046
OS 14.47295556 12.61281958
OS 14.472031 12.61281958
OS 14.45261524 12.62483886
OS 14.43135036 12.63408446
OS 14.41101004 12.64055638
OS 14.39159428 12.64425462
OS 14.37402764 12.6470283
OS 14.36663116 12.64795286
OS 14.36015924 12.64795286
OS 14.35553644 12.64887742
OS 14.34813996 12.64887742
OS 14.32502596 12.64795286
OS 14.30376108 12.64425462
OS 14.28619444 12.63870726
OS 14.27047692 12.6331599
OS 14.25845764 12.62668798
OS 14.24921204 12.62206518
OS 14.24366468 12.61836694
OS 14.24181556 12.61651782
OS 14.2270226 12.60264942
OS 14.2131542 12.5869319
OS 14.20205948 12.57028982
OS 14.19281388 12.55364774
OS 14.1854174 12.53885478
OS 14.18264372 12.5314583
OS 14.1807946 12.52591094
OS 14.17894548 12.52128814
OS 14.17709636 12.5175899
OS 14.1761718 12.51574078
OS 14.1761718 12.51481622
OS 14.0929614 12.53423198
OS 14.09850876 12.55087406
OS 14.10405612 12.56566702
OS 14.1114526 12.57953542
OS 14.11792452 12.59340382
OS 14.125321 12.6054231
OS 14.13364204 12.61651782
OS 14.14103852 12.62761254
OS 14.148435 12.63685814
OS 14.15583148 12.64425462
OS 14.1623034 12.6516511
OS 14.16877532 12.65812302
OS 14.17339812 12.66274582
OS 14.17802092 12.66736862
OS 14.18171916 12.6701423
OS 14.18356828 12.67106686
OS 14.18449284 12.67199142
OS 14.19743668 12.68031246
OS 14.21038052 12.6886335
OS 14.22332436 12.69510542
OS 14.23719276 12.70065278
OS 14.26492956 12.70897382
OS 14.28989268 12.71452118
OS 14.30191196 12.71729486
OS 14.31208212 12.71821942
OS 14.32225228 12.71914398
OS 14.33057332 12.72006854
OE
OB 13.59000076 12.63963182 I
OS 13.59000076 12.70157734
OS 14.00420364 12.70157734
OS 14.00420364 12.62576342
OS 13.6907778 12.62576342
OS 13.71296724 12.59895118
OS 13.73423212 12.57028982
OS 13.75272332 12.54255302
OS 13.77028996 12.51574078
OS 13.77768644 12.5037215
OS 13.78415836 12.49262678
OS 13.79063028 12.48245662
OS 13.79525308 12.47413558
OS 13.79895132 12.4667391
OS 13.801725 12.4621163
OS 13.80357412 12.45841806
OS 13.80449868 12.4574935
OS 13.82298988 12.4205111
OS 13.83963196 12.3835287
OS 13.85350036 12.34839542
OS 13.85904772 12.3326779
OS 13.86459508 12.31696038
OS 13.87014244 12.30309198
OS 13.87384068 12.29014814
OS 13.87753892 12.27905342
OS 13.8803126 12.26980782
OS 13.88308628 12.26148678
OS 13.8849354 12.25593942
OS 13.88585996 12.25224118
OS 13.88585996 12.25131662
OS 13.89510556 12.21340966
OS 13.8988038 12.19491846
OS 13.90157748 12.17827638
OS 13.90435116 12.16255886
OS 13.90712484 12.14684134
OS 13.90897396 12.1338975
OS 13.91082308 12.12095366
OS 13.91174764 12.10985894
OS 13.9126722 12.09968878
OS 13.91359676 12.09044318
OS 13.91359676 12.0830467
OS 13.91452132 12.07749934
OS 13.91452132 12.0738011
OS 13.91452132 12.07102742
OS 13.91452132 12.07010286
OS 13.8340846 12.07010286
OS 13.83131092 12.10523614
OS 13.82668812 12.13759574
OS 13.82206532 12.16718166
OS 13.81929164 12.18105006
OS 13.81651796 12.1939939
OS 13.81466884 12.20508862
OS 13.81189516 12.21525878
OS 13.81004604 12.22450438
OS 13.80819692 12.23190086
OS 13.8063478 12.23744822
OS 13.80542324 12.24207102
OS 13.80449868 12.2448447
OS 13.80449868 12.24576926
OS 13.79063028 12.28829902
OS 13.77583732 12.3280551
OS 13.76844084 12.34747086
OS 13.76104436 12.36596206
OS 13.75272332 12.38260414
OS 13.74532684 12.39924622
OS 13.73885492 12.41403918
OS 13.732383 12.42698302
OS 13.72683564 12.43807774
OS 13.72221284 12.4482479
OS 13.71759004 12.45656894
OS 13.71481636 12.4621163
OS 13.71296724 12.46581454
OS 13.71204268 12.4667391
OS 13.70094796 12.48615486
OS 13.68985324 12.50557062
OS 13.67875852 12.52313726
OS 13.6676638 12.53977934
OS 13.65749364 12.5545723
OS 13.64732348 12.56936526
OS 13.63715332 12.5823091
OS 13.62883228 12.59340382
OS 13.62051124 12.60449854
OS 13.61311476 12.61374414
OS 13.60571828 12.62114062
OS 13.60017092 12.62761254
OS 13.59647268 12.6331599
OS 13.59277444 12.63685814
OS 13.59092532 12.63870726
OS 13.59000076 12.63963182
OE
SE
S P 0
OB 13.78831888 7.7117448 I
OS 13.79386624 7.71266936
OS 13.80218728 7.71266936
OS 13.81698024 7.7117448
OS 13.8317732 7.71082024
OS 13.85766088 7.70527288
OS 13.86968016 7.70157464
OS 13.88077488 7.6978764
OS 13.89094504 7.6932536
OS 13.90019064 7.6886308
OS 13.90758712 7.684008
OS 13.9149836 7.6793852
OS 13.92145552 7.67568696
OS 13.92607832 7.67198872
OS 13.92977656 7.66921504
OS 13.93255024 7.66644136
OS 13.93439936 7.6655168
OS 13.93532392 7.66459224
OS 13.94364496 7.65534664
OS 13.951966 7.64610104
OS 13.95843792 7.63593088
OS 13.96398528 7.62576072
OS 13.97323088 7.60634496
OS 13.97877824 7.58785376
OS 13.98247648 7.57213624
OS 13.98340104 7.56473976
OS 13.9843256 7.5591924
OS 13.98525016 7.55364504
OS 13.98525016 7.5499468
OS 13.98525016 7.54809768
OS 13.98525016 7.54717312
OS 13.9843256 7.53053104
OS 13.98155192 7.51481352
OS 13.97785368 7.50094512
OS 13.97323088 7.48892584
OS 13.96953264 7.47968024
OS 13.9658344 7.47228376
OS 13.96306072 7.46858552
OS 13.96213616 7.4667364
OS 13.951966 7.45564168
OS 13.94087128 7.44547152
OS 13.928852 7.43622592
OS 13.91683272 7.42882944
OS 13.905738 7.42328208
OS 13.89741696 7.41958384
OS 13.89371872 7.41773472
OS 13.89094504 7.41681016
OS 13.89002048 7.4158856
OS 13.88909592 7.4158856
OS 13.9103608 7.40941368
OS 13.92792744 7.40109264
OS 13.94364496 7.39092248
OS 13.9565888 7.38167688
OS 13.96675896 7.37243128
OS 13.97415544 7.3650348
OS 13.97785368 7.360412
OS 13.9797028 7.35948744
OS 13.9797028 7.35856288
OS 13.98987296 7.3419208
OS 13.998194 7.32435416
OS 14.00374136 7.30771208
OS 14.0074396 7.29107
OS 14.00928872 7.27627704
OS 14.01021328 7.26980512
OS 14.01021328 7.26425776
OS 14.01113784 7.26055952
OS 14.01113784 7.25686128
OS 14.01113784 7.25501216
OS 14.01113784 7.2540876
OS 14.01021328 7.23929464
OS 14.00836416 7.22450168
OS 14.00559048 7.21063328
OS 14.00189224 7.19676488
OS 13.99264664 7.17365088
OS 13.98802384 7.16255616
OS 13.98247648 7.15331056
OS 13.97692912 7.14406496
OS 13.97230632 7.13666848
OS 13.96675896 7.13019656
OS 13.96306072 7.1246492
OS 13.95936248 7.1200264
OS 13.9565888 7.11725272
OS 13.95473968 7.1154036
OS 13.95381512 7.11447904
OS 13.9427204 7.10430888
OS 13.93070112 7.09598784
OS 13.91775728 7.08859136
OS 13.90481344 7.08211944
OS 13.89279416 7.07749664
OS 13.87985032 7.07287384
OS 13.8548872 7.06640192
OS 13.84379248 7.06362824
OS 13.83362232 7.06177912
OS 13.82437672 7.06085456
OS 13.81605568 7.05993
OS 13.80958376 7.05900544
OS 13.80033816 7.05900544
OS 13.78277152 7.05993
OS 13.767054 7.06177912
OS 13.75133648 7.0645528
OS 13.73654352 7.06732648
OS 13.72359968 7.07194928
OS 13.71065584 7.07657208
OS 13.69863656 7.08119488
OS 13.6884664 7.08674224
OS 13.6792208 7.0922896
OS 13.67089976 7.0969124
OS 13.66442784 7.1015352
OS 13.65795592 7.106158
OS 13.65333312 7.10893168
OS 13.65055944 7.11170536
OS 13.64871032 7.11355448
OS 13.64778576 7.11447904
OS 13.6376156 7.12557376
OS 13.62837 7.13666848
OS 13.62097352 7.1477632
OS 13.6145016 7.15978248
OS 13.60802968 7.1708772
OS 13.60340688 7.18289648
OS 13.59693496 7.20416136
OS 13.59416128 7.21433152
OS 13.59231216 7.22357712
OS 13.5913876 7.23189816
OS 13.59046304 7.23837008
OS 13.58953848 7.24391744
OS 13.58953848 7.24854024
OS 13.58953848 7.25131392
OS 13.58953848 7.25223848
OS 13.59046304 7.27350336
OS 13.59416128 7.29291912
OS 13.59970864 7.31048576
OS 13.605256 7.32527872
OS 13.61080336 7.337298
OS 13.61635072 7.3465436
OS 13.62004896 7.35209096
OS 13.62097352 7.35301552
OS 13.62097352 7.35394008
OS 13.63391736 7.36873304
OS 13.64778576 7.38167688
OS 13.66257872 7.39184704
OS 13.67644712 7.40109264
OS 13.68939096 7.40756456
OS 13.70048568 7.41218736
OS 13.70418392 7.41403648
OS 13.7069576 7.41496104
OS 13.70880672 7.4158856
OS 13.70973128 7.4158856
OS 13.6930892 7.42328208
OS 13.6792208 7.43160312
OS 13.66720152 7.43992416
OS 13.65703136 7.4482452
OS 13.64963488 7.45564168
OS 13.64408752 7.46118904
OS 13.64038928 7.46488728
OS 13.63946472 7.4667364
OS 13.63114368 7.47968024
OS 13.62559632 7.49262408
OS 13.62097352 7.50556792
OS 13.61819984 7.51851176
OS 13.61635072 7.52868192
OS 13.61542616 7.53700296
OS 13.61542616 7.54255032
OS 13.61542616 7.54347488
OS 13.61542616 7.54439944
OS 13.61635072 7.55734328
OS 13.61727528 7.56936256
OS 13.6237472 7.59247656
OS 13.63206824 7.61281688
OS 13.64131384 7.63038352
OS 13.65055944 7.64425192
OS 13.65518224 7.64979928
OS 13.65888048 7.65534664
OS 13.66257872 7.65904488
OS 13.6653524 7.66181856
OS 13.66627696 7.66274312
OS 13.66720152 7.66366768
OS 13.67737168 7.67198872
OS 13.68754184 7.68030976
OS 13.69863656 7.68678168
OS 13.70973128 7.69232904
OS 13.73192072 7.70065008
OS 13.75411016 7.70619744
OS 13.76335576 7.70897112
OS 13.77260136 7.70989568
OS 13.7809224 7.71082024
OS 13.78831888 7.7117448
OE
OB 14.3310356 7.72006584 I
OS 14.33750752 7.7209904
OS 14.34675312 7.7209904
OS 14.3772636 7.71914128
OS 14.40684952 7.71451848
OS 14.4327372 7.70897112
OS 14.44475648 7.70527288
OS 14.4558512 7.70157464
OS 14.46602136 7.6978764
OS 14.47526696 7.69417816
OS 14.48266344 7.69140448
OS 14.49005992 7.6886308
OS 14.49468272 7.68585712
OS 14.49838096 7.684008
OS 14.50115464 7.68308344
OS 14.5020792 7.68215888
OS 14.52704232 7.66644136
OS 14.5483072 7.64795016
OS 14.5667984 7.62945896
OS 14.58251592 7.61096776
OS 14.5945352 7.59432568
OS 14.599158 7.5869292
OS 14.60285624 7.58045728
OS 14.60655448 7.57583448
OS 14.6084036 7.57213624
OS 14.60932816 7.56936256
OS 14.61025272 7.568438
OS 14.62319656 7.53977664
OS 14.63244216 7.51019072
OS 14.63891408 7.4806048
OS 14.64353688 7.45379256
OS 14.645386 7.44177328
OS 14.64631056 7.429754
OS 14.64723512 7.4205084
OS 14.64723512 7.4112628
OS 14.64815968 7.40479088
OS 14.64815968 7.39924352
OS 14.64815968 7.39554528
OS 14.64815968 7.39462072
OS 14.64631056 7.36133656
OS 14.64261232 7.32897696
OS 14.63798952 7.3003156
OS 14.63429128 7.2864472
OS 14.6315176 7.27442792
OS 14.62874392 7.2633332
OS 14.62504568 7.25316304
OS 14.622272 7.24391744
OS 14.62042288 7.23652096
OS 14.6176492 7.2309736
OS 14.61672464 7.2263508
OS 14.61487552 7.22357712
OS 14.61487552 7.22265256
OS 14.60100712 7.19491576
OS 14.5852896 7.16995264
OS 14.56864752 7.14868776
OS 14.56032648 7.14036672
OS 14.55293 7.13204568
OS 14.54553352 7.1246492
OS 14.53813704 7.11817728
OS 14.53166512 7.11262992
OS 14.52611776 7.10893168
OS 14.52241952 7.10523344
OS 14.51872128 7.10245976
OS 14.51687216 7.1015352
OS 14.5159476 7.10061064
OS 14.50300376 7.09321416
OS 14.49005992 7.08674224
OS 14.46232312 7.07657208
OS 14.43458632 7.0691756
OS 14.40777408 7.0645528
OS 14.39483024 7.06270368
OS 14.38373552 7.06085456
OS 14.37356536 7.05993
OS 14.36524432 7.05993
OS 14.35784784 7.05900544
OS 14.34767768 7.05900544
OS 14.32918648 7.05993
OS 14.31161984 7.06177912
OS 14.29497776 7.06362824
OS 14.27926024 7.06732648
OS 14.26446728 7.07194928
OS 14.25059888 7.07657208
OS 14.23765504 7.08119488
OS 14.22563576 7.08674224
OS 14.2154656 7.09136504
OS 14.20529544 7.09598784
OS 14.19789896 7.10061064
OS 14.19050248 7.10523344
OS 14.18587968 7.10893168
OS 14.18125688 7.1107808
OS 14.17940776 7.11262992
OS 14.1784832 7.11355448
OS 14.16553936 7.1246492
OS 14.15444464 7.13574392
OS 14.14427448 7.14868776
OS 14.13410432 7.1616316
OS 14.11746224 7.18751928
OS 14.1045184 7.21340696
OS 14.09897104 7.22542624
OS 14.09434824 7.23652096
OS 14.09065 7.24669112
OS 14.08787632 7.25501216
OS 14.08510264 7.26240864
OS 14.08325352 7.267956
OS 14.08232896 7.27165424
OS 14.08232896 7.2725788
OS 14.16738848 7.29384368
OS 14.17108672 7.27905072
OS 14.17570952 7.26518232
OS 14.18033232 7.25223848
OS 14.18495512 7.2402192
OS 14.19050248 7.22912448
OS 14.19604984 7.21987888
OS 14.20252176 7.21063328
OS 14.20806912 7.20231224
OS 14.21269192 7.19491576
OS 14.21823928 7.1893684
OS 14.22286208 7.18382104
OS 14.22656032 7.17919824
OS 14.23025856 7.17642456
OS 14.23303224 7.17365088
OS 14.2339568 7.17272632
OS 14.23488136 7.17180176
OS 14.24412696 7.16440528
OS 14.25429712 7.15885792
OS 14.27463744 7.14868776
OS 14.2940532 7.14129128
OS 14.31346896 7.13666848
OS 14.33011104 7.13297024
OS 14.33658296 7.13204568
OS 14.34305488 7.13204568
OS 14.34860224 7.13112112
OS 14.35507416 7.13112112
OS 14.37633904 7.13204568
OS 14.39667936 7.13574392
OS 14.41517056 7.14036672
OS 14.43181264 7.14591408
OS 14.44475648 7.15146144
OS 14.45030384 7.15423512
OS 14.45492664 7.15608424
OS 14.45862488 7.15793336
OS 14.46139856 7.15978248
OS 14.46324768 7.16070704
OS 14.46417224 7.16070704
OS 14.48173888 7.17365088
OS 14.49653184 7.18751928
OS 14.50947568 7.2032368
OS 14.51964584 7.21802976
OS 14.52796688 7.2309736
OS 14.53351424 7.24206832
OS 14.53536336 7.24669112
OS 14.53721248 7.2494648
OS 14.53813704 7.25131392
OS 14.53813704 7.25223848
OS 14.54553352 7.27627704
OS 14.55108088 7.3003156
OS 14.55570368 7.32435416
OS 14.55847736 7.3465436
OS 14.55940192 7.35671376
OS 14.56032648 7.36595936
OS 14.56032648 7.3742804
OS 14.56125104 7.38075232
OS 14.56125104 7.38629968
OS 14.56125104 7.39092248
OS 14.56125104 7.39369616
OS 14.56125104 7.39462072
OS 14.56032648 7.41865928
OS 14.55847736 7.44084872
OS 14.55477912 7.46118904
OS 14.55108088 7.47968024
OS 14.5483072 7.49539776
OS 14.54645808 7.50186968
OS 14.54460896 7.50741704
OS 14.5436844 7.51203984
OS 14.54275984 7.51481352
OS 14.54183528 7.51666264
OS 14.54183528 7.5175872
OS 14.53258968 7.53885208
OS 14.52241952 7.55826784
OS 14.5113248 7.57398536
OS 14.49930552 7.58785376
OS 14.48913536 7.59894848
OS 14.48081432 7.60634496
OS 14.4743424 7.61096776
OS 14.47341784 7.61281688
OS 14.47249328 7.61281688
OS 14.45307752 7.62483616
OS 14.43181264 7.63408176
OS 14.41147232 7.64055368
OS 14.39205656 7.64425192
OS 14.37448992 7.6470256
OS 14.36709344 7.64795016
OS 14.36062152 7.64795016
OS 14.35599872 7.64887472
OS 14.34860224 7.64887472
OS 14.32548824 7.64795016
OS 14.30422336 7.64425192
OS 14.28665672 7.63870456
OS 14.2709392 7.6331572
OS 14.25891992 7.62668528
OS 14.24967432 7.62206248
OS 14.24412696 7.61836424
OS 14.24227784 7.61651512
OS 14.22748488 7.60264672
OS 14.21361648 7.5869292
OS 14.20252176 7.57028712
OS 14.19327616 7.55364504
OS 14.18587968 7.53885208
OS 14.183106 7.5314556
OS 14.18125688 7.52590824
OS 14.17940776 7.52128544
OS 14.17755864 7.5175872
OS 14.17663408 7.51573808
OS 14.17663408 7.51481352
OS 14.09342368 7.53422928
OS 14.09897104 7.55087136
OS 14.1045184 7.56566432
OS 14.11191488 7.57953272
OS 14.1183868 7.59340112
OS 14.12578328 7.6054204
OS 14.13410432 7.61651512
OS 14.1415008 7.62760984
OS 14.14889728 7.63685544
OS 14.15629376 7.64425192
OS 14.16276568 7.6516484
OS 14.1692376 7.65812032
OS 14.1738604 7.66274312
OS 14.1784832 7.66736592
OS 14.18218144 7.6701396
OS 14.18403056 7.67106416
OS 14.18495512 7.67198872
OS 14.19789896 7.68030976
OS 14.2108428 7.6886308
OS 14.22378664 7.69510272
OS 14.23765504 7.70065008
OS 14.26539184 7.70897112
OS 14.29035496 7.71451848
OS 14.30237424 7.71729216
OS 14.3125444 7.71821672
OS 14.32271456 7.71914128
OS 14.3310356 7.72006584
OE
OB 13.80033816 7.64795016 H
OS 13.78462064 7.6470256
OS 13.76982768 7.64332736
OS 13.7578084 7.63870456
OS 13.74671368 7.6331572
OS 13.73839264 7.62760984
OS 13.73192072 7.62298704
OS 13.72729792 7.6192888
OS 13.72637336 7.61836424
OS 13.7162032 7.60634496
OS 13.70880672 7.59432568
OS 13.70325936 7.5823064
OS 13.69956112 7.57121168
OS 13.697712 7.56104152
OS 13.69586288 7.55272048
OS 13.69586288 7.54717312
OS 13.69586288 7.54624856
OS 13.69586288 7.545324
OS 13.69678744 7.53053104
OS 13.70048568 7.51666264
OS 13.70510848 7.50464336
OS 13.71065584 7.4944732
OS 13.7162032 7.48615216
OS 13.720826 7.4806048
OS 13.72452424 7.475982
OS 13.7254488 7.47505744
OS 13.73654352 7.46581184
OS 13.74948736 7.45841536
OS 13.76150664 7.45379256
OS 13.77352592 7.45009432
OS 13.78462064 7.4482452
OS 13.79294168 7.44732064
OS 13.79848904 7.44639608
OS 13.80033816 7.44639608
OS 13.81698024 7.44732064
OS 13.8317732 7.45101888
OS 13.84471704 7.45564168
OS 13.85581176 7.46118904
OS 13.8641328 7.46581184
OS 13.87060472 7.47043464
OS 13.87522752 7.47413288
OS 13.87615208 7.47505744
OS 13.88539768 7.48615216
OS 13.89279416 7.499096
OS 13.89741696 7.51111528
OS 13.9011152 7.52313456
OS 13.90296432 7.53330472
OS 13.90388888 7.54162576
OS 13.90481344 7.54717312
OS 13.90481344 7.54809768
OS 13.90481344 7.54902224
OS 13.90388888 7.5638152
OS 13.90019064 7.57675904
OS 13.89556784 7.58877832
OS 13.89002048 7.59894848
OS 13.88539768 7.60726952
OS 13.88077488 7.61374144
OS 13.87707664 7.61743968
OS 13.87615208 7.61836424
OS 13.8641328 7.6285344
OS 13.85211352 7.63593088
OS 13.83916968 7.64055368
OS 13.8271504 7.64425192
OS 13.81605568 7.64610104
OS 13.80773464 7.64795016
OS 13.80033816 7.64795016
OE
OB 13.80311184 7.38260144 H
OS 13.78277152 7.38075232
OS 13.76428032 7.37705408
OS 13.74763824 7.37058216
OS 13.73376984 7.36411024
OS 13.72267512 7.35671376
OS 13.71435408 7.35024184
OS 13.70973128 7.3465436
OS 13.70788216 7.34469448
OS 13.69493832 7.32990152
OS 13.68569272 7.314184
OS 13.6792208 7.29846648
OS 13.674598 7.28459808
OS 13.67182432 7.27072968
OS 13.67089976 7.26055952
OS 13.6699752 7.25686128
OS 13.6699752 7.2540876
OS 13.6699752 7.25223848
OS 13.6699752 7.25131392
OS 13.67182432 7.23189816
OS 13.67552256 7.21340696
OS 13.68199448 7.19768944
OS 13.6884664 7.1847456
OS 13.69493832 7.17457544
OS 13.70141024 7.1662544
OS 13.70510848 7.1616316
OS 13.7069576 7.15978248
OS 13.72175056 7.1477632
OS 13.73654352 7.1385176
OS 13.75226104 7.13297024
OS 13.767054 7.12834744
OS 13.77999784 7.12557376
OS 13.79109256 7.1246492
OS 13.7947908 7.12372464
OS 13.80033816 7.12372464
OS 13.813282 7.1246492
OS 13.82622584 7.12649832
OS 13.83824512 7.129272
OS 13.84841528 7.13204568
OS 13.85673632 7.13481936
OS 13.86320824 7.13759304
OS 13.86690648 7.13944216
OS 13.8687556 7.14036672
OS 13.87985032 7.1477632
OS 13.88909592 7.15515968
OS 13.89741696 7.16348072
OS 13.90388888 7.17180176
OS 13.90943624 7.17827368
OS 13.91313448 7.18382104
OS 13.9149836 7.18844384
OS 13.91590816 7.1893684
OS 13.92053096 7.20138768
OS 13.9242292 7.2124824
OS 13.92700288 7.22357712
OS 13.928852 7.23374728
OS 13.92977656 7.24206832
OS 13.93070112 7.24854024
OS 13.93070112 7.25223848
OS 13.93070112 7.2540876
OS 13.928852 7.27350336
OS 13.92515376 7.29107
OS 13.9196064 7.30678752
OS 13.91220992 7.32065592
OS 13.905738 7.33082608
OS 13.90019064 7.33914712
OS 13.8964924 7.34376992
OS 13.89464328 7.34561904
OS 13.88077488 7.35763832
OS 13.86505736 7.36688392
OS 13.8502644 7.37335584
OS 13.83547144 7.37797864
OS 13.8225276 7.38075232
OS 13.81235744 7.38167688
OS 13.8086592 7.38260144
OS 13.80311184 7.38260144
OE
SE
S P 0
OB 14.33288472 10.12006612 I
OS 14.33935664 10.12099068
OS 14.34860224 10.12099068
OS 14.37911272 10.11914156
OS 14.40869864 10.11451876
OS 14.43458632 10.1089714
OS 14.4466056 10.10527316
OS 14.45770032 10.10157492
OS 14.46787048 10.09787668
OS 14.47711608 10.09417844
OS 14.48451256 10.09140476
OS 14.49190904 10.08863108
OS 14.49653184 10.0858574
OS 14.50023008 10.08400828
OS 14.50300376 10.08308372
OS 14.50392832 10.08215916
OS 14.52889144 10.06644164
OS 14.55015632 10.04795044
OS 14.56864752 10.02945924
OS 14.58436504 10.01096804
OS 14.59638432 9.99432596
OS 14.60100712 9.98692948
OS 14.60470536 9.98045756
OS 14.6084036 9.97583476
OS 14.61025272 9.97213652
OS 14.61117728 9.96936284
OS 14.61210184 9.96843828
OS 14.62504568 9.93977692
OS 14.63429128 9.910191
OS 14.6407632 9.88060508
OS 14.645386 9.85379284
OS 14.64723512 9.84177356
OS 14.64815968 9.82975428
OS 14.64908424 9.82050868
OS 14.64908424 9.81126308
OS 14.6500088 9.80479116
OS 14.6500088 9.7992438
OS 14.6500088 9.79554556
OS 14.6500088 9.794621
OS 14.64815968 9.76133684
OS 14.64446144 9.72897724
OS 14.63983864 9.70031588
OS 14.6361404 9.68644748
OS 14.63336672 9.6744282
OS 14.63059304 9.66333348
OS 14.6268948 9.65316332
OS 14.62412112 9.64391772
OS 14.622272 9.63652124
OS 14.61949832 9.63097388
OS 14.61857376 9.62635108
OS 14.61672464 9.6235774
OS 14.61672464 9.62265284
OS 14.60285624 9.59491604
OS 14.58713872 9.56995292
OS 14.57049664 9.54868804
OS 14.5621756 9.540367
OS 14.55477912 9.53204596
OS 14.54738264 9.52464948
OS 14.53998616 9.51817756
OS 14.53351424 9.5126302
OS 14.52796688 9.50893196
OS 14.52426864 9.50523372
OS 14.5205704 9.50246004
OS 14.51872128 9.50153548
OS 14.51779672 9.50061092
OS 14.50485288 9.49321444
OS 14.49190904 9.48674252
OS 14.46417224 9.47657236
OS 14.43643544 9.46917588
OS 14.4096232 9.46455308
OS 14.39667936 9.46270396
OS 14.38558464 9.46085484
OS 14.37541448 9.45993028
OS 14.36709344 9.45993028
OS 14.35969696 9.45900572
OS 14.3495268 9.45900572
OS 14.3310356 9.45993028
OS 14.31346896 9.4617794
OS 14.29682688 9.46362852
OS 14.28110936 9.46732676
OS 14.2663164 9.47194956
OS 14.252448 9.47657236
OS 14.23950416 9.48119516
OS 14.22748488 9.48674252
OS 14.21731472 9.49136532
OS 14.20714456 9.49598812
OS 14.19974808 9.50061092
OS 14.1923516 9.50523372
OS 14.1877288 9.50893196
OS 14.183106 9.51078108
OS 14.18125688 9.5126302
OS 14.18033232 9.51355476
OS 14.16738848 9.52464948
OS 14.15629376 9.5357442
OS 14.1461236 9.54868804
OS 14.13595344 9.56163188
OS 14.11931136 9.58751956
OS 14.10636752 9.61340724
OS 14.10082016 9.62542652
OS 14.09619736 9.63652124
OS 14.09249912 9.6466914
OS 14.08972544 9.65501244
OS 14.08695176 9.66240892
OS 14.08510264 9.66795628
OS 14.08417808 9.67165452
OS 14.08417808 9.67257908
OS 14.1692376 9.69384396
OS 14.17293584 9.679051
OS 14.17755864 9.6651826
OS 14.18218144 9.65223876
OS 14.18680424 9.64021948
OS 14.1923516 9.62912476
OS 14.19789896 9.61987916
OS 14.20437088 9.61063356
OS 14.20991824 9.60231252
OS 14.21454104 9.59491604
OS 14.2200884 9.58936868
OS 14.2247112 9.58382132
OS 14.22840944 9.57919852
OS 14.23210768 9.57642484
OS 14.23488136 9.57365116
OS 14.23580592 9.5727266
OS 14.23673048 9.57180204
OS 14.24597608 9.56440556
OS 14.25614624 9.5588582
OS 14.27648656 9.54868804
OS 14.29590232 9.54129156
OS 14.31531808 9.53666876
OS 14.33196016 9.53297052
OS 14.33843208 9.53204596
OS 14.344904 9.53204596
OS 14.35045136 9.5311214
OS 14.35692328 9.5311214
OS 14.37818816 9.53204596
OS 14.39852848 9.5357442
OS 14.41701968 9.540367
OS 14.43366176 9.54591436
OS 14.4466056 9.55146172
OS 14.45215296 9.5542354
OS 14.45677576 9.55608452
OS 14.460474 9.55793364
OS 14.46324768 9.55978276
OS 14.4650968 9.56070732
OS 14.46602136 9.56070732
OS 14.483588 9.57365116
OS 14.49838096 9.58751956
OS 14.5113248 9.60323708
OS 14.52149496 9.61803004
OS 14.529816 9.63097388
OS 14.53536336 9.6420686
OS 14.53721248 9.6466914
OS 14.5390616 9.64946508
OS 14.53998616 9.6513142
OS 14.53998616 9.65223876
OS 14.54738264 9.67627732
OS 14.55293 9.70031588
OS 14.5575528 9.72435444
OS 14.56032648 9.74654388
OS 14.56125104 9.75671404
OS 14.5621756 9.76595964
OS 14.5621756 9.77428068
OS 14.56310016 9.7807526
OS 14.56310016 9.78629996
OS 14.56310016 9.79092276
OS 14.56310016 9.79369644
OS 14.56310016 9.794621
OS 14.5621756 9.81865956
OS 14.56032648 9.840849
OS 14.55662824 9.86118932
OS 14.55293 9.87968052
OS 14.55015632 9.89539804
OS 14.5483072 9.90186996
OS 14.54645808 9.90741732
OS 14.54553352 9.91204012
OS 14.54460896 9.9148138
OS 14.5436844 9.91666292
OS 14.5436844 9.91758748
OS 14.5344388 9.93885236
OS 14.52426864 9.95826812
OS 14.51317392 9.97398564
OS 14.50115464 9.98785404
OS 14.49098448 9.99894876
OS 14.48266344 10.00634524
OS 14.47619152 10.01096804
OS 14.47526696 10.01281716
OS 14.4743424 10.01281716
OS 14.45492664 10.02483644
OS 14.43366176 10.03408204
OS 14.41332144 10.04055396
OS 14.39390568 10.0442522
OS 14.37633904 10.04702588
OS 14.36894256 10.04795044
OS 14.36247064 10.04795044
OS 14.35784784 10.048875
OS 14.35045136 10.048875
OS 14.32733736 10.04795044
OS 14.30607248 10.0442522
OS 14.28850584 10.03870484
OS 14.27278832 10.03315748
OS 14.26076904 10.02668556
OS 14.25152344 10.02206276
OS 14.24597608 10.01836452
OS 14.24412696 10.0165154
OS 14.229334 10.002647
OS 14.2154656 9.98692948
OS 14.20437088 9.9702874
OS 14.19512528 9.95364532
OS 14.1877288 9.93885236
OS 14.18495512 9.93145588
OS 14.183106 9.92590852
OS 14.18125688 9.92128572
OS 14.17940776 9.91758748
OS 14.1784832 9.91573836
OS 14.1784832 9.9148138
OS 14.0952728 9.93422956
OS 14.10082016 9.95087164
OS 14.10636752 9.9656646
OS 14.113764 9.979533
OS 14.12023592 9.9934014
OS 14.1276324 10.00542068
OS 14.13595344 10.0165154
OS 14.14334992 10.02761012
OS 14.1507464 10.03685572
OS 14.15814288 10.0442522
OS 14.1646148 10.05164868
OS 14.17108672 10.0581206
OS 14.17570952 10.0627434
OS 14.18033232 10.0673662
OS 14.18403056 10.07013988
OS 14.18587968 10.07106444
OS 14.18680424 10.071989
OS 14.19974808 10.08031004
OS 14.21269192 10.08863108
OS 14.22563576 10.095103
OS 14.23950416 10.10065036
OS 14.26724096 10.1089714
OS 14.29220408 10.11451876
OS 14.30422336 10.11729244
OS 14.31439352 10.118217
OS 14.32456368 10.11914156
OS 14.33288472 10.12006612
OE
OB 13.61819984 10.02668556 I
OS 13.61819984 10.10157492
OS 13.93624848 10.10157492
OS 13.998194 9.77243156
OS 13.9242292 9.7622614
OS 13.91775728 9.77243156
OS 13.90943624 9.7807526
OS 13.90203976 9.78907364
OS 13.89464328 9.79554556
OS 13.8872468 9.80016836
OS 13.88169944 9.80479116
OS 13.8780012 9.80664028
OS 13.87707664 9.80756484
OS 13.86505736 9.8131122
OS 13.85303808 9.817735
OS 13.84194336 9.82050868
OS 13.83084864 9.82328236
OS 13.82160304 9.82420692
OS 13.81420656 9.82513148
OS 13.79663992 9.82513148
OS 13.7855452 9.82328236
OS 13.76612944 9.81865956
OS 13.74948736 9.81218764
OS 13.7346944 9.80571572
OS 13.72359968 9.79831924
OS 13.71527864 9.79184732
OS 13.71065584 9.78722452
OS 13.70880672 9.78629996
OS 13.70880672 9.7853754
OS 13.69586288 9.76965788
OS 13.68661728 9.7530158
OS 13.68014536 9.73544916
OS 13.67552256 9.71788252
OS 13.67274888 9.70308956
OS 13.67182432 9.69661764
OS 13.67182432 9.69107028
OS 13.67089976 9.68644748
OS 13.67089976 9.68274924
OS 13.67089976 9.68090012
OS 13.67089976 9.67997556
OS 13.67089976 9.66703172
OS 13.67274888 9.65501244
OS 13.67737168 9.63189844
OS 13.6838436 9.61248268
OS 13.69031552 9.59676516
OS 13.697712 9.58382132
OS 13.70418392 9.57365116
OS 13.7069576 9.57087748
OS 13.70880672 9.5681038
OS 13.70973128 9.56717924
OS 13.71065584 9.56625468
OS 13.71805232 9.5588582
OS 13.7254488 9.55238628
OS 13.74209088 9.54129156
OS 13.7578084 9.53389508
OS 13.77352592 9.52927228
OS 13.78646976 9.52557404
OS 13.79756448 9.52464948
OS 13.80126272 9.52372492
OS 13.80681008 9.52372492
OS 13.82437672 9.52464948
OS 13.84009424 9.52834772
OS 13.85396264 9.53297052
OS 13.86505736 9.53851788
OS 13.87522752 9.54406524
OS 13.882624 9.54868804
OS 13.88632224 9.55238628
OS 13.88817136 9.55331084
OS 13.89926608 9.56625468
OS 13.90851168 9.58012308
OS 13.91590816 9.5958406
OS 13.92145552 9.609709
OS 13.92515376 9.6235774
OS 13.92792744 9.63374756
OS 13.928852 9.63837036
OS 13.92977656 9.64114404
OS 13.92977656 9.64299316
OS 13.92977656 9.64391772
OS 14.0120624 9.6374458
OS 14.01021328 9.62265284
OS 14.0074396 9.60878444
OS 13.99911856 9.58289676
OS 13.9889484 9.56070732
OS 13.98340104 9.55053716
OS 13.97785368 9.54221612
OS 13.97323088 9.53389508
OS 13.96768352 9.5264986
OS 13.96306072 9.52095124
OS 13.95843792 9.51632844
OS 13.95473968 9.5126302
OS 13.95289056 9.50893196
OS 13.95104144 9.5080074
OS 13.95011688 9.50708284
OS 13.93902216 9.4987618
OS 13.92792744 9.49136532
OS 13.91590816 9.4848934
OS 13.90388888 9.47934604
OS 13.88077488 9.471025
OS 13.85766088 9.46547764
OS 13.84749072 9.46270396
OS 13.83732056 9.4617794
OS 13.82899952 9.46085484
OS 13.82160304 9.45993028
OS 13.81513112 9.45900572
OS 13.80681008 9.45900572
OS 13.78739432 9.45993028
OS 13.76890312 9.46270396
OS 13.75133648 9.4664022
OS 13.73561896 9.471025
OS 13.720826 9.47749692
OS 13.7069576 9.48396884
OS 13.69401376 9.49044076
OS 13.68291904 9.49783724
OS 13.67274888 9.50523372
OS 13.66350328 9.51170564
OS 13.6561068 9.51910212
OS 13.64963488 9.52464948
OS 13.64501208 9.52927228
OS 13.64131384 9.53297052
OS 13.63946472 9.5357442
OS 13.63854016 9.53666876
OS 13.62929456 9.54868804
OS 13.62189808 9.56163188
OS 13.6145016 9.57365116
OS 13.60895424 9.586595
OS 13.59970864 9.61155812
OS 13.59416128 9.63559668
OS 13.59231216 9.64576684
OS 13.59046304 9.655937
OS 13.58953848 9.66425804
OS 13.58861392 9.67165452
OS 13.58768936 9.67812644
OS 13.58768936 9.68274924
OS 13.58768936 9.68552292
OS 13.58768936 9.68644748
OS 13.58861392 9.70308956
OS 13.59046304 9.71880708
OS 13.59323672 9.7345246
OS 13.59693496 9.748393
OS 13.60155776 9.76133684
OS 13.60618056 9.77428068
OS 13.61172792 9.7853754
OS 13.61635072 9.79554556
OS 13.62189808 9.80479116
OS 13.62744544 9.8131122
OS 13.63206824 9.81958412
OS 13.63669104 9.82605604
OS 13.64038928 9.83067884
OS 13.64316296 9.83345252
OS 13.64501208 9.83530164
OS 13.64593664 9.8362262
OS 13.65703136 9.84639636
OS 13.66812608 9.85564196
OS 13.68014536 9.86303844
OS 13.69216464 9.86951036
OS 13.70418392 9.87598228
OS 13.7162032 9.88060508
OS 13.73839264 9.887077
OS 13.7485628 9.88985068
OS 13.7578084 9.8916998
OS 13.76612944 9.89262436
OS 13.77352592 9.89354892
OS 13.77907328 9.89447348
OS 13.7994136 9.89447348
OS 13.81050832 9.89262436
OS 13.83269776 9.88800156
OS 13.85303808 9.88152964
OS 13.87152928 9.87413316
OS 13.88632224 9.86673668
OS 13.89279416 9.86303844
OS 13.89834152 9.86026476
OS 13.90296432 9.85749108
OS 13.905738 9.85564196
OS 13.90758712 9.8547174
OS 13.90851168 9.85379284
OS 13.87430296 10.02668556
OS 13.61819984 10.02668556
OE
SE
S P 0
OB 14.59533784 24.16461512 I
OS 14.60180976 24.16553968
OS 14.61105536 24.16553968
OS 14.64156584 24.16369056
OS 14.67115176 24.15906776
OS 14.69703944 24.1535204
OS 14.70905872 24.14982216
OS 14.72015344 24.14612392
OS 14.7303236 24.14242568
OS 14.7395692 24.13872744
OS 14.74696568 24.13595376
OS 14.75436216 24.13318008
OS 14.75898496 24.1304064
OS 14.7626832 24.12855728
OS 14.76545688 24.12763272
OS 14.76638144 24.12670816
OS 14.79134456 24.11099064
OS 14.81260944 24.09249944
OS 14.83110064 24.07400824
OS 14.84681816 24.05551704
OS 14.85883744 24.03887496
OS 14.86346024 24.03147848
OS 14.86715848 24.02500656
OS 14.87085672 24.02038376
OS 14.87270584 24.01668552
OS 14.8736304 24.01391184
OS 14.87455496 24.01298728
OS 14.8874988 23.98432592
OS 14.8967444 23.95474
OS 14.90321632 23.92515408
OS 14.90783912 23.89834184
OS 14.90968824 23.88632256
OS 14.9106128 23.87430328
OS 14.91153736 23.86505768
OS 14.91153736 23.85581208
OS 14.91246192 23.84934016
OS 14.91246192 23.8437928
OS 14.91246192 23.84009456
OS 14.91246192 23.83917
OS 14.9106128 23.80588584
OS 14.90691456 23.77352624
OS 14.90229176 23.74486488
OS 14.89859352 23.73099648
OS 14.89581984 23.7189772
OS 14.89304616 23.70788248
OS 14.88934792 23.69771232
OS 14.88657424 23.68846672
OS 14.88472512 23.68107024
OS 14.88195144 23.67552288
OS 14.88102688 23.67090008
OS 14.87917776 23.6681264
OS 14.87917776 23.66720184
OS 14.86530936 23.63946504
OS 14.84959184 23.61450192
OS 14.83294976 23.59323704
OS 14.82462872 23.584916
OS 14.81723224 23.57659496
OS 14.80983576 23.56919848
OS 14.80243928 23.56272656
OS 14.79596736 23.5571792
OS 14.79042 23.55348096
OS 14.78672176 23.54978272
OS 14.78302352 23.54700904
OS 14.7811744 23.54608448
OS 14.78024984 23.54515992
OS 14.767306 23.53776344
OS 14.75436216 23.53129152
OS 14.72662536 23.52112136
OS 14.69888856 23.51372488
OS 14.67207632 23.50910208
OS 14.65913248 23.50725296
OS 14.64803776 23.50540384
OS 14.6378676 23.50447928
OS 14.62954656 23.50447928
OS 14.62215008 23.50355472
OS 14.61197992 23.50355472
OS 14.59348872 23.50447928
OS 14.57592208 23.5063284
OS 14.55928 23.50817752
OS 14.54356248 23.51187576
OS 14.52876952 23.51649856
OS 14.51490112 23.52112136
OS 14.50195728 23.52574416
OS 14.489938 23.53129152
OS 14.47976784 23.53591432
OS 14.46959768 23.54053712
OS 14.4622012 23.54515992
OS 14.45480472 23.54978272
OS 14.45018192 23.55348096
OS 14.44555912 23.55533008
OS 14.44371 23.5571792
OS 14.44278544 23.55810376
OS 14.4298416 23.56919848
OS 14.41874688 23.5802932
OS 14.40857672 23.59323704
OS 14.39840656 23.60618088
OS 14.38176448 23.63206856
OS 14.36882064 23.65795624
OS 14.36327328 23.66997552
OS 14.35865048 23.68107024
OS 14.35495224 23.6912404
OS 14.35217856 23.69956144
OS 14.34940488 23.70695792
OS 14.34755576 23.71250528
OS 14.3466312 23.71620352
OS 14.3466312 23.71712808
OS 14.43169072 23.73839296
OS 14.43538896 23.7236
OS 14.44001176 23.7097316
OS 14.44463456 23.69678776
OS 14.44925736 23.68476848
OS 14.45480472 23.67367376
OS 14.46035208 23.66442816
OS 14.466824 23.65518256
OS 14.47237136 23.64686152
OS 14.47699416 23.63946504
OS 14.48254152 23.63391768
OS 14.48716432 23.62837032
OS 14.49086256 23.62374752
OS 14.4945608 23.62097384
OS 14.49733448 23.61820016
OS 14.49825904 23.6172756
OS 14.4991836 23.61635104
OS 14.5084292 23.60895456
OS 14.51859936 23.6034072
OS 14.53893968 23.59323704
OS 14.55835544 23.58584056
OS 14.5777712 23.58121776
OS 14.59441328 23.57751952
OS 14.6008852 23.57659496
OS 14.60735712 23.57659496
OS 14.61290448 23.5756704
OS 14.6193764 23.5756704
OS 14.64064128 23.57659496
OS 14.6609816 23.5802932
OS 14.6794728 23.584916
OS 14.69611488 23.59046336
OS 14.70905872 23.59601072
OS 14.71460608 23.5987844
OS 14.71922888 23.60063352
OS 14.72292712 23.60248264
OS 14.7257008 23.60433176
OS 14.72754992 23.60525632
OS 14.72847448 23.60525632
OS 14.74604112 23.61820016
OS 14.76083408 23.63206856
OS 14.77377792 23.64778608
OS 14.78394808 23.66257904
OS 14.79226912 23.67552288
OS 14.79781648 23.6866176
OS 14.7996656 23.6912404
OS 14.80151472 23.69401408
OS 14.80243928 23.6958632
OS 14.80243928 23.69678776
OS 14.80983576 23.72082632
OS 14.81538312 23.74486488
OS 14.82000592 23.76890344
OS 14.8227796 23.79109288
OS 14.82370416 23.80126304
OS 14.82462872 23.81050864
OS 14.82462872 23.81882968
OS 14.82555328 23.8253016
OS 14.82555328 23.83084896
OS 14.82555328 23.83547176
OS 14.82555328 23.83824544
OS 14.82555328 23.83917
OS 14.82462872 23.86320856
OS 14.8227796 23.885398
OS 14.81908136 23.90573832
OS 14.81538312 23.92422952
OS 14.81260944 23.93994704
OS 14.81076032 23.94641896
OS 14.8089112 23.95196632
OS 14.80798664 23.95658912
OS 14.80706208 23.9593628
OS 14.80613752 23.96121192
OS 14.80613752 23.96213648
OS 14.79689192 23.98340136
OS 14.78672176 24.00281712
OS 14.77562704 24.01853464
OS 14.76360776 24.03240304
OS 14.7534376 24.04349776
OS 14.74511656 24.05089424
OS 14.73864464 24.05551704
OS 14.73772008 24.05736616
OS 14.73679552 24.05736616
OS 14.71737976 24.06938544
OS 14.69611488 24.07863104
OS 14.67577456 24.08510296
OS 14.6563588 24.0888012
OS 14.63879216 24.09157488
OS 14.63139568 24.09249944
OS 14.62492376 24.09249944
OS 14.62030096 24.093424
OS 14.61290448 24.093424
OS 14.58979048 24.09249944
OS 14.5685256 24.0888012
OS 14.55095896 24.08325384
OS 14.53524144 24.07770648
OS 14.52322216 24.07123456
OS 14.51397656 24.06661176
OS 14.5084292 24.06291352
OS 14.50658008 24.0610644
OS 14.49178712 24.047196
OS 14.47791872 24.03147848
OS 14.466824 24.0148364
OS 14.4575784 23.99819432
OS 14.45018192 23.98340136
OS 14.44740824 23.97600488
OS 14.44555912 23.97045752
OS 14.44371 23.96583472
OS 14.44186088 23.96213648
OS 14.44093632 23.96028736
OS 14.44093632 23.9593628
OS 14.35772592 23.97877856
OS 14.36327328 23.99542064
OS 14.36882064 24.0102136
OS 14.37621712 24.024082
OS 14.38268904 24.0379504
OS 14.39008552 24.04996968
OS 14.39840656 24.0610644
OS 14.40580304 24.07215912
OS 14.41319952 24.08140472
OS 14.420596 24.0888012
OS 14.42706792 24.09619768
OS 14.43353984 24.1026696
OS 14.43816264 24.1072924
OS 14.44278544 24.1119152
OS 14.44648368 24.11468888
OS 14.4483328 24.11561344
OS 14.44925736 24.116538
OS 14.4622012 24.12485904
OS 14.47514504 24.13318008
OS 14.48808888 24.139652
OS 14.50195728 24.14519936
OS 14.52969408 24.1535204
OS 14.5546572 24.15906776
OS 14.56667648 24.16184144
OS 14.57684664 24.162766
OS 14.5870168 24.16369056
OS 14.59533784 24.16461512
OE
OB 13.9444476 23.74024208 I
OS 13.9444476 24.15444496
OS 14.00824224 24.15444496
OS 14.30132776 23.74024208
OS 14.30132776 23.6681264
OS 14.0230352 23.6681264
OS 14.0230352 23.51464944
OS 13.9444476 23.51464944
OS 13.9444476 23.6681264
OS 13.85753896 23.6681264
OS 13.85753896 23.74024208
OS 13.9444476 23.74024208
OE
OB 14.0230352 24.02685568 H
OS 14.0230352 23.74024208
OS 14.22458928 23.74024208
OS 14.0230352 24.02685568
OE
SE
S P 0
OB 14.1498066 40.99926268 I
OS 14.1498066 41.64183188
OS 14.2006574 41.64183188
OS 14.209903 41.62611436
OS 14.22007316 41.6113214
OS 14.23209244 41.59652844
OS 14.24318716 41.5835846
OS 14.25428188 41.57248988
OS 14.26260292 41.56324428
OS 14.26630116 41.5604706
OS 14.26907484 41.55769692
OS 14.2699994 41.55677236
OS 14.27092396 41.5558478
OS 14.29033972 41.54013028
OS 14.30975548 41.52533732
OS 14.32824668 41.51239348
OS 14.34673788 41.50222332
OS 14.3624554 41.49297772
OS 14.36892732 41.48927948
OS 14.37447468 41.4865058
OS 14.37909748 41.48373212
OS 14.38279572 41.48280756
OS 14.38464484 41.48095844
OS 14.3855694 41.48095844
OS 14.3855694 41.40514452
OS 14.371701 41.41069188
OS 14.3578326 41.4171638
OS 14.3439642 41.42363572
OS 14.33102036 41.43010764
OS 14.31992564 41.435655
OS 14.31068004 41.4402778
OS 14.30513268 41.44397604
OS 14.30420812 41.4449006
OS 14.30328356 41.4449006
OS 14.28664148 41.45507076
OS 14.27184852 41.46524092
OS 14.25890468 41.47448652
OS 14.24873452 41.48280756
OS 14.23948892 41.48927948
OS 14.23394156 41.49482684
OS 14.22931876 41.49852508
OS 14.2283942 41.49944964
OS 14.2283942 40.99926268
OS 14.1498066 40.99926268
OE
OB 14.73320396 41.63813364 I
OS 14.74707236 41.6390582
OS 15.0096474 41.6390582
OS 15.0096474 40.99926268
OS 14.92458788 40.99926268
OS 14.92458788 41.25906404
OS 14.76094076 41.25906404
OS 14.7369022 41.2599886
OS 14.7137882 41.26183772
OS 14.69344788 41.2646114
OS 14.67495668 41.26830964
OS 14.65739004 41.27200788
OS 14.64259708 41.27663068
OS 14.62872868 41.28217804
OS 14.6167094 41.2877254
OS 14.60653924 41.2923482
OS 14.59729364 41.29789556
OS 14.58989716 41.30251836
OS 14.5843498 41.30714116
OS 14.579727 41.30991484
OS 14.57695332 41.31268852
OS 14.5751042 41.31453764
OS 14.57417964 41.3154622
OS 14.56493404 41.32655692
OS 14.556613 41.33765164
OS 14.55014108 41.34874636
OS 14.54366916 41.36076564
OS 14.5381218 41.37278492
OS 14.53442356 41.38387964
OS 14.52795164 41.40514452
OS 14.52610252 41.41531468
OS 14.5242534 41.42456028
OS 14.52332884 41.43288132
OS 14.52240428 41.43935324
OS 14.52147972 41.44582516
OS 14.52147972 41.4495234
OS 14.52147972 41.45229708
OS 14.52147972 41.45322164
OS 14.52240428 41.47078828
OS 14.5242534 41.48743036
OS 14.52795164 41.50222332
OS 14.53072532 41.51516716
OS 14.53442356 41.52626188
OS 14.5381218 41.53458292
OS 14.53997092 41.53920572
OS 14.54089548 41.54105484
OS 14.54829196 41.55492324
OS 14.55753756 41.56694252
OS 14.5658586 41.57803724
OS 14.57417964 41.58635828
OS 14.58157612 41.5928302
OS 14.58712348 41.59837756
OS 14.59082172 41.60115124
OS 14.59267084 41.6020758
OS 14.60469012 41.60947228
OS 14.61855852 41.6159442
OS 14.63150236 41.62149156
OS 14.64352164 41.62611436
OS 14.65461636 41.62888804
OS 14.6629374 41.63073716
OS 14.66940932 41.63258628
OS 14.67125844 41.63258628
OS 14.68512684 41.6344354
OS 14.70084436 41.63628452
OS 14.71748644 41.63720908
OS 14.73320396 41.63813364
OE
OB 13.72081076 41.64090732 I
OS 13.73098092 41.64183188
OS 13.73930196 41.64183188
OS 13.76426508 41.63998276
OS 13.78737908 41.63628452
OS 13.80679484 41.6298126
OS 13.82343692 41.62334068
OS 13.83730532 41.6159442
OS 13.84285268 41.61317052
OS 13.84747548 41.60947228
OS 13.85117372 41.60762316
OS 13.8539474 41.60577404
OS 13.85487196 41.60392492
OS 13.85579652 41.60392492
OS 13.8724386 41.58913196
OS 13.886307 41.57156532
OS 13.89832628 41.55399868
OS 13.90757188 41.5373566
OS 13.91496836 41.52163908
OS 13.9186666 41.51516716
OS 13.92051572 41.50869524
OS 13.92236484 41.50407244
OS 13.92421396 41.5003742
OS 13.92513852 41.49852508
OS 13.92513852 41.49760052
OS 13.92883676 41.48373212
OS 13.932535 41.46986372
OS 13.93808236 41.43935324
OS 13.94270516 41.40884276
OS 13.94547884 41.3801814
OS 13.9464034 41.366313
OS 13.94732796 41.35429372
OS 13.94732796 41.343199
OS 13.94825252 41.33302884
OS 13.94825252 41.32563236
OS 13.94825252 41.31916044
OS 13.94825252 41.3154622
OS 13.94825252 41.31453764
OS 13.94732796 41.28217804
OS 13.94547884 41.25166756
OS 13.94270516 41.22393076
OS 13.93808236 41.19804308
OS 13.93345956 41.17400452
OS 13.9279122 41.15273964
OS 13.92236484 41.13332388
OS 13.91681748 41.1166818
OS 13.91127012 41.10188884
OS 13.9047982 41.088945
OS 13.9001754 41.07785028
OS 13.8955526 41.06952924
OS 13.8909298 41.06213276
OS 13.88815612 41.05750996
OS 13.886307 41.05473628
OS 13.88538244 41.05381172
OS 13.87521228 41.042717
OS 13.86411756 41.03254684
OS 13.85209828 41.02330124
OS 13.840079 41.01590476
OS 13.82805972 41.00943284
OS 13.81604044 41.00388548
OS 13.80402116 41.00018724
OS 13.79292644 40.996489
OS 13.78183172 40.99371532
OS 13.77166156 40.9918662
OS 13.76241596 40.99001708
OS 13.75501948 40.98909252
OS 13.74854756 40.98816796
OS 13.73930196 40.98816796
OS 13.71433884 40.99001708
OS 13.69122484 40.99371532
OS 13.67180908 41.00018724
OS 13.655167 41.00665916
OS 13.6412986 41.01313108
OS 13.6366758 41.01682932
OS 13.632053 41.019603
OS 13.62835476 41.02145212
OS 13.62558108 41.02330124
OS 13.62465652 41.02515036
OS 13.62373196 41.02515036
OS 13.60708988 41.04086788
OS 13.59322148 41.05750996
OS 13.5812022 41.07600116
OS 13.5719566 41.09264324
OS 13.56456012 41.10836076
OS 13.56086188 41.11483268
OS 13.55901276 41.1213046
OS 13.55716364 41.1259274
OS 13.55531452 41.12962564
OS 13.55438996 41.13147476
OS 13.55438996 41.13239932
OS 13.54976716 41.14626772
OS 13.54606892 41.16013612
OS 13.54052156 41.18972204
OS 13.53589876 41.22023252
OS 13.53312508 41.24981844
OS 13.53220052 41.26276228
OS 13.53127596 41.27478156
OS 13.53127596 41.28587628
OS 13.5303514 41.29604644
OS 13.5303514 41.30344292
OS 13.5303514 41.30991484
OS 13.5303514 41.31361308
OS 13.5303514 41.31453764
OS 13.5303514 41.33210428
OS 13.53127596 41.34874636
OS 13.53127596 41.36353932
OS 13.53220052 41.37833228
OS 13.53404964 41.39127612
OS 13.5349742 41.40421996
OS 13.53589876 41.41531468
OS 13.53774788 41.42548484
OS 13.53867244 41.43473044
OS 13.54052156 41.44305148
OS 13.54144612 41.4495234
OS 13.54237068 41.45507076
OS 13.54329524 41.45969356
OS 13.5442198 41.46246724
OS 13.54514436 41.46431636
OS 13.54514436 41.46524092
OS 13.55069172 41.48558124
OS 13.55716364 41.50407244
OS 13.56456012 41.51978996
OS 13.57010748 41.53365836
OS 13.5765794 41.54567764
OS 13.58027764 41.55399868
OS 13.58397588 41.55862148
OS 13.58490044 41.5604706
OS 13.5950706 41.574339
OS 13.60524076 41.58635828
OS 13.61633548 41.59652844
OS 13.62650564 41.60577404
OS 13.63575124 41.61224596
OS 13.64314772 41.61686876
OS 13.64777052 41.61964244
OS 13.64869508 41.620567
OS 13.64961964 41.620567
OS 13.6644126 41.62796348
OS 13.68013012 41.63258628
OS 13.69492308 41.63628452
OS 13.70879148 41.6390582
OS 13.72081076 41.64090732
OE
OB 13.74022652 41.57711268 H
OS 13.73005636 41.57618812
OS 13.7198862 41.57526356
OS 13.7106406 41.57248988
OS 13.70231956 41.56879164
OS 13.68660204 41.5604706
OS 13.67273364 41.551225
OS 13.66256348 41.54105484
OS 13.65424244 41.5327338
OS 13.65146876 41.52903556
OS 13.64961964 41.52626188
OS 13.64777052 41.52533732
OS 13.64777052 41.52441276
OS 13.6412986 41.51331804
OS 13.63575124 41.5003742
OS 13.63020388 41.48558124
OS 13.62650564 41.46986372
OS 13.6228074 41.45322164
OS 13.62003372 41.435655
OS 13.61541092 41.40052172
OS 13.6135618 41.38295508
OS 13.61263724 41.36723756
OS 13.61171268 41.3524446
OS 13.61171268 41.34042532
OS 13.61078812 41.3293306
OS 13.61078812 41.32100956
OS 13.61078812 41.31638676
OS 13.61078812 41.3154622
OS 13.61078812 41.31453764
OS 13.61078812 41.28587628
OS 13.61263724 41.2599886
OS 13.61448636 41.2368746
OS 13.61633548 41.21468516
OS 13.61910916 41.19619396
OS 13.6228074 41.17862732
OS 13.62650564 41.16383436
OS 13.62927932 41.14996596
OS 13.63297756 41.13887124
OS 13.6366758 41.12962564
OS 13.63944948 41.1213046
OS 13.64314772 41.11483268
OS 13.64499684 41.11020988
OS 13.64684596 41.1074362
OS 13.64869508 41.10558708
OS 13.64869508 41.10466252
OS 13.65609156 41.09541692
OS 13.66348804 41.08802044
OS 13.67088452 41.08062396
OS 13.678281 41.0750766
OS 13.69399852 41.065831
OS 13.70786692 41.05935908
OS 13.72081076 41.05566084
OS 13.73005636 41.05381172
OS 13.7337546 41.05288716
OS 13.73930196 41.05288716
OS 13.74947212 41.05381172
OS 13.75871772 41.05473628
OS 13.77628436 41.0612082
OS 13.79200188 41.06952924
OS 13.80587028 41.07877484
OS 13.81604044 41.08802044
OS 13.82436148 41.09634148
OS 13.82898428 41.1028134
OS 13.8308334 41.10373796
OS 13.8308334 41.10466252
OS 13.83730532 41.11575724
OS 13.84285268 41.12870108
OS 13.84840004 41.14349404
OS 13.85209828 41.15921156
OS 13.85579652 41.17585364
OS 13.8585702 41.19342028
OS 13.863193 41.22947812
OS 13.86504212 41.2461202
OS 13.86596668 41.26183772
OS 13.86689124 41.27663068
OS 13.86689124 41.28864996
OS 13.8678158 41.29974468
OS 13.8678158 41.30806572
OS 13.8678158 41.31268852
OS 13.8678158 41.31453764
OS 13.86689124 41.343199
OS 13.86596668 41.36908668
OS 13.86411756 41.39312524
OS 13.86134388 41.41531468
OS 13.8585702 41.43473044
OS 13.85487196 41.45229708
OS 13.85117372 41.4680146
OS 13.84747548 41.481883
OS 13.84377724 41.49390228
OS 13.84100356 41.50407244
OS 13.83730532 41.51239348
OS 13.83453164 41.51978996
OS 13.83175796 41.52441276
OS 13.82990884 41.528111
OS 13.82805972 41.52996012
OS 13.82805972 41.53088468
OS 13.8215878 41.53920572
OS 13.81511588 41.5466022
OS 13.8077194 41.55214956
OS 13.80032292 41.55769692
OS 13.78552996 41.56601796
OS 13.77166156 41.57156532
OS 13.75964228 41.574339
OS 13.74947212 41.57618812
OS 13.74577388 41.57711268
OS 13.74022652 41.57711268
OE
OB 14.741525 41.56324428 H
OS 14.72488292 41.56231972
OS 14.71101452 41.56139516
OS 14.6999198 41.5604706
OS 14.69252332 41.55862148
OS 14.68697596 41.55769692
OS 14.68327772 41.55677236
OS 14.68235316 41.55677236
OS 14.67033388 41.55214956
OS 14.66016372 41.5466022
OS 14.65091812 41.54105484
OS 14.64259708 41.53458292
OS 14.63704972 41.528111
OS 14.63242692 41.5234882
OS 14.62965324 41.51978996
OS 14.62872868 41.5188654
OS 14.62225676 41.50777068
OS 14.6167094 41.49667596
OS 14.61301116 41.48465668
OS 14.61116204 41.47448652
OS 14.60931292 41.46524092
OS 14.60838836 41.45691988
OS 14.60838836 41.45229708
OS 14.60838836 41.45137252
OS 14.60838836 41.45044796
OS 14.61023748 41.4310322
OS 14.61393572 41.41439012
OS 14.61948308 41.39959716
OS 14.625955 41.38757788
OS 14.63242692 41.37833228
OS 14.63797428 41.3709358
OS 14.64167252 41.36723756
OS 14.64352164 41.36538844
OS 14.64999356 41.35984108
OS 14.6583146 41.35521828
OS 14.67588124 41.3478218
OS 14.695297 41.34227444
OS 14.71471276 41.3385762
OS 14.7322794 41.33672708
OS 14.73967588 41.33580252
OS 14.7461478 41.33580252
OS 14.75261972 41.33487796
OS 14.92458788 41.33487796
OS 14.92458788 41.56324428
OS 14.741525 41.56324428
OE
SE
S P 0
OB 14.72794362 15.94423532 I
OS 14.72794362 16.31405932
OS 14.81300314 16.31405932
OS 14.81300314 15.94423532
OS 14.81300314 15.92297044
OS 14.81485226 15.90263012
OS 14.81670138 15.88506348
OS 14.81947506 15.8684214
OS 14.82224874 15.85362844
OS 14.82594698 15.83976004
OS 14.82872066 15.82774076
OS 14.8324189 15.8175706
OS 14.83611714 15.80924956
OS 14.83981538 15.80092852
OS 14.84351362 15.79538116
OS 14.8462873 15.7898338
OS 14.84906098 15.78613556
OS 14.8509101 15.78336188
OS 14.85183466 15.78243732
OS 14.85275922 15.78151276
OS 14.86108026 15.77411628
OS 14.87032586 15.76764436
OS 14.89066618 15.7574742
OS 14.91193106 15.75007772
OS 14.9341205 15.74545492
OS 14.95446082 15.74175668
OS 14.96278186 15.74083212
OS 14.9711029 15.74083212
OS 14.97665026 15.73990756
OS 14.98589586 15.73990756
OS 15.00531162 15.74083212
OS 15.02287826 15.7436058
OS 15.03952034 15.74637948
OS 15.05246418 15.75100228
OS 15.0635589 15.75470052
OS 15.07187994 15.7574742
OS 15.07650274 15.76024788
OS 15.07835186 15.76117244
OS 15.0912957 15.76949348
OS 15.10239042 15.77966364
OS 15.11163602 15.7898338
OS 15.11810794 15.7990794
OS 15.1236553 15.808325
OS 15.1282781 15.81479692
OS 15.13012722 15.81941972
OS 15.13105178 15.82126884
OS 15.13382546 15.82958988
OS 15.13567458 15.83791092
OS 15.13937282 15.85732668
OS 15.1421465 15.877667
OS 15.14399562 15.89800732
OS 15.14492018 15.91557396
OS 15.14492018 15.923895
OS 15.14584474 15.93036692
OS 15.14584474 15.93591428
OS 15.14584474 15.94053708
OS 15.14584474 15.94331076
OS 15.14584474 15.94423532
OS 15.14584474 16.31405932
OS 15.23090426 16.31405932
OS 15.23090426 15.94423532
OS 15.23090426 15.92574412
OS 15.2299797 15.90817748
OS 15.22905514 15.8915354
OS 15.22720602 15.87581788
OS 15.2253569 15.86194948
OS 15.22350778 15.84900564
OS 15.2207341 15.83698636
OS 15.21888498 15.82589164
OS 15.21703586 15.81572148
OS 15.21426218 15.80740044
OS 15.21241306 15.80000396
OS 15.21056394 15.7944566
OS 15.20871482 15.7898338
OS 15.20779026 15.78613556
OS 15.2068657 15.78428644
OS 15.2068657 15.78336188
OS 15.19669554 15.76302156
OS 15.1837517 15.74453036
OS 15.17080786 15.7297374
OS 15.15693946 15.71679356
OS 15.14492018 15.7066234
OS 15.13475002 15.69922692
OS 15.13105178 15.6973778
OS 15.1282781 15.69552868
OS 15.12642898 15.69367956
OS 15.12550442 15.69367956
OS 15.10239042 15.6835094
OS 15.07835186 15.67611292
OS 15.05338874 15.67056556
OS 15.03027474 15.66686732
OS 15.02010458 15.66594276
OS 15.00993442 15.6650182
OS 15.00068882 15.66409364
OS 14.99329234 15.66409364
OS 14.98682042 15.66316908
OS 14.97849938 15.66316908
OS 14.94521522 15.6650182
OS 14.93042226 15.66686732
OS 14.91655386 15.66871644
OS 14.90268546 15.67149012
OS 14.89066618 15.6742638
OS 14.87957146 15.67703748
OS 14.8694013 15.68073572
OS 14.8601557 15.68443396
OS 14.85275922 15.68720764
OS 14.84536274 15.68998132
OS 14.83981538 15.692755
OS 14.83519258 15.69552868
OS 14.8324189 15.69645324
OS 14.83056978 15.69830236
OS 14.82964522 15.69830236
OS 14.8093049 15.71217076
OS 14.79266282 15.72788828
OS 14.77971898 15.74268124
OS 14.76862426 15.7574742
OS 14.76030322 15.77041804
OS 14.75475586 15.7805882
OS 14.75290674 15.78428644
OS 14.75105762 15.78706012
OS 14.75013306 15.78890924
OS 14.75013306 15.7898338
OS 14.74643482 15.80092852
OS 14.74273658 15.8129478
OS 14.73718922 15.83791092
OS 14.73349098 15.8637986
OS 14.7307173 15.88876172
OS 14.72979274 15.89985644
OS 14.72886818 15.91095116
OS 14.72886818 15.92019676
OS 14.72794362 15.9285178
OS 14.72794362 15.93498972
OS 14.72794362 15.93961252
OS 14.72794362 15.94331076
OS 14.72794362 15.94423532
OE
OB 14.39880026 16.31590844 I
OS 14.40897042 16.316833
OS 14.43208442 16.316833
OS 14.44502826 16.31498388
OS 14.46999138 16.31036108
OS 14.49125626 16.3029646
OS 14.50974746 16.29556812
OS 14.5180685 16.29094532
OS 14.52454042 16.28724708
OS 14.53101234 16.28354884
OS 14.53563514 16.2798506
OS 14.53933338 16.27707692
OS 14.54210706 16.2752278
OS 14.54395618 16.27430324
OS 14.54488074 16.27337868
OS 14.56244738 16.25581204
OS 14.57631578 16.23639628
OS 14.5874105 16.21605596
OS 14.5966561 16.19571564
OS 14.60220346 16.178149
OS 14.60497714 16.17075252
OS 14.60682626 16.1642806
OS 14.60775082 16.15873324
OS 14.60867538 16.155035
OS 14.60959994 16.15226132
OS 14.60959994 16.15133676
OS 14.53101234 16.13746836
OS 14.5273141 16.15780868
OS 14.52176674 16.17537532
OS 14.51529482 16.19016828
OS 14.5088229 16.20218756
OS 14.50235098 16.21143316
OS 14.49680362 16.21790508
OS 14.49310538 16.22252788
OS 14.49218082 16.22345244
OS 14.48016154 16.23269804
OS 14.4672177 16.24009452
OS 14.45519842 16.24471732
OS 14.44317914 16.24841556
OS 14.43208442 16.25026468
OS 14.42376338 16.2521138
OS 14.4163669 16.2521138
OS 14.39972482 16.25118924
OS 14.38493186 16.247491
OS 14.37198802 16.2428682
OS 14.3608933 16.2382454
OS 14.35257226 16.23269804
OS 14.34610034 16.22807524
OS 14.34147754 16.224377
OS 14.34055298 16.22345244
OS 14.33038282 16.21235772
OS 14.32298634 16.20033844
OS 14.31836354 16.18831916
OS 14.3146653 16.17722444
OS 14.31281618 16.16705428
OS 14.31096706 16.1596578
OS 14.31096706 16.15411044
OS 14.31096706 16.15318588
OS 14.31096706 16.15226132
OS 14.31096706 16.14209116
OS 14.31281618 16.13284556
OS 14.31743898 16.11712804
OS 14.3239109 16.10325964
OS 14.33130738 16.09124036
OS 14.33870386 16.08291932
OS 14.34517578 16.0764474
OS 14.34979858 16.07274916
OS 14.35072314 16.0718246
OS 14.3516477 16.0718246
OS 14.36736522 16.06350356
OS 14.38215818 16.05703164
OS 14.3978757 16.05240884
OS 14.4117441 16.04963516
OS 14.42376338 16.04778604
OS 14.43393354 16.04593692
OS 14.44595282 16.04593692
OS 14.44965106 16.04686148
OS 14.45427386 16.04686148
OS 14.46351946 15.97751948
OS 14.45150018 15.98029316
OS 14.44040546 15.98214228
OS 14.43115986 15.9839914
OS 14.42283882 15.98491596
OS 14.4163669 15.98584052
OS 14.40804586 15.98584052
OS 14.3886301 15.9839914
OS 14.37106346 15.98029316
OS 14.35534594 15.9747458
OS 14.3424021 15.96827388
OS 14.33223194 15.96180196
OS 14.32483546 15.9562546
OS 14.32021266 15.95255636
OS 14.31836354 15.95070724
OS 14.30634426 15.93683884
OS 14.29709866 15.92204588
OS 14.29062674 15.90725292
OS 14.2869285 15.89245996
OS 14.28415482 15.88044068
OS 14.28323026 15.87027052
OS 14.2823057 15.86657228
OS 14.2823057 15.8637986
OS 14.2823057 15.86194948
OS 14.2823057 15.86102492
OS 14.28415482 15.8406846
OS 14.28877762 15.8221934
OS 14.29432498 15.80647588
OS 14.30172146 15.79260748
OS 14.30911794 15.78151276
OS 14.3146653 15.77319172
OS 14.3192881 15.76764436
OS 14.32113722 15.76579524
OS 14.33593018 15.7528514
OS 14.3516477 15.7436058
OS 14.36736522 15.73713388
OS 14.38215818 15.73251108
OS 14.39510202 15.7297374
OS 14.40527218 15.72881284
OS 14.40897042 15.72788828
OS 14.41451778 15.72788828
OS 14.43115986 15.72881284
OS 14.44687738 15.73251108
OS 14.46074578 15.73713388
OS 14.4718405 15.74268124
OS 14.4810861 15.74730404
OS 14.48848258 15.75192684
OS 14.49218082 15.75562508
OS 14.49402994 15.75654964
OS 14.50512466 15.76949348
OS 14.51437026 15.78428644
OS 14.5226913 15.80000396
OS 14.52916322 15.81664604
OS 14.53378602 15.83051444
OS 14.53563514 15.83698636
OS 14.5365597 15.84253372
OS 14.53748426 15.84715652
OS 14.53840882 15.85085476
OS 14.53933338 15.85270388
OS 14.53933338 15.85362844
OS 14.61792098 15.84345828
OS 14.61607186 15.82866532
OS 14.61329818 15.81479692
OS 14.60497714 15.78890924
OS 14.59480698 15.7667198
OS 14.58925962 15.7574742
OS 14.58371226 15.7482286
OS 14.5781649 15.73990756
OS 14.57261754 15.73343564
OS 14.56799474 15.72696372
OS 14.56337194 15.72234092
OS 14.56059826 15.71864268
OS 14.55782458 15.715869
OS 14.55597546 15.71401988
OS 14.5550509 15.71309532
OS 14.54395618 15.70477428
OS 14.53286146 15.69645324
OS 14.52176674 15.68998132
OS 14.50974746 15.68443396
OS 14.48663346 15.67518836
OS 14.46444402 15.669641
OS 14.45427386 15.66779188
OS 14.44502826 15.66594276
OS 14.43670722 15.6650182
OS 14.42931074 15.66409364
OS 14.42376338 15.66316908
OS 14.41544234 15.66316908
OS 14.3978757 15.66409364
OS 14.38215818 15.66594276
OS 14.36644066 15.66871644
OS 14.3516477 15.67241468
OS 14.3377793 15.67703748
OS 14.32576002 15.68166028
OS 14.31374074 15.68720764
OS 14.30357058 15.692755
OS 14.29340042 15.6973778
OS 14.28507938 15.70292516
OS 14.2776829 15.70754796
OS 14.27213554 15.71217076
OS 14.26751274 15.715869
OS 14.2638145 15.71864268
OS 14.26196538 15.7204918
OS 14.26104082 15.72141636
OS 14.2499461 15.73251108
OS 14.2407005 15.74453036
OS 14.23237946 15.75654964
OS 14.22498298 15.76856892
OS 14.21943562 15.77966364
OS 14.21388826 15.79168292
OS 14.20649178 15.81387236
OS 14.20464266 15.82404252
OS 14.20279354 15.83328812
OS 14.20094442 15.84160916
OS 14.20001986 15.84900564
OS 14.1990953 15.854553
OS 14.1990953 15.8591758
OS 14.1990953 15.86194948
OS 14.1990953 15.86287404
OS 14.20001986 15.88506348
OS 14.2037181 15.9054038
OS 14.20926546 15.92297044
OS 14.21481282 15.9377634
OS 14.22036018 15.94978268
OS 14.22590754 15.95902828
OS 14.22960578 15.96457564
OS 14.23053034 15.96642476
OS 14.24347418 15.98029316
OS 14.25734258 15.99231244
OS 14.27213554 16.00155804
OS 14.2869285 16.00895452
OS 14.29987234 16.01450188
OS 14.3100425 16.01820012
OS 14.31374074 16.01912468
OS 14.31651442 16.02004924
OS 14.31836354 16.0209738
OS 14.3192881 16.0209738
OS 14.30357058 16.02929484
OS 14.29062674 16.03761588
OS 14.27953202 16.04686148
OS 14.27028642 16.05518252
OS 14.26288994 16.062579
OS 14.25734258 16.06905092
OS 14.2545689 16.07274916
OS 14.25364434 16.07459828
OS 14.24624786 16.08754212
OS 14.2407005 16.10048596
OS 14.2360777 16.1134298
OS 14.23330402 16.12544908
OS 14.2314549 16.13561924
OS 14.23053034 16.14301572
OS 14.23053034 16.14856308
OS 14.23053034 16.1504122
OS 14.2314549 16.16612972
OS 14.23422858 16.18184724
OS 14.23792682 16.19571564
OS 14.24254962 16.20773492
OS 14.24717242 16.21790508
OS 14.25087066 16.22622612
OS 14.25364434 16.23084892
OS 14.2545689 16.23269804
OS 14.2638145 16.24656644
OS 14.27490922 16.25858572
OS 14.28600394 16.26875588
OS 14.29709866 16.27800148
OS 14.30634426 16.2844734
OS 14.3146653 16.29002076
OS 14.32021266 16.29279444
OS 14.32113722 16.293719
OS 14.32206178 16.293719
OS 14.33870386 16.30111548
OS 14.35534594 16.30666284
OS 14.37198802 16.31128564
OS 14.38678098 16.31405932
OS 14.39880026 16.31590844
OE
SE
S P 0
OB 15.22672596 15.12006882 I
OS 15.23319788 15.12099338
OS 15.24244348 15.12099338
OS 15.27295396 15.11914426
OS 15.30253988 15.11452146
OS 15.32842756 15.1089741
OS 15.34044684 15.10527586
OS 15.35154156 15.10157762
OS 15.36171172 15.09787938
OS 15.37095732 15.09418114
OS 15.3783538 15.09140746
OS 15.38575028 15.08863378
OS 15.39037308 15.0858601
OS 15.39407132 15.08401098
OS 15.396845 15.08308642
OS 15.39776956 15.08216186
OS 15.42273268 15.06644434
OS 15.44399756 15.04795314
OS 15.46248876 15.02946194
OS 15.47820628 15.01097074
OS 15.49022556 14.99432866
OS 15.49484836 14.98693218
OS 15.4985466 14.98046026
OS 15.50224484 14.97583746
OS 15.50409396 14.97213922
OS 15.50501852 14.96936554
OS 15.50594308 14.96844098
OS 15.51888692 14.93977962
OS 15.52813252 14.9101937
OS 15.53460444 14.88060778
OS 15.53922724 14.85379554
OS 15.54107636 14.84177626
OS 15.54200092 14.82975698
OS 15.54292548 14.82051138
OS 15.54292548 14.81126578
OS 15.54385004 14.80479386
OS 15.54385004 14.7992465
OS 15.54385004 14.79554826
OS 15.54385004 14.7946237
OS 15.54200092 14.76133954
OS 15.53830268 14.72897994
OS 15.53367988 14.70031858
OS 15.52998164 14.68645018
OS 15.52720796 14.6744309
OS 15.52443428 14.66333618
OS 15.52073604 14.65316602
OS 15.51796236 14.64392042
OS 15.51611324 14.63652394
OS 15.51333956 14.63097658
OS 15.512415 14.62635378
OS 15.51056588 14.6235801
OS 15.51056588 14.62265554
OS 15.49669748 14.59491874
OS 15.48097996 14.56995562
OS 15.46433788 14.54869074
OS 15.45601684 14.5403697
OS 15.44862036 14.53204866
OS 15.44122388 14.52465218
OS 15.4338274 14.51818026
OS 15.42735548 14.5126329
OS 15.42180812 14.50893466
OS 15.41810988 14.50523642
OS 15.41441164 14.50246274
OS 15.41256252 14.50153818
OS 15.41163796 14.50061362
OS 15.39869412 14.49321714
OS 15.38575028 14.48674522
OS 15.35801348 14.47657506
OS 15.33027668 14.46917858
OS 15.30346444 14.46455578
OS 15.2905206 14.46270666
OS 15.27942588 14.46085754
OS 15.26925572 14.45993298
OS 15.26093468 14.45993298
OS 15.2535382 14.45900842
OS 15.24336804 14.45900842
OS 15.22487684 14.45993298
OS 15.2073102 14.4617821
OS 15.19066812 14.46363122
OS 15.1749506 14.46732946
OS 15.16015764 14.47195226
OS 15.14628924 14.47657506
OS 15.1333454 14.48119786
OS 15.12132612 14.48674522
OS 15.11115596 14.49136802
OS 15.1009858 14.49599082
OS 15.09358932 14.50061362
OS 15.08619284 14.50523642
OS 15.08157004 14.50893466
OS 15.07694724 14.51078378
OS 15.07509812 14.5126329
OS 15.07417356 14.51355746
OS 15.06122972 14.52465218
OS 15.050135 14.5357469
OS 15.03996484 14.54869074
OS 15.02979468 14.56163458
OS 15.0131526 14.58752226
OS 15.00020876 14.61340994
OS 14.9946614 14.62542922
OS 14.9900386 14.63652394
OS 14.98634036 14.6466941
OS 14.98356668 14.65501514
OS 14.980793 14.66241162
OS 14.97894388 14.66795898
OS 14.97801932 14.67165722
OS 14.97801932 14.67258178
OS 15.06307884 14.69384666
OS 15.06677708 14.6790537
OS 15.07139988 14.6651853
OS 15.07602268 14.65224146
OS 15.08064548 14.64022218
OS 15.08619284 14.62912746
OS 15.0917402 14.61988186
OS 15.09821212 14.61063626
OS 15.10375948 14.60231522
OS 15.10838228 14.59491874
OS 15.11392964 14.58937138
OS 15.11855244 14.58382402
OS 15.12225068 14.57920122
OS 15.12594892 14.57642754
OS 15.1287226 14.57365386
OS 15.12964716 14.5727293
OS 15.13057172 14.57180474
OS 15.13981732 14.56440826
OS 15.14998748 14.5588609
OS 15.1703278 14.54869074
OS 15.18974356 14.54129426
OS 15.20915932 14.53667146
OS 15.2258014 14.53297322
OS 15.23227332 14.53204866
OS 15.23874524 14.53204866
OS 15.2442926 14.5311241
OS 15.25076452 14.5311241
OS 15.2720294 14.53204866
OS 15.29236972 14.5357469
OS 15.31086092 14.5403697
OS 15.327503 14.54591706
OS 15.34044684 14.55146442
OS 15.3459942 14.5542381
OS 15.350617 14.55608722
OS 15.35431524 14.55793634
OS 15.35708892 14.55978546
OS 15.35893804 14.56071002
OS 15.3598626 14.56071002
OS 15.37742924 14.57365386
OS 15.3922222 14.58752226
OS 15.40516604 14.60323978
OS 15.4153362 14.61803274
OS 15.42365724 14.63097658
OS 15.4292046 14.6420713
OS 15.43105372 14.6466941
OS 15.43290284 14.64946778
OS 15.4338274 14.6513169
OS 15.4338274 14.65224146
OS 15.44122388 14.67628002
OS 15.44677124 14.70031858
OS 15.45139404 14.72435714
OS 15.45416772 14.74654658
OS 15.45509228 14.75671674
OS 15.45601684 14.76596234
OS 15.45601684 14.77428338
OS 15.4569414 14.7807553
OS 15.4569414 14.78630266
OS 15.4569414 14.79092546
OS 15.4569414 14.79369914
OS 15.4569414 14.7946237
OS 15.45601684 14.81866226
OS 15.45416772 14.8408517
OS 15.45046948 14.86119202
OS 15.44677124 14.87968322
OS 15.44399756 14.89540074
OS 15.44214844 14.90187266
OS 15.44029932 14.90742002
OS 15.43937476 14.91204282
OS 15.4384502 14.9148165
OS 15.43752564 14.91666562
OS 15.43752564 14.91759018
OS 15.42828004 14.93885506
OS 15.41810988 14.95827082
OS 15.40701516 14.97398834
OS 15.39499588 14.98785674
OS 15.38482572 14.99895146
OS 15.37650468 15.00634794
OS 15.37003276 15.01097074
OS 15.3691082 15.01281986
OS 15.36818364 15.01281986
OS 15.34876788 15.02483914
OS 15.327503 15.03408474
OS 15.30716268 15.04055666
OS 15.28774692 15.0442549
OS 15.27018028 15.04702858
OS 15.2627838 15.04795314
OS 15.25631188 15.04795314
OS 15.25168908 15.0488777
OS 15.2442926 15.0488777
OS 15.2211786 15.04795314
OS 15.19991372 15.0442549
OS 15.18234708 15.03870754
OS 15.16662956 15.03316018
OS 15.15461028 15.02668826
OS 15.14536468 15.02206546
OS 15.13981732 15.01836722
OS 15.1379682 15.0165181
OS 15.12317524 15.0026497
OS 15.10930684 14.98693218
OS 15.09821212 14.9702901
OS 15.08896652 14.95364802
OS 15.08157004 14.93885506
OS 15.07879636 14.93145858
OS 15.07694724 14.92591122
OS 15.07509812 14.92128842
OS 15.073249 14.91759018
OS 15.07232444 14.91574106
OS 15.07232444 14.9148165
OS 14.98911404 14.93423226
OS 14.9946614 14.95087434
OS 15.00020876 14.9656673
OS 15.00760524 14.9795357
OS 15.01407716 14.9934041
OS 15.02147364 15.00542338
OS 15.02979468 15.0165181
OS 15.03719116 15.02761282
OS 15.04458764 15.03685842
OS 15.05198412 15.0442549
OS 15.05845604 15.05165138
OS 15.06492796 15.0581233
OS 15.06955076 15.0627461
OS 15.07417356 15.0673689
OS 15.0778718 15.07014258
OS 15.07972092 15.07106714
OS 15.08064548 15.0719917
OS 15.09358932 15.08031274
OS 15.10653316 15.08863378
OS 15.119477 15.0951057
OS 15.1333454 15.10065306
OS 15.1610822 15.1089741
OS 15.18604532 15.11452146
OS 15.1980646 15.11729514
OS 15.20823476 15.1182197
OS 15.21840492 15.11914426
OS 15.22672596 15.12006882
OE
OB 14.6664426 15.11174778 I
OS 14.67198996 15.11267234
OS 14.67938644 15.11267234
OS 14.69787764 15.11174778
OS 14.71544428 15.10989866
OS 14.73208636 15.10620042
OS 14.74780388 15.10157762
OS 14.76167228 15.0951057
OS 14.77554068 15.08955834
OS 14.78755996 15.08216186
OS 14.79865468 15.07568994
OS 14.80790028 15.06921802
OS 14.81714588 15.06182154
OS 14.82454236 15.05627418
OS 14.83008972 15.05072682
OS 14.83471252 15.04517946
OS 14.83841076 15.04148122
OS 14.84025988 15.0396321
OS 14.84118444 15.03870754
OS 14.85320372 15.02206546
OS 14.86337388 15.0026497
OS 14.87261948 14.98230938
OS 14.88094052 14.9610445
OS 14.88741244 14.93885506
OS 14.8929598 14.91666562
OS 14.8975826 14.89355162
OS 14.90128084 14.87228674
OS 14.90405452 14.85102186
OS 14.90590364 14.8316061
OS 14.90775276 14.81403946
OS 14.90867732 14.7992465
OS 14.90867732 14.78630266
OS 14.90960188 14.77705706
OS 14.90960188 14.77335882
OS 14.90960188 14.77058514
OS 14.90960188 14.76966058
OS 14.90960188 14.76873602
OS 14.90867732 14.7391501
OS 14.9068282 14.7114133
OS 14.90405452 14.68552562
OS 14.89943172 14.66148706
OS 14.89480892 14.64022218
OS 14.89018612 14.62080642
OS 14.88463876 14.60323978
OS 14.87816684 14.58752226
OS 14.87261948 14.57457842
OS 14.86707212 14.56255914
OS 14.86244932 14.55331354
OS 14.85690196 14.5449925
OS 14.85320372 14.53852058
OS 14.85043004 14.53482234
OS 14.84858092 14.53204866
OS 14.84765636 14.5311241
OS 14.83563708 14.51818026
OS 14.82269324 14.50708554
OS 14.8097494 14.49783994
OS 14.79680556 14.4895189
OS 14.78293716 14.48212242
OS 14.76999332 14.47657506
OS 14.75704948 14.47195226
OS 14.74410564 14.46825402
OS 14.73301092 14.46548034
OS 14.7219162 14.46270666
OS 14.7126706 14.46085754
OS 14.70434956 14.45993298
OS 14.69695308 14.45993298
OS 14.69233028 14.45900842
OS 14.68770748 14.45900842
OS 14.6664426 14.45993298
OS 14.64702684 14.46363122
OS 14.6294602 14.46732946
OS 14.61374268 14.47287682
OS 14.6017234 14.47749962
OS 14.5924778 14.48212242
OS 14.58877956 14.48304698
OS 14.58600588 14.4848961
OS 14.58508132 14.48582066
OS 14.58415676 14.48582066
OS 14.56843924 14.49691538
OS 14.55364628 14.50985922
OS 14.541627 14.52280306
OS 14.53145684 14.5357469
OS 14.5231358 14.54776618
OS 14.51758844 14.55701178
OS 14.51573932 14.56071002
OS 14.5138902 14.5634837
OS 14.51296564 14.56440826
OS 14.51296564 14.56533282
OS 14.50372004 14.58474858
OS 14.49724812 14.6050889
OS 14.49262532 14.6235801
OS 14.48985164 14.64114674
OS 14.48707796 14.6559397
OS 14.48707796 14.66148706
OS 14.4861534 14.66703442
OS 14.4861534 14.67165722
OS 14.4861534 14.6744309
OS 14.4861534 14.67628002
OS 14.4861534 14.67720458
OS 14.48707796 14.69384666
OS 14.48892708 14.70956418
OS 14.49170076 14.7252817
OS 14.49447444 14.7391501
OS 14.49909724 14.75209394
OS 14.50372004 14.76503778
OS 14.50834284 14.7761325
OS 14.5138902 14.78630266
OS 14.51943756 14.79554826
OS 14.52406036 14.8038693
OS 14.52868316 14.81034122
OS 14.53330596 14.81681314
OS 14.53607964 14.82143594
OS 14.53885332 14.82420962
OS 14.54070244 14.82605874
OS 14.541627 14.8269833
OS 14.55179716 14.83715346
OS 14.56289188 14.84639906
OS 14.57491116 14.85379554
OS 14.58600588 14.86026746
OS 14.5971006 14.86673938
OS 14.60819532 14.87136218
OS 14.6294602 14.8778341
OS 14.6387058 14.88060778
OS 14.6479514 14.8824569
OS 14.65534788 14.88338146
OS 14.66274436 14.88430602
OS 14.66829172 14.88523058
OS 14.6756882 14.88523058
OS 14.69233028 14.88430602
OS 14.7080478 14.88153234
OS 14.72284076 14.87875866
OS 14.7357846 14.87506042
OS 14.74687932 14.87043762
OS 14.75520036 14.86766394
OS 14.76074772 14.86489026
OS 14.76167228 14.8639657
OS 14.76259684 14.8639657
OS 14.7773898 14.8547201
OS 14.79033364 14.84454994
OS 14.80235292 14.83437978
OS 14.81159852 14.82328506
OS 14.81991956 14.81403946
OS 14.82639148 14.80664298
OS 14.83008972 14.80109562
OS 14.83101428 14.80017106
OS 14.83101428 14.81681314
OS 14.83008972 14.83345522
OS 14.82916516 14.84824818
OS 14.82731604 14.86304114
OS 14.82639148 14.87598498
OS 14.82454236 14.88800426
OS 14.82269324 14.89909898
OS 14.81991956 14.90926914
OS 14.81807044 14.91851474
OS 14.81622132 14.92591122
OS 14.8143722 14.93238314
OS 14.81344764 14.9379305
OS 14.81159852 14.94162874
OS 14.81067396 14.94440242
OS 14.8097494 14.94625154
OS 14.8097494 14.9471761
OS 14.8005038 14.9656673
OS 14.7912582 14.98230938
OS 14.78108804 14.99525322
OS 14.77184244 15.00634794
OS 14.7635214 15.01559354
OS 14.75704948 15.02206546
OS 14.75242668 15.0257637
OS 14.75057756 15.02668826
OS 14.73948284 15.03408474
OS 14.72838812 15.03870754
OS 14.7172934 15.04240578
OS 14.70619868 15.04517946
OS 14.69787764 15.04702858
OS 14.69048116 15.04795314
OS 14.68400924 15.04795314
OS 14.66736716 15.04610402
OS 14.65164964 15.04240578
OS 14.6387058 15.03685842
OS 14.62668652 15.03131106
OS 14.61744092 15.02483914
OS 14.610969 15.01929178
OS 14.60727076 15.01559354
OS 14.60542164 15.01374442
OS 14.59894972 15.00542338
OS 14.5924778 14.99525322
OS 14.58693044 14.9841585
OS 14.5832322 14.97306378
OS 14.57953396 14.96289362
OS 14.57676028 14.95457258
OS 14.57583572 14.94902522
OS 14.57491116 14.94810066
OS 14.57491116 14.9471761
OS 14.49632356 14.95364802
OS 14.50187092 14.9795357
OS 14.51019196 15.0026497
OS 14.51943756 15.02299002
OS 14.52960772 15.0396321
OS 14.53977788 15.05257594
OS 14.54347612 15.0581233
OS 14.54809892 15.0627461
OS 14.5508726 15.06551978
OS 14.55364628 15.06829346
OS 14.55457084 15.06921802
OS 14.5554954 15.07014258
OS 14.564741 15.07753906
OS 14.57491116 15.08401098
OS 14.59525148 15.0951057
OS 14.6155918 15.10250218
OS 14.63500756 15.10712498
OS 14.6525742 15.11082322
OS 14.65997068 15.11174778
OS 14.6664426 15.11174778
OE
OB 14.69140572 14.81588858 H
OS 14.67198996 14.81403946
OS 14.65442332 14.80941666
OS 14.63963036 14.8038693
OS 14.62668652 14.79647282
OS 14.61651636 14.78907634
OS 14.60911988 14.78352898
OS 14.60449708 14.77890618
OS 14.60264796 14.77705706
OS 14.59062868 14.76133954
OS 14.58138308 14.74469746
OS 14.57491116 14.72713082
OS 14.57121292 14.71048874
OS 14.56843924 14.69569578
OS 14.56751468 14.68922386
OS 14.56751468 14.6836765
OS 14.56659012 14.6790537
OS 14.56659012 14.67535546
OS 14.56659012 14.67350634
OS 14.56659012 14.67258178
OS 14.56843924 14.64761866
OS 14.57213748 14.62635378
OS 14.57768484 14.60786258
OS 14.58415676 14.59214506
OS 14.59155324 14.58012578
OS 14.5971006 14.57088018
OS 14.60079884 14.56533282
OS 14.60264796 14.56440826
OS 14.60264796 14.5634837
OS 14.60911988 14.55608722
OS 14.61651636 14.55053986
OS 14.63130932 14.5403697
OS 14.64610228 14.53389778
OS 14.65904612 14.52835042
OS 14.6710654 14.52557674
OS 14.680311 14.52465218
OS 14.68400924 14.52372762
OS 14.68863204 14.52372762
OS 14.70157588 14.52465218
OS 14.71359516 14.5265013
OS 14.72468988 14.53019954
OS 14.73393548 14.53389778
OS 14.74225652 14.53667146
OS 14.74872844 14.5403697
OS 14.75242668 14.54221882
OS 14.7542758 14.54314338
OS 14.76537052 14.55146442
OS 14.77461612 14.55978546
OS 14.78293716 14.56995562
OS 14.78940908 14.57827666
OS 14.79495644 14.5865977
OS 14.79865468 14.59306962
OS 14.80142836 14.59769242
OS 14.80235292 14.59954154
OS 14.80790028 14.61340994
OS 14.81159852 14.62727834
OS 14.81529676 14.64022218
OS 14.81714588 14.65224146
OS 14.81807044 14.66241162
OS 14.818995 14.67073266
OS 14.818995 14.67535546
OS 14.818995 14.67720458
OS 14.81714588 14.69939402
OS 14.81344764 14.71880978
OS 14.80697572 14.73637642
OS 14.8005038 14.75024482
OS 14.79403188 14.7622641
OS 14.78755996 14.77058514
OS 14.78386172 14.77520794
OS 14.7820126 14.77705706
OS 14.76721964 14.7900009
OS 14.75242668 14.7992465
OS 14.73670916 14.80664298
OS 14.72284076 14.81126578
OS 14.70989692 14.81403946
OS 14.70065132 14.81496402
OS 14.69695308 14.81588858
OS 14.69140572 14.81588858
OE
SE
S P 0
OB 15.86672468 24.15768092 I
OS 15.87412116 24.15860548
OS 16.17090492 24.15860548
OS 16.17090492 23.51880996
OS 16.0858454 23.51880996
OS 16.0858454 23.80264988
OS 15.97674732 23.80264988
OS 15.96657716 23.80172532
OS 15.95918068 23.80172532
OS 15.95270876 23.80080076
OS 15.94808596 23.7998762
OS 15.94438772 23.7998762
OS 15.9425386 23.79895164
OS 15.94161404 23.79895164
OS 15.92682108 23.79432884
OS 15.92034916 23.79155516
OS 15.9148018 23.78878148
OS 15.90925444 23.7860078
OS 15.9055562 23.78415868
OS 15.90370708 23.78323412
OS 15.90278252 23.78230956
OS 15.89538604 23.7767622
OS 15.88798956 23.77029028
OS 15.87412116 23.75642188
OS 15.86764924 23.74994996
OS 15.86302644 23.7444026
OS 15.86025276 23.74070436
OS 15.8593282 23.7397798
OS 15.8500826 23.72683596
OS 15.83991244 23.71296756
OS 15.82974228 23.6981746
OS 15.81957212 23.6843062
OS 15.81125108 23.67136236
OS 15.80477916 23.6611922
OS 15.80200548 23.65749396
OS 15.80015636 23.65472028
OS 15.79830724 23.65287116
OS 15.79830724 23.6519466
OS 15.71417228 23.51880996
OS 15.60877244 23.51880996
OS 15.71879508 23.69262724
OS 15.73173892 23.71111844
OS 15.7437582 23.72776052
OS 15.75577748 23.74162892
OS 15.76594764 23.75457276
OS 15.77519324 23.76381836
OS 15.78258972 23.77121484
OS 15.78721252 23.77583764
OS 15.78906164 23.77768676
OS 15.79645812 23.78323412
OS 15.80477916 23.78970604
OS 15.82142124 23.7998762
OS 15.82881772 23.80357444
OS 15.83436508 23.80727268
OS 15.83806332 23.8091218
OS 15.83991244 23.81004636
OS 15.82327036 23.81282004
OS 15.80755284 23.81559372
OS 15.79368444 23.82021652
OS 15.77981604 23.82391476
OS 15.76779676 23.82853756
OS 15.75670204 23.83408492
OS 15.74653188 23.83870772
OS 15.73728628 23.84333052
OS 15.7298898 23.84887788
OS 15.72249332 23.85350068
OS 15.71694596 23.85719892
OS 15.71232316 23.86089716
OS 15.70862492 23.86367084
OS 15.70585124 23.86644452
OS 15.70492668 23.86736908
OS 15.70400212 23.86829364
OS 15.69660564 23.87753924
OS 15.68920916 23.88678484
OS 15.67811444 23.9062006
OS 15.67071796 23.92561636
OS 15.6651706 23.94410756
OS 15.66147236 23.95982508
OS 15.6605478 23.966297
OS 15.6605478 23.97276892
OS 15.65962324 23.97739172
OS 15.65962324 23.98108996
OS 15.65962324 23.98293908
OS 15.65962324 23.98386364
OS 15.6605478 24.0032794
OS 15.66332148 24.02084604
OS 15.66794428 24.03748812
OS 15.67256708 24.05135652
OS 15.67811444 24.0633758
OS 15.68181268 24.0726214
OS 15.68551092 24.07816876
OS 15.68643548 24.07909332
OS 15.68643548 24.08001788
OS 15.6975302 24.09481084
OS 15.70862492 24.10775468
OS 15.7206442 24.1188494
OS 15.73173892 24.12717044
OS 15.74190908 24.13364236
OS 15.75023012 24.1373406
OS 15.75577748 24.14011428
OS 15.75670204 24.14103884
OS 15.7576266 24.14103884
OS 15.76594764 24.14381252
OS 15.7761178 24.1465862
OS 15.79645812 24.151209
OS 15.81864756 24.15398268
OS 15.83898788 24.15675636
OS 15.85840364 24.15768092
OS 15.86672468 24.15768092
OE
OB 15.31938516 24.1604546 I
OS 15.32493252 24.16137916
OS 15.332329 24.16137916
OS 15.3508202 24.1604546
OS 15.36838684 24.15860548
OS 15.38502892 24.15490724
OS 15.40074644 24.15028444
OS 15.41461484 24.14381252
OS 15.42848324 24.13826516
OS 15.44050252 24.13086868
OS 15.45159724 24.12439676
OS 15.46084284 24.11792484
OS 15.47008844 24.11052836
OS 15.47748492 24.104981
OS 15.48303228 24.09943364
OS 15.48765508 24.09388628
OS 15.49135332 24.09018804
OS 15.49320244 24.08833892
OS 15.494127 24.08741436
OS 15.50614628 24.07077228
OS 15.51631644 24.05135652
OS 15.52556204 24.0310162
OS 15.53388308 24.00975132
OS 15.540355 23.98756188
OS 15.54590236 23.96537244
OS 15.55052516 23.94225844
OS 15.5542234 23.92099356
OS 15.55699708 23.89972868
OS 15.5588462 23.88031292
OS 15.56069532 23.86274628
OS 15.56161988 23.84795332
OS 15.56161988 23.83500948
OS 15.56254444 23.82576388
OS 15.56254444 23.82206564
OS 15.56254444 23.81929196
OS 15.56254444 23.8183674
OS 15.56254444 23.81744284
OS 15.56161988 23.78785692
OS 15.55977076 23.76012012
OS 15.55699708 23.73423244
OS 15.55237428 23.71019388
OS 15.54775148 23.688929
OS 15.54312868 23.66951324
OS 15.53758132 23.6519466
OS 15.5311094 23.63622908
OS 15.52556204 23.62328524
OS 15.52001468 23.61126596
OS 15.51539188 23.60202036
OS 15.50984452 23.59369932
OS 15.50614628 23.5872274
OS 15.5033726 23.58352916
OS 15.50152348 23.58075548
OS 15.50059892 23.57983092
OS 15.48857964 23.56688708
OS 15.4756358 23.55579236
OS 15.46269196 23.54654676
OS 15.44974812 23.53822572
OS 15.43587972 23.53082924
OS 15.42293588 23.52528188
OS 15.40999204 23.52065908
OS 15.3970482 23.51696084
OS 15.38595348 23.51418716
OS 15.37485876 23.51141348
OS 15.36561316 23.50956436
OS 15.35729212 23.5086398
OS 15.34989564 23.5086398
OS 15.34527284 23.50771524
OS 15.34065004 23.50771524
OS 15.31938516 23.5086398
OS 15.2999694 23.51233804
OS 15.28240276 23.51603628
OS 15.26668524 23.52158364
OS 15.25466596 23.52620644
OS 15.24542036 23.53082924
OS 15.24172212 23.5317538
OS 15.23894844 23.53360292
OS 15.23802388 23.53452748
OS 15.23709932 23.53452748
OS 15.2213818 23.5456222
OS 15.20658884 23.55856604
OS 15.19456956 23.57150988
OS 15.1843994 23.58445372
OS 15.17607836 23.596473
OS 15.170531 23.6057186
OS 15.16868188 23.60941684
OS 15.16683276 23.61219052
OS 15.1659082 23.61311508
OS 15.1659082 23.61403964
OS 15.1566626 23.6334554
OS 15.15019068 23.65379572
OS 15.14556788 23.67228692
OS 15.1427942 23.68985356
OS 15.14002052 23.70464652
OS 15.14002052 23.71019388
OS 15.13909596 23.71574124
OS 15.13909596 23.72036404
OS 15.13909596 23.72313772
OS 15.13909596 23.72498684
OS 15.13909596 23.7259114
OS 15.14002052 23.74255348
OS 15.14186964 23.758271
OS 15.14464332 23.77398852
OS 15.147417 23.78785692
OS 15.1520398 23.80080076
OS 15.1566626 23.8137446
OS 15.1612854 23.82483932
OS 15.16683276 23.83500948
OS 15.17238012 23.84425508
OS 15.17700292 23.85257612
OS 15.18162572 23.85904804
OS 15.18624852 23.86551996
OS 15.1890222 23.87014276
OS 15.19179588 23.87291644
OS 15.193645 23.87476556
OS 15.19456956 23.87569012
OS 15.20473972 23.88586028
OS 15.21583444 23.89510588
OS 15.22785372 23.90250236
OS 15.23894844 23.90897428
OS 15.25004316 23.9154462
OS 15.26113788 23.920069
OS 15.28240276 23.92654092
OS 15.29164836 23.9293146
OS 15.30089396 23.93116372
OS 15.30829044 23.93208828
OS 15.31568692 23.93301284
OS 15.32123428 23.9339374
OS 15.32863076 23.9339374
OS 15.34527284 23.93301284
OS 15.36099036 23.93023916
OS 15.37578332 23.92746548
OS 15.38872716 23.92376724
OS 15.39982188 23.91914444
OS 15.40814292 23.91637076
OS 15.41369028 23.91359708
OS 15.41461484 23.91267252
OS 15.4155394 23.91267252
OS 15.43033236 23.90342692
OS 15.4432762 23.89325676
OS 15.45529548 23.8830866
OS 15.46454108 23.87199188
OS 15.47286212 23.86274628
OS 15.47933404 23.8553498
OS 15.48303228 23.84980244
OS 15.48395684 23.84887788
OS 15.48395684 23.86551996
OS 15.48303228 23.88216204
OS 15.48210772 23.896955
OS 15.4802586 23.91174796
OS 15.47933404 23.9246918
OS 15.47748492 23.93671108
OS 15.4756358 23.9478058
OS 15.47286212 23.95797596
OS 15.471013 23.96722156
OS 15.46916388 23.97461804
OS 15.46731476 23.98108996
OS 15.4663902 23.98663732
OS 15.46454108 23.99033556
OS 15.46361652 23.99310924
OS 15.46269196 23.99495836
OS 15.46269196 23.99588292
OS 15.45344636 24.01437412
OS 15.44420076 24.0310162
OS 15.4340306 24.04396004
OS 15.424785 24.05505476
OS 15.41646396 24.06430036
OS 15.40999204 24.07077228
OS 15.40536924 24.07447052
OS 15.40352012 24.07539508
OS 15.3924254 24.08279156
OS 15.38133068 24.08741436
OS 15.37023596 24.0911126
OS 15.35914124 24.09388628
OS 15.3508202 24.0957354
OS 15.34342372 24.09665996
OS 15.3369518 24.09665996
OS 15.32030972 24.09481084
OS 15.3045922 24.0911126
OS 15.29164836 24.08556524
OS 15.27962908 24.08001788
OS 15.27038348 24.07354596
OS 15.26391156 24.0679986
OS 15.26021332 24.06430036
OS 15.2583642 24.06245124
OS 15.25189228 24.0541302
OS 15.24542036 24.04396004
OS 15.239873 24.03286532
OS 15.23617476 24.0217706
OS 15.23247652 24.01160044
OS 15.22970284 24.0032794
OS 15.22877828 23.99773204
OS 15.22785372 23.99680748
OS 15.22785372 23.99588292
OS 15.14926612 24.00235484
OS 15.15481348 24.02824252
OS 15.16313452 24.05135652
OS 15.17238012 24.07169684
OS 15.18255028 24.08833892
OS 15.19272044 24.10128276
OS 15.19641868 24.10683012
OS 15.20104148 24.11145292
OS 15.20381516 24.1142266
OS 15.20658884 24.11700028
OS 15.2075134 24.11792484
OS 15.20843796 24.1188494
OS 15.21768356 24.12624588
OS 15.22785372 24.1327178
OS 15.24819404 24.14381252
OS 15.26853436 24.151209
OS 15.28795012 24.1558318
OS 15.30551676 24.15953004
OS 15.31291324 24.1604546
OS 15.31938516 24.1604546
OE
OB 15.88429132 24.08741436 H
OS 15.8593282 24.0864898
OS 15.83806332 24.08279156
OS 15.81957212 24.07816876
OS 15.80570372 24.0726214
OS 15.79368444 24.06707404
OS 15.78628796 24.06245124
OS 15.78166516 24.058753
OS 15.77981604 24.05782844
OS 15.76872132 24.04580916
OS 15.76040028 24.03378988
OS 15.75485292 24.02084604
OS 15.75023012 24.00975132
OS 15.748381 23.9986566
OS 15.74745644 23.99033556
OS 15.74653188 23.9847882
OS 15.74653188 23.98386364
OS 15.74653188 23.98293908
OS 15.74745644 23.97184436
OS 15.74930556 23.96074964
OS 15.75207924 23.95150404
OS 15.75485292 23.943183
OS 15.75855116 23.93578652
OS 15.76132484 23.93023916
OS 15.76317396 23.92654092
OS 15.76409852 23.92561636
OS 15.77057044 23.91637076
OS 15.77889148 23.90804972
OS 15.78721252 23.9015778
OS 15.79553356 23.89603044
OS 15.80293004 23.8923322
OS 15.8084774 23.88955852
OS 15.81217564 23.8877094
OS 15.81402476 23.88678484
OS 15.8269686 23.8830866
OS 15.84176156 23.88031292
OS 15.85655452 23.8784638
OS 15.87134748 23.87753924
OS 15.88429132 23.87661468
OS 15.89538604 23.87569012
OS 16.0858454 23.87569012
OS 16.0858454 24.08741436
OS 15.88429132 24.08741436
OE
OB 15.34434828 23.8645954 H
OS 15.32493252 23.86274628
OS 15.30736588 23.85812348
OS 15.29257292 23.85257612
OS 15.27962908 23.84517964
OS 15.26945892 23.83778316
OS 15.26206244 23.8322358
OS 15.25743964 23.827613
OS 15.25559052 23.82576388
OS 15.24357124 23.81004636
OS 15.23432564 23.79340428
OS 15.22785372 23.77583764
OS 15.22415548 23.75919556
OS 15.2213818 23.7444026
OS 15.22045724 23.73793068
OS 15.22045724 23.73238332
OS 15.21953268 23.72776052
OS 15.21953268 23.72406228
OS 15.21953268 23.72221316
OS 15.21953268 23.7212886
OS 15.2213818 23.69632548
OS 15.22508004 23.6750606
OS 15.2306274 23.6565694
OS 15.23709932 23.64085188
OS 15.2444958 23.6288326
OS 15.25004316 23.619587
OS 15.2537414 23.61403964
OS 15.25559052 23.61311508
OS 15.25559052 23.61219052
OS 15.26206244 23.60479404
OS 15.26945892 23.59924668
OS 15.28425188 23.58907652
OS 15.29904484 23.5826046
OS 15.31198868 23.57705724
OS 15.32400796 23.57428356
OS 15.33325356 23.573359
OS 15.3369518 23.57243444
OS 15.3415746 23.57243444
OS 15.35451844 23.573359
OS 15.36653772 23.57520812
OS 15.37763244 23.57890636
OS 15.38687804 23.5826046
OS 15.39519908 23.58537828
OS 15.401671 23.58907652
OS 15.40536924 23.59092564
OS 15.40721836 23.5918502
OS 15.41831308 23.60017124
OS 15.42755868 23.60849228
OS 15.43587972 23.61866244
OS 15.44235164 23.62698348
OS 15.447899 23.63530452
OS 15.45159724 23.64177644
OS 15.45437092 23.64639924
OS 15.45529548 23.64824836
OS 15.46084284 23.66211676
OS 15.46454108 23.67598516
OS 15.46823932 23.688929
OS 15.47008844 23.70094828
OS 15.471013 23.71111844
OS 15.47193756 23.71943948
OS 15.47193756 23.72406228
OS 15.47193756 23.7259114
OS 15.47008844 23.74810084
OS 15.4663902 23.7675166
OS 15.45991828 23.78508324
OS 15.45344636 23.79895164
OS 15.44697444 23.81097092
OS 15.44050252 23.81929196
OS 15.43680428 23.82391476
OS 15.43495516 23.82576388
OS 15.4201622 23.83870772
OS 15.40536924 23.84795332
OS 15.38965172 23.8553498
OS 15.37578332 23.8599726
OS 15.36283948 23.86274628
OS 15.35359388 23.86367084
OS 15.34989564 23.8645954
OS 15.34434828 23.8645954
OE
SE
S P 0
OB 17.16903348 24.15906776 I
OS 17.17642996 24.15999232
OS 17.47321372 24.15999232
OS 17.47321372 23.5201968
OS 17.3881542 23.5201968
OS 17.3881542 23.80403672
OS 17.27905612 23.80403672
OS 17.26888596 23.80311216
OS 17.26148948 23.80311216
OS 17.25501756 23.8021876
OS 17.25039476 23.80126304
OS 17.24669652 23.80126304
OS 17.2448474 23.80033848
OS 17.24392284 23.80033848
OS 17.22912988 23.79571568
OS 17.22265796 23.792942
OS 17.2171106 23.79016832
OS 17.21156324 23.78739464
OS 17.207865 23.78554552
OS 17.20601588 23.78462096
OS 17.20509132 23.7836964
OS 17.19769484 23.77814904
OS 17.19029836 23.77167712
OS 17.17642996 23.75780872
OS 17.16995804 23.7513368
OS 17.16533524 23.74578944
OS 17.16256156 23.7420912
OS 17.161637 23.74116664
OS 17.1523914 23.7282228
OS 17.14222124 23.7143544
OS 17.13205108 23.69956144
OS 17.12188092 23.68569304
OS 17.11355988 23.6727492
OS 17.10708796 23.66257904
OS 17.10431428 23.6588808
OS 17.10246516 23.65610712
OS 17.10061604 23.654258
OS 17.10061604 23.65333344
OS 17.01648108 23.5201968
OS 16.91108124 23.5201968
OS 17.02110388 23.69401408
OS 17.03404772 23.71250528
OS 17.046067 23.72914736
OS 17.05808628 23.74301576
OS 17.06825644 23.7559596
OS 17.07750204 23.7652052
OS 17.08489852 23.77260168
OS 17.08952132 23.77722448
OS 17.09137044 23.7790736
OS 17.09876692 23.78462096
OS 17.10708796 23.79109288
OS 17.12373004 23.80126304
OS 17.13112652 23.80496128
OS 17.13667388 23.80865952
OS 17.14037212 23.81050864
OS 17.14222124 23.8114332
OS 17.12557916 23.81420688
OS 17.10986164 23.81698056
OS 17.09599324 23.82160336
OS 17.08212484 23.8253016
OS 17.07010556 23.8299244
OS 17.05901084 23.83547176
OS 17.04884068 23.84009456
OS 17.03959508 23.84471736
OS 17.0321986 23.85026472
OS 17.02480212 23.85488752
OS 17.01925476 23.85858576
OS 17.01463196 23.862284
OS 17.01093372 23.86505768
OS 17.00816004 23.86783136
OS 17.00723548 23.86875592
OS 17.00631092 23.86968048
OS 16.99891444 23.87892608
OS 16.99151796 23.88817168
OS 16.98042324 23.90758744
OS 16.97302676 23.9270032
OS 16.9674794 23.9454944
OS 16.96378116 23.96121192
OS 16.9628566 23.96768384
OS 16.9628566 23.97415576
OS 16.96193204 23.97877856
OS 16.96193204 23.9824768
OS 16.96193204 23.98432592
OS 16.96193204 23.98525048
OS 16.9628566 24.00466624
OS 16.96563028 24.02223288
OS 16.97025308 24.03887496
OS 16.97487588 24.05274336
OS 16.98042324 24.06476264
OS 16.98412148 24.07400824
OS 16.98781972 24.0795556
OS 16.98874428 24.08048016
OS 16.98874428 24.08140472
OS 16.999839 24.09619768
OS 17.01093372 24.10914152
OS 17.022953 24.12023624
OS 17.03404772 24.12855728
OS 17.04421788 24.1350292
OS 17.05253892 24.13872744
OS 17.05808628 24.14150112
OS 17.05901084 24.14242568
OS 17.0599354 24.14242568
OS 17.06825644 24.14519936
OS 17.0784266 24.14797304
OS 17.09876692 24.15259584
OS 17.12095636 24.15536952
OS 17.14129668 24.1581432
OS 17.16071244 24.15906776
OS 17.16903348 24.15906776
OE
OB 16.46729244 24.07678192 I
OS 16.46729244 24.15167128
OS 16.78534108 24.15167128
OS 16.8472866 23.82252792
OS 16.7733218 23.81235776
OS 16.76684988 23.82252792
OS 16.75852884 23.83084896
OS 16.75113236 23.83917
OS 16.74373588 23.84564192
OS 16.7363394 23.85026472
OS 16.73079204 23.85488752
OS 16.7270938 23.85673664
OS 16.72616924 23.8576612
OS 16.71414996 23.86320856
OS 16.70213068 23.86783136
OS 16.69103596 23.87060504
OS 16.67994124 23.87337872
OS 16.67069564 23.87430328
OS 16.66329916 23.87522784
OS 16.64573252 23.87522784
OS 16.6346378 23.87337872
OS 16.61522204 23.86875592
OS 16.59857996 23.862284
OS 16.583787 23.85581208
OS 16.57269228 23.8484156
OS 16.56437124 23.84194368
OS 16.55974844 23.83732088
OS 16.55789932 23.83639632
OS 16.55789932 23.83547176
OS 16.54495548 23.81975424
OS 16.53570988 23.80311216
OS 16.52923796 23.78554552
OS 16.52461516 23.76797888
OS 16.52184148 23.75318592
OS 16.52091692 23.746714
OS 16.52091692 23.74116664
OS 16.51999236 23.73654384
OS 16.51999236 23.7328456
OS 16.51999236 23.73099648
OS 16.51999236 23.73007192
OS 16.51999236 23.71712808
OS 16.52184148 23.7051088
OS 16.52646428 23.6819948
OS 16.5329362 23.66257904
OS 16.53940812 23.64686152
OS 16.5468046 23.63391768
OS 16.55327652 23.62374752
OS 16.5560502 23.62097384
OS 16.55789932 23.61820016
OS 16.55882388 23.6172756
OS 16.55974844 23.61635104
OS 16.56714492 23.60895456
OS 16.5745414 23.60248264
OS 16.59118348 23.59138792
OS 16.606901 23.58399144
OS 16.62261852 23.57936864
OS 16.63556236 23.5756704
OS 16.64665708 23.57474584
OS 16.65035532 23.57382128
OS 16.65590268 23.57382128
OS 16.67346932 23.57474584
OS 16.68918684 23.57844408
OS 16.70305524 23.58306688
OS 16.71414996 23.58861424
OS 16.72432012 23.5941616
OS 16.7317166 23.5987844
OS 16.73541484 23.60248264
OS 16.73726396 23.6034072
OS 16.74835868 23.61635104
OS 16.75760428 23.63021944
OS 16.76500076 23.64593696
OS 16.77054812 23.65980536
OS 16.77424636 23.67367376
OS 16.77702004 23.68384392
OS 16.7779446 23.68846672
OS 16.77886916 23.6912404
OS 16.77886916 23.69308952
OS 16.77886916 23.69401408
OS 16.861155 23.68754216
OS 16.85930588 23.6727492
OS 16.8565322 23.6588808
OS 16.84821116 23.63299312
OS 16.838041 23.61080368
OS 16.83249364 23.60063352
OS 16.82694628 23.59231248
OS 16.82232348 23.58399144
OS 16.81677612 23.57659496
OS 16.81215332 23.5710476
OS 16.80753052 23.5664248
OS 16.80383228 23.56272656
OS 16.80198316 23.55902832
OS 16.80013404 23.55810376
OS 16.79920948 23.5571792
OS 16.78811476 23.54885816
OS 16.77702004 23.54146168
OS 16.76500076 23.53498976
OS 16.75298148 23.5294424
OS 16.72986748 23.52112136
OS 16.70675348 23.515574
OS 16.69658332 23.51280032
OS 16.68641316 23.51187576
OS 16.67809212 23.5109512
OS 16.67069564 23.51002664
OS 16.66422372 23.50910208
OS 16.65590268 23.50910208
OS 16.63648692 23.51002664
OS 16.61799572 23.51280032
OS 16.60042908 23.51649856
OS 16.58471156 23.52112136
OS 16.5699186 23.52759328
OS 16.5560502 23.5340652
OS 16.54310636 23.54053712
OS 16.53201164 23.5479336
OS 16.52184148 23.55533008
OS 16.51259588 23.561802
OS 16.5051994 23.56919848
OS 16.49872748 23.57474584
OS 16.49410468 23.57936864
OS 16.49040644 23.58306688
OS 16.48855732 23.58584056
OS 16.48763276 23.58676512
OS 16.47838716 23.5987844
OS 16.47099068 23.61172824
OS 16.4635942 23.62374752
OS 16.45804684 23.63669136
OS 16.44880124 23.66165448
OS 16.44325388 23.68569304
OS 16.44140476 23.6958632
OS 16.43955564 23.70603336
OS 16.43863108 23.7143544
OS 16.43770652 23.72175088
OS 16.43678196 23.7282228
OS 16.43678196 23.7328456
OS 16.43678196 23.73561928
OS 16.43678196 23.73654384
OS 16.43770652 23.75318592
OS 16.43955564 23.76890344
OS 16.44232932 23.78462096
OS 16.44602756 23.79848936
OS 16.45065036 23.8114332
OS 16.45527316 23.82437704
OS 16.46082052 23.83547176
OS 16.46544332 23.84564192
OS 16.47099068 23.85488752
OS 16.47653804 23.86320856
OS 16.48116084 23.86968048
OS 16.48578364 23.8761524
OS 16.48948188 23.8807752
OS 16.49225556 23.88354888
OS 16.49410468 23.885398
OS 16.49502924 23.88632256
OS 16.50612396 23.89649272
OS 16.51721868 23.90573832
OS 16.52923796 23.9131348
OS 16.54125724 23.91960672
OS 16.55327652 23.92607864
OS 16.5652958 23.93070144
OS 16.58748524 23.93717336
OS 16.5976554 23.93994704
OS 16.606901 23.94179616
OS 16.61522204 23.94272072
OS 16.62261852 23.94364528
OS 16.62816588 23.94456984
OS 16.6485062 23.94456984
OS 16.65960092 23.94272072
OS 16.68179036 23.93809792
OS 16.70213068 23.931626
OS 16.72062188 23.92422952
OS 16.73541484 23.91683304
OS 16.74188676 23.9131348
OS 16.74743412 23.91036112
OS 16.75205692 23.90758744
OS 16.7548306 23.90573832
OS 16.75667972 23.90481376
OS 16.75760428 23.9038892
OS 16.72339556 24.07678192
OS 16.46729244 24.07678192
OE
OB 17.18660012 24.0888012 H
OS 17.161637 24.08787664
OS 17.14037212 24.0841784
OS 17.12188092 24.0795556
OS 17.10801252 24.07400824
OS 17.09599324 24.06846088
OS 17.08859676 24.06383808
OS 17.08397396 24.06013984
OS 17.08212484 24.05921528
OS 17.07103012 24.047196
OS 17.06270908 24.03517672
OS 17.05716172 24.02223288
OS 17.05253892 24.01113816
OS 17.0506898 24.00004344
OS 17.04976524 23.9917224
OS 17.04884068 23.98617504
OS 17.04884068 23.98525048
OS 17.04884068 23.98432592
OS 17.04976524 23.9732312
OS 17.05161436 23.96213648
OS 17.05438804 23.95289088
OS 17.05716172 23.94456984
OS 17.06085996 23.93717336
OS 17.06363364 23.931626
OS 17.06548276 23.92792776
OS 17.06640732 23.9270032
OS 17.07287924 23.9177576
OS 17.08120028 23.90943656
OS 17.08952132 23.90296464
OS 17.09784236 23.89741728
OS 17.10523884 23.89371904
OS 17.1107862 23.89094536
OS 17.11448444 23.88909624
OS 17.11633356 23.88817168
OS 17.1292774 23.88447344
OS 17.14407036 23.88169976
OS 17.15886332 23.87985064
OS 17.17365628 23.87892608
OS 17.18660012 23.87800152
OS 17.19769484 23.87707696
OS 17.3881542 23.87707696
OS 17.3881542 24.0888012
OS 17.18660012 24.0888012
OE
SE
S P 0
OB 17.16718436 25.09506792 I
OS 17.17365628 25.09599248
OS 17.18290188 25.09599248
OS 17.21341236 25.09414336
OS 17.24299828 25.08952056
OS 17.26888596 25.0839732
OS 17.28090524 25.08027496
OS 17.29199996 25.07657672
OS 17.30217012 25.07287848
OS 17.31141572 25.06918024
OS 17.3188122 25.06640656
OS 17.32620868 25.06363288
OS 17.33083148 25.0608592
OS 17.33452972 25.05901008
OS 17.3373034 25.05808552
OS 17.33822796 25.05716096
OS 17.36319108 25.04144344
OS 17.38445596 25.02295224
OS 17.40294716 25.00446104
OS 17.41866468 24.98596984
OS 17.43068396 24.96932776
OS 17.43530676 24.96193128
OS 17.439005 24.95545936
OS 17.44270324 24.95083656
OS 17.44455236 24.94713832
OS 17.44547692 24.94436464
OS 17.44640148 24.94344008
OS 17.45934532 24.91477872
OS 17.46859092 24.8851928
OS 17.47506284 24.85560688
OS 17.47968564 24.82879464
OS 17.48153476 24.81677536
OS 17.48245932 24.80475608
OS 17.48338388 24.79551048
OS 17.48338388 24.78626488
OS 17.48430844 24.77979296
OS 17.48430844 24.7742456
OS 17.48430844 24.77054736
OS 17.48430844 24.7696228
OS 17.48245932 24.73633864
OS 17.47876108 24.70397904
OS 17.47413828 24.67531768
OS 17.47044004 24.66144928
OS 17.46766636 24.64943
OS 17.46489268 24.63833528
OS 17.46119444 24.62816512
OS 17.45842076 24.61891952
OS 17.45657164 24.61152304
OS 17.45379796 24.60597568
OS 17.4528734 24.60135288
OS 17.45102428 24.5985792
OS 17.45102428 24.59765464
OS 17.43715588 24.56991784
OS 17.42143836 24.54495472
OS 17.40479628 24.52368984
OS 17.39647524 24.5153688
OS 17.38907876 24.50704776
OS 17.38168228 24.49965128
OS 17.3742858 24.49317936
OS 17.36781388 24.487632
OS 17.36226652 24.48393376
OS 17.35856828 24.48023552
OS 17.35487004 24.47746184
OS 17.35302092 24.47653728
OS 17.35209636 24.47561272
OS 17.33915252 24.46821624
OS 17.32620868 24.46174432
OS 17.29847188 24.45157416
OS 17.27073508 24.44417768
OS 17.24392284 24.43955488
OS 17.230979 24.43770576
OS 17.21988428 24.43585664
OS 17.20971412 24.43493208
OS 17.20139308 24.43493208
OS 17.1939966 24.43400752
OS 17.18382644 24.43400752
OS 17.16533524 24.43493208
OS 17.1477686 24.4367812
OS 17.13112652 24.43863032
OS 17.115409 24.44232856
OS 17.10061604 24.44695136
OS 17.08674764 24.45157416
OS 17.0738038 24.45619696
OS 17.06178452 24.46174432
OS 17.05161436 24.46636712
OS 17.0414442 24.47098992
OS 17.03404772 24.47561272
OS 17.02665124 24.48023552
OS 17.02202844 24.48393376
OS 17.01740564 24.48578288
OS 17.01555652 24.487632
OS 17.01463196 24.48855656
OS 17.00168812 24.49965128
OS 16.9905934 24.510746
OS 16.98042324 24.52368984
OS 16.97025308 24.53663368
OS 16.953611 24.56252136
OS 16.94066716 24.58840904
OS 16.9351198 24.60042832
OS 16.930497 24.61152304
OS 16.92679876 24.6216932
OS 16.92402508 24.63001424
OS 16.9212514 24.63741072
OS 16.91940228 24.64295808
OS 16.91847772 24.64665632
OS 16.91847772 24.64758088
OS 17.00353724 24.66884576
OS 17.00723548 24.6540528
OS 17.01185828 24.6401844
OS 17.01648108 24.62724056
OS 17.02110388 24.61522128
OS 17.02665124 24.60412656
OS 17.0321986 24.59488096
OS 17.03867052 24.58563536
OS 17.04421788 24.57731432
OS 17.04884068 24.56991784
OS 17.05438804 24.56437048
OS 17.05901084 24.55882312
OS 17.06270908 24.55420032
OS 17.06640732 24.55142664
OS 17.069181 24.54865296
OS 17.07010556 24.5477284
OS 17.07103012 24.54680384
OS 17.08027572 24.53940736
OS 17.09044588 24.53386
OS 17.1107862 24.52368984
OS 17.13020196 24.51629336
OS 17.14961772 24.51167056
OS 17.1662598 24.50797232
OS 17.17273172 24.50704776
OS 17.17920364 24.50704776
OS 17.184751 24.5061232
OS 17.19122292 24.5061232
OS 17.2124878 24.50704776
OS 17.23282812 24.510746
OS 17.25131932 24.5153688
OS 17.2679614 24.52091616
OS 17.28090524 24.52646352
OS 17.2864526 24.5292372
OS 17.2910754 24.53108632
OS 17.29477364 24.53293544
OS 17.29754732 24.53478456
OS 17.29939644 24.53570912
OS 17.300321 24.53570912
OS 17.31788764 24.54865296
OS 17.3326806 24.56252136
OS 17.34562444 24.57823888
OS 17.3557946 24.59303184
OS 17.36411564 24.60597568
OS 17.369663 24.6170704
OS 17.37151212 24.6216932
OS 17.37336124 24.62446688
OS 17.3742858 24.626316
OS 17.3742858 24.62724056
OS 17.38168228 24.65127912
OS 17.38722964 24.67531768
OS 17.39185244 24.69935624
OS 17.39462612 24.72154568
OS 17.39555068 24.73171584
OS 17.39647524 24.74096144
OS 17.39647524 24.74928248
OS 17.3973998 24.7557544
OS 17.3973998 24.76130176
OS 17.3973998 24.76592456
OS 17.3973998 24.76869824
OS 17.3973998 24.7696228
OS 17.39647524 24.79366136
OS 17.39462612 24.8158508
OS 17.39092788 24.83619112
OS 17.38722964 24.85468232
OS 17.38445596 24.87039984
OS 17.38260684 24.87687176
OS 17.38075772 24.88241912
OS 17.37983316 24.88704192
OS 17.3789086 24.8898156
OS 17.37798404 24.89166472
OS 17.37798404 24.89258928
OS 17.36873844 24.91385416
OS 17.35856828 24.93326992
OS 17.34747356 24.94898744
OS 17.33545428 24.96285584
OS 17.32528412 24.97395056
OS 17.31696308 24.98134704
OS 17.31049116 24.98596984
OS 17.3095666 24.98781896
OS 17.30864204 24.98781896
OS 17.28922628 24.99983824
OS 17.2679614 25.00908384
OS 17.24762108 25.01555576
OS 17.22820532 25.019254
OS 17.21063868 25.02202768
OS 17.2032422 25.02295224
OS 17.19677028 25.02295224
OS 17.19214748 25.0238768
OS 17.184751 25.0238768
OS 17.161637 25.02295224
OS 17.14037212 25.019254
OS 17.12280548 25.01370664
OS 17.10708796 25.00815928
OS 17.09506868 25.00168736
OS 17.08582308 24.99706456
OS 17.08027572 24.99336632
OS 17.0784266 24.9915172
OS 17.06363364 24.9776488
OS 17.04976524 24.96193128
OS 17.03867052 24.9452892
OS 17.02942492 24.92864712
OS 17.02202844 24.91385416
OS 17.01925476 24.90645768
OS 17.01740564 24.90091032
OS 17.01555652 24.89628752
OS 17.0137074 24.89258928
OS 17.01278284 24.89074016
OS 17.01278284 24.8898156
OS 16.92957244 24.90923136
OS 16.9351198 24.92587344
OS 16.94066716 24.9406664
OS 16.94806364 24.9545348
OS 16.95453556 24.9684032
OS 16.96193204 24.98042248
OS 16.97025308 24.9915172
OS 16.97764956 25.00261192
OS 16.98504604 25.01185752
OS 16.99244252 25.019254
OS 16.99891444 25.02665048
OS 17.00538636 25.0331224
OS 17.01000916 25.0377452
OS 17.01463196 25.042368
OS 17.0183302 25.04514168
OS 17.02017932 25.04606624
OS 17.02110388 25.0469908
OS 17.03404772 25.05531184
OS 17.04699156 25.06363288
OS 17.0599354 25.0701048
OS 17.0738038 25.07565216
OS 17.1015406 25.0839732
OS 17.12650372 25.08952056
OS 17.138523 25.09229424
OS 17.14869316 25.0932188
OS 17.15886332 25.09414336
OS 17.16718436 25.09506792
OE
OB 16.6346378 25.08674688 I
OS 16.6392606 25.08767144
OS 16.64573252 25.08767144
OS 16.66145004 25.08674688
OS 16.676243 25.08489776
OS 16.69103596 25.08212408
OS 16.7039798 25.07842584
OS 16.72894292 25.06825568
OS 16.74003764 25.06363288
OS 16.74928324 25.05808552
OS 16.75852884 25.0516136
OS 16.76592532 25.0469908
OS 16.7733218 25.04144344
OS 16.77886916 25.03682064
OS 16.78349196 25.0331224
OS 16.78626564 25.03034872
OS 16.78811476 25.0284996
OS 16.78903932 25.02757504
OS 16.79920948 25.01648032
OS 16.80753052 25.00353648
OS 16.81585156 24.9915172
OS 16.82232348 24.97857336
OS 16.82787084 24.96470496
OS 16.83249364 24.95176112
OS 16.83896556 24.92772256
OS 16.84173924 24.91570328
OS 16.84358836 24.90553312
OS 16.84451292 24.89536296
OS 16.84543748 24.88704192
OS 16.84636204 24.88057
OS 16.84636204 24.8759472
OS 16.84636204 24.87224896
OS 16.84636204 24.8713244
OS 16.84543748 24.85375776
OS 16.84358836 24.83804024
OS 16.84173924 24.82232272
OS 16.838041 24.80752976
OS 16.8334182 24.79458592
OS 16.8287954 24.78164208
OS 16.8241726 24.77054736
OS 16.81862524 24.7603772
OS 16.81400244 24.7511316
OS 16.80937964 24.74281056
OS 16.80475684 24.73633864
OS 16.80013404 24.72986672
OS 16.7964358 24.72524392
OS 16.79458668 24.72247024
OS 16.79273756 24.72062112
OS 16.791813 24.71969656
OS 16.78164284 24.7095264
OS 16.77054812 24.70120536
OS 16.7594534 24.69288432
OS 16.74743412 24.6864124
OS 16.7363394 24.68086504
OS 16.72524468 24.67624224
OS 16.7039798 24.66977032
OS 16.6947342 24.66699664
OS 16.6854886 24.66514752
OS 16.67809212 24.66422296
OS 16.67069564 24.6632984
OS 16.66514828 24.66237384
OS 16.6577518 24.66237384
OS 16.64018516 24.6632984
OS 16.62354308 24.66607208
OS 16.60875012 24.66977032
OS 16.59488172 24.67439312
OS 16.58471156 24.67809136
OS 16.57639052 24.6817896
OS 16.57084316 24.68456328
OS 16.56899404 24.68548784
OS 16.55420108 24.69473344
OS 16.54125724 24.7049036
OS 16.53016252 24.71507376
OS 16.52091692 24.72431936
OS 16.514445 24.73356496
OS 16.50889764 24.74003688
OS 16.5051994 24.74465968
OS 16.50427484 24.7465088
OS 16.50427484 24.73911232
OS 16.50427484 24.73448952
OS 16.50427484 24.73171584
OS 16.50427484 24.73079128
OS 16.5051994 24.71230008
OS 16.50612396 24.69473344
OS 16.50797308 24.67901592
OS 16.5098222 24.66422296
OS 16.51259588 24.65220368
OS 16.514445 24.64295808
OS 16.51536956 24.63925984
OS 16.51536956 24.63648616
OS 16.51629412 24.6355616
OS 16.51629412 24.63463704
OS 16.52091692 24.61799496
OS 16.52553972 24.603202
OS 16.53016252 24.59025816
OS 16.53478532 24.57916344
OS 16.53848356 24.5708424
OS 16.5421818 24.56437048
OS 16.54403092 24.55974768
OS 16.54495548 24.55882312
OS 16.55235196 24.54865296
OS 16.55974844 24.54033192
OS 16.56714492 24.53293544
OS 16.5745414 24.52646352
OS 16.58008876 24.52091616
OS 16.58563612 24.51721792
OS 16.58933436 24.5153688
OS 16.59025892 24.51444424
OS 16.60042908 24.50889688
OS 16.6115238 24.50519864
OS 16.62169396 24.50242496
OS 16.63186412 24.50057584
OS 16.64018516 24.49965128
OS 16.64665708 24.49872672
OS 16.653129 24.49872672
OS 16.66792196 24.49965128
OS 16.68179036 24.50242496
OS 16.69380964 24.5061232
OS 16.7039798 24.510746
OS 16.71137628 24.51444424
OS 16.7178482 24.51814248
OS 16.72154644 24.52091616
OS 16.722471 24.52184072
OS 16.7317166 24.53201088
OS 16.73911308 24.54403016
OS 16.745585 24.556974
OS 16.7502078 24.56991784
OS 16.75390604 24.58101256
OS 16.75667972 24.59118272
OS 16.75760428 24.59488096
OS 16.75760428 24.59673008
OS 16.75852884 24.5985792
OS 16.75852884 24.59950376
OS 16.83434276 24.59303184
OS 16.8287954 24.5662196
OS 16.82139892 24.5431056
OS 16.81215332 24.52276528
OS 16.80290772 24.5061232
OS 16.79366212 24.49317936
OS 16.78903932 24.487632
OS 16.78534108 24.4830092
OS 16.7825674 24.48023552
OS 16.77979372 24.47746184
OS 16.77886916 24.47653728
OS 16.7779446 24.47561272
OS 16.768699 24.46821624
OS 16.75852884 24.46174432
OS 16.73818852 24.45157416
OS 16.7178482 24.44417768
OS 16.69843244 24.43955488
OS 16.6808658 24.43585664
OS 16.67346932 24.43493208
OS 16.6669974 24.43493208
OS 16.6623746 24.43400752
OS 16.65497812 24.43400752
OS 16.62909044 24.43585664
OS 16.60597644 24.43955488
OS 16.58471156 24.4460268
OS 16.56714492 24.45342328
OS 16.55974844 24.45619696
OS 16.55235196 24.4598952
OS 16.5468046 24.46359344
OS 16.54125724 24.46636712
OS 16.537559 24.46821624
OS 16.53478532 24.47006536
OS 16.5329362 24.47191448
OS 16.53201164 24.47191448
OS 16.51352044 24.487632
OS 16.49687836 24.50519864
OS 16.48393452 24.52368984
OS 16.4728398 24.54125648
OS 16.4635942 24.556974
OS 16.45989596 24.56437048
OS 16.45712228 24.56991784
OS 16.45527316 24.5754652
OS 16.45342404 24.57916344
OS 16.45249948 24.58101256
OS 16.45249948 24.58193712
OS 16.44787668 24.59580552
OS 16.44325388 24.61152304
OS 16.43678196 24.64295808
OS 16.43215916 24.67624224
OS 16.42938548 24.70767728
OS 16.42753636 24.72154568
OS 16.4266118 24.73541408
OS 16.4266118 24.74743336
OS 16.42568724 24.75760352
OS 16.42568724 24.76592456
OS 16.42568724 24.77239648
OS 16.42568724 24.77701928
OS 16.42568724 24.77794384
OS 16.42568724 24.79920872
OS 16.4266118 24.81954904
OS 16.42846092 24.83804024
OS 16.43031004 24.85560688
OS 16.43215916 24.8713244
OS 16.43400828 24.88611736
OS 16.43678196 24.89998576
OS 16.43955564 24.91200504
OS 16.44232932 24.9221752
OS 16.44417844 24.9314208
OS 16.44695212 24.93974184
OS 16.44880124 24.94621376
OS 16.45065036 24.95083656
OS 16.45249948 24.9545348
OS 16.45342404 24.95638392
OS 16.45342404 24.95730848
OS 16.46451876 24.97949792
OS 16.47653804 24.99891368
OS 16.49040644 25.01555576
OS 16.50242572 25.02942416
OS 16.514445 25.03959432
OS 16.5236906 25.0469908
OS 16.52738884 25.04976448
OS 16.53016252 25.0516136
OS 16.53108708 25.05346272
OS 16.53201164 25.05346272
OS 16.5514274 25.06455744
OS 16.57084316 25.07287848
OS 16.59025892 25.0793504
OS 16.60782556 25.08304864
OS 16.62354308 25.08582232
OS 16.630015 25.08674688
OS 16.6346378 25.08674688
OE
OB 16.62631676 25.02295224 H
OS 16.61707116 25.02110312
OS 16.60042908 25.01648032
OS 16.58563612 25.0100084
OS 16.57269228 25.00353648
OS 16.56252212 24.99614
OS 16.55512564 24.98966808
OS 16.55050284 24.98504528
OS 16.54865372 24.98412072
OS 16.54865372 24.98319616
OS 16.53663444 24.96747864
OS 16.52738884 24.949912
OS 16.52091692 24.9314208
OS 16.51721868 24.91385416
OS 16.514445 24.8990612
OS 16.51352044 24.89258928
OS 16.51352044 24.88611736
OS 16.51259588 24.88149456
OS 16.51259588 24.87779632
OS 16.51259588 24.8759472
OS 16.51259588 24.87502264
OS 16.514445 24.85098408
OS 16.51814324 24.8297192
OS 16.5236906 24.81215256
OS 16.53016252 24.7973596
OS 16.537559 24.78534032
OS 16.54310636 24.77701928
OS 16.5468046 24.77147192
OS 16.54865372 24.7696228
OS 16.56252212 24.75667896
OS 16.57731508 24.74743336
OS 16.59210804 24.74096144
OS 16.606901 24.73633864
OS 16.61892028 24.73356496
OS 16.62909044 24.7326404
OS 16.63278868 24.73171584
OS 16.63833604 24.73171584
OS 16.6577518 24.73356496
OS 16.67531844 24.7372632
OS 16.69103596 24.74373512
OS 16.70490436 24.7511316
OS 16.71507452 24.75760352
OS 16.72339556 24.76407544
OS 16.72801836 24.76777368
OS 16.72986748 24.7696228
OS 16.74188676 24.78441576
OS 16.75113236 24.80105784
OS 16.75667972 24.81769992
OS 16.76130252 24.83341744
OS 16.7640762 24.84728584
OS 16.76500076 24.8528332
OS 16.76500076 24.85838056
OS 16.76592532 24.86300336
OS 16.76592532 24.86577704
OS 16.76592532 24.86762616
OS 16.76592532 24.86855072
OS 16.7640762 24.89258928
OS 16.76037796 24.91477872
OS 16.75390604 24.93419448
OS 16.74650956 24.949912
OS 16.74003764 24.96285584
OS 16.73356572 24.97210144
OS 16.7317166 24.97487512
OS 16.72986748 24.9776488
OS 16.72801836 24.97857336
OS 16.72801836 24.97949792
OS 16.72062188 24.9868944
OS 16.7132254 24.99429088
OS 16.69750788 25.00446104
OS 16.68179036 25.01278208
OS 16.6669974 25.01740488
OS 16.65497812 25.02110312
OS 16.64480796 25.02202768
OS 16.64110972 25.02295224
OS 16.62631676 25.02295224
OE
SE
S P 0
OB 19.33922472 22.53186756 I
OS 19.34569664 22.53279212
OS 19.35494224 22.53279212
OS 19.38545272 22.530943
OS 19.41503864 22.5263202
OS 19.44092632 22.52077284
OS 19.4529456 22.5170746
OS 19.46404032 22.51337636
OS 19.47421048 22.50967812
OS 19.48345608 22.50597988
OS 19.49085256 22.5032062
OS 19.49824904 22.50043252
OS 19.50287184 22.49765884
OS 19.50657008 22.49580972
OS 19.50934376 22.49488516
OS 19.51026832 22.4939606
OS 19.53523144 22.47824308
OS 19.55649632 22.45975188
OS 19.57498752 22.44126068
OS 19.59070504 22.42276948
OS 19.60272432 22.4061274
OS 19.60734712 22.39873092
OS 19.61104536 22.392259
OS 19.6147436 22.3876362
OS 19.61659272 22.38393796
OS 19.61751728 22.38116428
OS 19.61844184 22.38023972
OS 19.63138568 22.35157836
OS 19.64063128 22.32199244
OS 19.6471032 22.29240652
OS 19.651726 22.26559428
OS 19.65357512 22.253575
OS 19.65449968 22.24155572
OS 19.65542424 22.23231012
OS 19.65542424 22.22306452
OS 19.6563488 22.2165926
OS 19.6563488 22.21104524
OS 19.6563488 22.207347
OS 19.6563488 22.20642244
OS 19.65449968 22.17313828
OS 19.65080144 22.14077868
OS 19.64617864 22.11211732
OS 19.6424804 22.09824892
OS 19.63970672 22.08622964
OS 19.63693304 22.07513492
OS 19.6332348 22.06496476
OS 19.63046112 22.05571916
OS 19.628612 22.04832268
OS 19.62583832 22.04277532
OS 19.62491376 22.03815252
OS 19.62306464 22.03537884
OS 19.62306464 22.03445428
OS 19.60919624 22.00671748
OS 19.59347872 21.98175436
OS 19.57683664 21.96048948
OS 19.5685156 21.95216844
OS 19.56111912 21.9438474
OS 19.55372264 21.93645092
OS 19.54632616 21.929979
OS 19.53985424 21.92443164
OS 19.53430688 21.9207334
OS 19.53060864 21.91703516
OS 19.5269104 21.91426148
OS 19.52506128 21.91333692
OS 19.52413672 21.91241236
OS 19.51119288 21.90501588
OS 19.49824904 21.89854396
OS 19.47051224 21.8883738
OS 19.44277544 21.88097732
OS 19.4159632 21.87635452
OS 19.40301936 21.8745054
OS 19.39192464 21.87265628
OS 19.38175448 21.87173172
OS 19.37343344 21.87173172
OS 19.36603696 21.87080716
OS 19.3558668 21.87080716
OS 19.3373756 21.87173172
OS 19.31980896 21.87358084
OS 19.30316688 21.87542996
OS 19.28744936 21.8791282
OS 19.2726564 21.883751
OS 19.258788 21.8883738
OS 19.24584416 21.8929966
OS 19.23382488 21.89854396
OS 19.22365472 21.90316676
OS 19.21348456 21.90778956
OS 19.20608808 21.91241236
OS 19.1986916 21.91703516
OS 19.1940688 21.9207334
OS 19.189446 21.92258252
OS 19.18759688 21.92443164
OS 19.18667232 21.9253562
OS 19.17372848 21.93645092
OS 19.16263376 21.94754564
OS 19.1524636 21.96048948
OS 19.14229344 21.97343332
OS 19.12565136 21.999321
OS 19.11270752 22.02520868
OS 19.10716016 22.03722796
OS 19.10253736 22.04832268
OS 19.09883912 22.05849284
OS 19.09606544 22.06681388
OS 19.09329176 22.07421036
OS 19.09144264 22.07975772
OS 19.09051808 22.08345596
OS 19.09051808 22.08438052
OS 19.1755776 22.1056454
OS 19.17927584 22.09085244
OS 19.18389864 22.07698404
OS 19.18852144 22.0640402
OS 19.19314424 22.05202092
OS 19.1986916 22.0409262
OS 19.20423896 22.0316806
OS 19.21071088 22.022435
OS 19.21625824 22.01411396
OS 19.22088104 22.00671748
OS 19.2264284 22.00117012
OS 19.2310512 21.99562276
OS 19.23474944 21.99099996
OS 19.23844768 21.98822628
OS 19.24122136 21.9854526
OS 19.24214592 21.98452804
OS 19.24307048 21.98360348
OS 19.25231608 21.976207
OS 19.26248624 21.97065964
OS 19.28282656 21.96048948
OS 19.30224232 21.953093
OS 19.32165808 21.9484702
OS 19.33830016 21.94477196
OS 19.34477208 21.9438474
OS 19.351244 21.9438474
OS 19.35679136 21.94292284
OS 19.36326328 21.94292284
OS 19.38452816 21.9438474
OS 19.40486848 21.94754564
OS 19.42335968 21.95216844
OS 19.44000176 21.9577158
OS 19.4529456 21.96326316
OS 19.45849296 21.96603684
OS 19.46311576 21.96788596
OS 19.466814 21.96973508
OS 19.46958768 21.9715842
OS 19.4714368 21.97250876
OS 19.47236136 21.97250876
OS 19.489928 21.9854526
OS 19.50472096 21.999321
OS 19.5176648 22.01503852
OS 19.52783496 22.02983148
OS 19.536156 22.04277532
OS 19.54170336 22.05387004
OS 19.54355248 22.05849284
OS 19.5454016 22.06126652
OS 19.54632616 22.06311564
OS 19.54632616 22.0640402
OS 19.55372264 22.08807876
OS 19.55927 22.11211732
OS 19.5638928 22.13615588
OS 19.56666648 22.15834532
OS 19.56759104 22.16851548
OS 19.5685156 22.17776108
OS 19.5685156 22.18608212
OS 19.56944016 22.19255404
OS 19.56944016 22.1981014
OS 19.56944016 22.2027242
OS 19.56944016 22.20549788
OS 19.56944016 22.20642244
OS 19.5685156 22.230461
OS 19.56666648 22.25265044
OS 19.56296824 22.27299076
OS 19.55927 22.29148196
OS 19.55649632 22.30719948
OS 19.5546472 22.3136714
OS 19.55279808 22.31921876
OS 19.55187352 22.32384156
OS 19.55094896 22.32661524
OS 19.5500244 22.32846436
OS 19.5500244 22.32938892
OS 19.5407788 22.3506538
OS 19.53060864 22.37006956
OS 19.51951392 22.38578708
OS 19.50749464 22.39965548
OS 19.49732448 22.4107502
OS 19.48900344 22.41814668
OS 19.48253152 22.42276948
OS 19.48160696 22.4246186
OS 19.4806824 22.4246186
OS 19.46126664 22.43663788
OS 19.44000176 22.44588348
OS 19.41966144 22.4523554
OS 19.40024568 22.45605364
OS 19.38267904 22.45882732
OS 19.37528256 22.45975188
OS 19.36881064 22.45975188
OS 19.36418784 22.46067644
OS 19.35679136 22.46067644
OS 19.33367736 22.45975188
OS 19.31241248 22.45605364
OS 19.29484584 22.45050628
OS 19.27912832 22.44495892
OS 19.26710904 22.438487
OS 19.25786344 22.4338642
OS 19.25231608 22.43016596
OS 19.25046696 22.42831684
OS 19.235674 22.41444844
OS 19.2218056 22.39873092
OS 19.21071088 22.38208884
OS 19.20146528 22.36544676
OS 19.1940688 22.3506538
OS 19.19129512 22.34325732
OS 19.189446 22.33770996
OS 19.18759688 22.33308716
OS 19.18574776 22.32938892
OS 19.1848232 22.3275398
OS 19.1848232 22.32661524
OS 19.1016128 22.346031
OS 19.10716016 22.36267308
OS 19.11270752 22.37746604
OS 19.120104 22.39133444
OS 19.12657592 22.40520284
OS 19.1339724 22.41722212
OS 19.14229344 22.42831684
OS 19.14968992 22.43941156
OS 19.1570864 22.44865716
OS 19.16448288 22.45605364
OS 19.1709548 22.46345012
OS 19.17742672 22.46992204
OS 19.18204952 22.47454484
OS 19.18667232 22.47916764
OS 19.19037056 22.48194132
OS 19.19221968 22.48286588
OS 19.19314424 22.48379044
OS 19.20608808 22.49211148
OS 19.21903192 22.50043252
OS 19.23197576 22.50690444
OS 19.24584416 22.5124518
OS 19.27358096 22.52077284
OS 19.29854408 22.5263202
OS 19.31056336 22.52909388
OS 19.32073352 22.53001844
OS 19.33090368 22.530943
OS 19.33922472 22.53186756
OE
OB 18.79835712 22.52354652 I
OS 18.80852728 22.52447108
OS 18.83164128 22.52447108
OS 18.84458512 22.52262196
OS 18.86954824 22.51799916
OS 18.89081312 22.51060268
OS 18.90930432 22.5032062
OS 18.91762536 22.4985834
OS 18.92409728 22.49488516
OS 18.9305692 22.49118692
OS 18.935192 22.48748868
OS 18.93889024 22.484715
OS 18.94166392 22.48286588
OS 18.94351304 22.48194132
OS 18.9444376 22.48101676
OS 18.96200424 22.46345012
OS 18.97587264 22.44403436
OS 18.98696736 22.42369404
OS 18.99621296 22.40335372
OS 19.00176032 22.38578708
OS 19.004534 22.3783906
OS 19.00638312 22.37191868
OS 19.00730768 22.36637132
OS 19.00823224 22.36267308
OS 19.0091568 22.3598994
OS 19.0091568 22.35897484
OS 18.9305692 22.34510644
OS 18.92687096 22.36544676
OS 18.9213236 22.3830134
OS 18.91485168 22.39780636
OS 18.90837976 22.40982564
OS 18.90190784 22.41907124
OS 18.89636048 22.42554316
OS 18.89266224 22.43016596
OS 18.89173768 22.43109052
OS 18.8797184 22.44033612
OS 18.86677456 22.4477326
OS 18.85475528 22.4523554
OS 18.842736 22.45605364
OS 18.83164128 22.45790276
OS 18.82332024 22.45975188
OS 18.81592376 22.45975188
OS 18.79928168 22.45882732
OS 18.78448872 22.45512908
OS 18.77154488 22.45050628
OS 18.76045016 22.44588348
OS 18.75212912 22.44033612
OS 18.7456572 22.43571332
OS 18.7410344 22.43201508
OS 18.74010984 22.43109052
OS 18.72993968 22.4199958
OS 18.7225432 22.40797652
OS 18.7179204 22.39595724
OS 18.71422216 22.38486252
OS 18.71237304 22.37469236
OS 18.71052392 22.36729588
OS 18.71052392 22.36174852
OS 18.71052392 22.36082396
OS 18.71052392 22.3598994
OS 18.71052392 22.34972924
OS 18.71237304 22.34048364
OS 18.71699584 22.32476612
OS 18.72346776 22.31089772
OS 18.73086424 22.29887844
OS 18.73826072 22.2905574
OS 18.74473264 22.28408548
OS 18.74935544 22.28038724
OS 18.75028 22.27946268
OS 18.75120456 22.27946268
OS 18.76692208 22.27114164
OS 18.78171504 22.26466972
OS 18.79743256 22.26004692
OS 18.81130096 22.25727324
OS 18.82332024 22.25542412
OS 18.8334904 22.253575
OS 18.84550968 22.253575
OS 18.84920792 22.25449956
OS 18.85383072 22.25449956
OS 18.86307632 22.18515756
OS 18.85105704 22.18793124
OS 18.83996232 22.18978036
OS 18.83071672 22.19162948
OS 18.82239568 22.19255404
OS 18.81592376 22.1934786
OS 18.80760272 22.1934786
OS 18.78818696 22.19162948
OS 18.77062032 22.18793124
OS 18.7549028 22.18238388
OS 18.74195896 22.17591196
OS 18.7317888 22.16944004
OS 18.72439232 22.16389268
OS 18.71976952 22.16019444
OS 18.7179204 22.15834532
OS 18.70590112 22.14447692
OS 18.69665552 22.12968396
OS 18.6901836 22.114891
OS 18.68648536 22.10009804
OS 18.68371168 22.08807876
OS 18.68278712 22.0779086
OS 18.68186256 22.07421036
OS 18.68186256 22.07143668
OS 18.68186256 22.06958756
OS 18.68186256 22.068663
OS 18.68371168 22.04832268
OS 18.68833448 22.02983148
OS 18.69388184 22.01411396
OS 18.70127832 22.00024556
OS 18.7086748 21.98915084
OS 18.71422216 21.9808298
OS 18.71884496 21.97528244
OS 18.72069408 21.97343332
OS 18.73548704 21.96048948
OS 18.75120456 21.95124388
OS 18.76692208 21.94477196
OS 18.78171504 21.94014916
OS 18.79465888 21.93737548
OS 18.80482904 21.93645092
OS 18.80852728 21.93552636
OS 18.81407464 21.93552636
OS 18.83071672 21.93645092
OS 18.84643424 21.94014916
OS 18.86030264 21.94477196
OS 18.87139736 21.95031932
OS 18.88064296 21.95494212
OS 18.88803944 21.95956492
OS 18.89173768 21.96326316
OS 18.8935868 21.96418772
OS 18.90468152 21.97713156
OS 18.91392712 21.99192452
OS 18.92224816 22.00764204
OS 18.92872008 22.02428412
OS 18.93334288 22.03815252
OS 18.935192 22.04462444
OS 18.93611656 22.0501718
OS 18.93704112 22.0547946
OS 18.93796568 22.05849284
OS 18.93889024 22.06034196
OS 18.93889024 22.06126652
OS 19.01747784 22.05109636
OS 19.01562872 22.0363034
OS 19.01285504 22.022435
OS 19.004534 21.99654732
OS 18.99436384 21.97435788
OS 18.98881648 21.96511228
OS 18.98326912 21.95586668
OS 18.97772176 21.94754564
OS 18.9721744 21.94107372
OS 18.9675516 21.9346018
OS 18.9629288 21.929979
OS 18.96015512 21.92628076
OS 18.95738144 21.92350708
OS 18.95553232 21.92165796
OS 18.95460776 21.9207334
OS 18.94351304 21.91241236
OS 18.93241832 21.90409132
OS 18.9213236 21.8976194
OS 18.90930432 21.89207204
OS 18.88619032 21.88282644
OS 18.86400088 21.87727908
OS 18.85383072 21.87542996
OS 18.84458512 21.87358084
OS 18.83626408 21.87265628
OS 18.8288676 21.87173172
OS 18.82332024 21.87080716
OS 18.8149992 21.87080716
OS 18.79743256 21.87173172
OS 18.78171504 21.87358084
OS 18.76599752 21.87635452
OS 18.75120456 21.88005276
OS 18.73733616 21.88467556
OS 18.72531688 21.88929836
OS 18.7132976 21.89484572
OS 18.70312744 21.90039308
OS 18.69295728 21.90501588
OS 18.68463624 21.91056324
OS 18.67723976 21.91518604
OS 18.6716924 21.91980884
OS 18.6670696 21.92350708
OS 18.66337136 21.92628076
OS 18.66152224 21.92812988
OS 18.66059768 21.92905444
OS 18.64950296 21.94014916
OS 18.64025736 21.95216844
OS 18.63193632 21.96418772
OS 18.62453984 21.976207
OS 18.61899248 21.98730172
OS 18.61344512 21.999321
OS 18.60604864 22.02151044
OS 18.60419952 22.0316806
OS 18.6023504 22.0409262
OS 18.60050128 22.04924724
OS 18.59957672 22.05664372
OS 18.59865216 22.06219108
OS 18.59865216 22.06681388
OS 18.59865216 22.06958756
OS 18.59865216 22.07051212
OS 18.59957672 22.09270156
OS 18.60327496 22.11304188
OS 18.60882232 22.13060852
OS 18.61436968 22.14540148
OS 18.61991704 22.15742076
OS 18.6254644 22.16666636
OS 18.62916264 22.17221372
OS 18.6300872 22.17406284
OS 18.64303104 22.18793124
OS 18.65689944 22.19995052
OS 18.6716924 22.20919612
OS 18.68648536 22.2165926
OS 18.6994292 22.22213996
OS 18.70959936 22.2258382
OS 18.7132976 22.22676276
OS 18.71607128 22.22768732
OS 18.7179204 22.22861188
OS 18.71884496 22.22861188
OS 18.70312744 22.23693292
OS 18.6901836 22.24525396
OS 18.67908888 22.25449956
OS 18.66984328 22.2628206
OS 18.6624468 22.27021708
OS 18.65689944 22.276689
OS 18.65412576 22.28038724
OS 18.6532012 22.28223636
OS 18.64580472 22.2951802
OS 18.64025736 22.30812404
OS 18.63563456 22.32106788
OS 18.63286088 22.33308716
OS 18.63101176 22.34325732
OS 18.6300872 22.3506538
OS 18.6300872 22.35620116
OS 18.6300872 22.35805028
OS 18.63101176 22.3737678
OS 18.63378544 22.38948532
OS 18.63748368 22.40335372
OS 18.64210648 22.415373
OS 18.64672928 22.42554316
OS 18.65042752 22.4338642
OS 18.6532012 22.438487
OS 18.65412576 22.44033612
OS 18.66337136 22.45420452
OS 18.67446608 22.4662238
OS 18.6855608 22.47639396
OS 18.69665552 22.48563956
OS 18.70590112 22.49211148
OS 18.71422216 22.49765884
OS 18.71976952 22.50043252
OS 18.72069408 22.50135708
OS 18.72161864 22.50135708
OS 18.73826072 22.50875356
OS 18.7549028 22.51430092
OS 18.77154488 22.51892372
OS 18.78633784 22.5216974
OS 18.79835712 22.52354652
OE
SE
S P 0
OB 20.32367284 38.3026666 I
OS 20.32367284 38.73905892
OS 20.40873236 38.73905892
OS 20.40873236 38.2980438
OS 20.40873236 38.27862804
OS 20.41058148 38.26198596
OS 20.41150604 38.24811756
OS 20.41335516 38.23702284
OS 20.41520428 38.2287018
OS 20.41612884 38.22222988
OS 20.41797796 38.21853164
OS 20.41797796 38.21760708
OS 20.4216762 38.20836148
OS 20.426299 38.200965
OS 20.43184636 38.19449308
OS 20.43646916 38.18802116
OS 20.44201652 38.18432292
OS 20.44571476 38.18062468
OS 20.44848844 38.17877556
OS 20.449413 38.177851
OS 20.4586586 38.1732282
OS 20.4679042 38.16952996
OS 20.4771498 38.16768084
OS 20.48547084 38.16583172
OS 20.49379188 38.16490716
OS 20.49933924 38.1639826
OS 20.5048866 38.1639826
OS 20.51967956 38.16490716
OS 20.53354796 38.1686054
OS 20.54464268 38.17230364
OS 20.55481284 38.177851
OS 20.56220932 38.1824738
OS 20.56775668 38.1870966
OS 20.57145492 38.18987028
OS 20.57237948 38.19079484
OS 20.57700228 38.1963422
OS 20.58070052 38.20281412
OS 20.58624788 38.21760708
OS 20.59179524 38.23424916
OS 20.59456892 38.25089124
OS 20.5973426 38.26660876
OS 20.5973426 38.27308068
OS 20.59826716 38.27862804
OS 20.59919172 38.2841754
OS 20.59919172 38.28787364
OS 20.59919172 38.28972276
OS 20.59919172 38.29064732
OS 20.6759302 38.2795526
OS 20.6759302 38.26198596
OS 20.67500564 38.24626844
OS 20.67223196 38.23055092
OS 20.67038284 38.21668252
OS 20.6666846 38.20373868
OS 20.66298636 38.19264396
OS 20.65928812 38.18154924
OS 20.65558988 38.17230364
OS 20.65096708 38.1639826
OS 20.64726884 38.15658612
OS 20.6435706 38.1501142
OS 20.63987236 38.1454914
OS 20.63709868 38.14179316
OS 20.63524956 38.13809492
OS 20.634325 38.13717036
OS 20.63340044 38.1362458
OS 20.62415484 38.12792476
OS 20.61490924 38.12052828
OS 20.60473908 38.11405636
OS 20.59364436 38.108509
OS 20.57237948 38.10018796
OS 20.55203916 38.0946406
OS 20.5326234 38.09094236
OS 20.52522692 38.0900178
OS 20.51783044 38.08909324
OS 20.51228308 38.08816868
OS 20.50396204 38.08816868
OS 20.48362172 38.08909324
OS 20.46513052 38.09186692
OS 20.44848844 38.09556516
OS 20.43369548 38.10018796
OS 20.4216762 38.1038862
OS 20.41335516 38.10758444
OS 20.4078078 38.11035812
OS 20.40595868 38.11128268
OS 20.39116572 38.12052828
OS 20.37822188 38.131623
OS 20.36805172 38.14271772
OS 20.35880612 38.15288788
OS 20.3523342 38.16305804
OS 20.3477114 38.17045452
OS 20.34493772 38.17600188
OS 20.34401316 38.17692644
OS 20.34401316 38.177851
OS 20.33754124 38.1963422
OS 20.33199388 38.21575796
OS 20.32829564 38.23702284
OS 20.32644652 38.25736316
OS 20.3245974 38.2749298
OS 20.3245974 38.28232628
OS 20.32367284 38.28972276
OS 20.32367284 38.29527012
OS 20.32367284 38.29896836
OS 20.32367284 38.30174204
OS 20.32367284 38.3026666
OE
OB 19.98990668 38.74090804 I
OS 19.9963786 38.7418326
OS 20.0056242 38.7418326
OS 20.02226628 38.74090804
OS 20.0379838 38.73998348
OS 20.05277676 38.7372098
OS 20.06664516 38.73443612
OS 20.079589 38.73073788
OS 20.09160828 38.72703964
OS 20.102703 38.72241684
OS 20.11287316 38.71779404
OS 20.12211876 38.71317124
OS 20.12951524 38.70854844
OS 20.13598716 38.7048502
OS 20.14153452 38.70115196
OS 20.14615732 38.69837828
OS 20.148931 38.6956046
OS 20.15078012 38.69468004
OS 20.15170468 38.69375548
OS 20.16095028 38.68450988
OS 20.16927132 38.67433972
OS 20.17759236 38.663245
OS 20.18406428 38.65215028
OS 20.195159 38.62996084
OS 20.20255548 38.6077714
OS 20.20532916 38.59760124
OS 20.20810284 38.58743108
OS 20.20995196 38.57911004
OS 20.21180108 38.57171356
OS 20.21272564 38.56524164
OS 20.21272564 38.56061884
OS 20.2136502 38.55784516
OS 20.2136502 38.5569206
OS 20.13321348 38.54859956
OS 20.13136436 38.56986444
OS 20.12766612 38.58835564
OS 20.12211876 38.60499772
OS 20.11564684 38.61794156
OS 20.11009948 38.62903628
OS 20.10455212 38.63643276
OS 20.10085388 38.64105556
OS 20.09900476 38.64290468
OS 20.08513636 38.6539994
OS 20.0703434 38.66232044
OS 20.05462588 38.66879236
OS 20.04075748 38.6724906
OS 20.02781364 38.67526428
OS 20.01671892 38.67618884
OS 20.01302068 38.6771134
OS 20.00747332 38.6771134
OS 19.98805756 38.67618884
OS 19.97049092 38.6724906
OS 19.95569796 38.66694324
OS 19.94275412 38.66139588
OS 19.93258396 38.65492396
OS 19.92611204 38.65030116
OS 19.92148924 38.64660292
OS 19.91964012 38.6447538
OS 19.9085454 38.63180996
OS 19.90022436 38.61886612
OS 19.89375244 38.60592228
OS 19.8900542 38.59297844
OS 19.88728052 38.58280828
OS 19.88635596 38.57356268
OS 19.8854314 38.56801532
OS 19.8854314 38.56709076
OS 19.8854314 38.5661662
OS 19.88728052 38.54952412
OS 19.89097876 38.53195748
OS 19.89745068 38.51623996
OS 19.9039226 38.501447
OS 19.91131908 38.48942772
OS 19.917791 38.47925756
OS 19.91964012 38.47555932
OS 19.92148924 38.47278564
OS 19.92333836 38.47186108
OS 19.92333836 38.47093652
OS 19.93073484 38.46076636
OS 19.93998044 38.4505962
OS 19.9501506 38.43950148
OS 19.96124532 38.42840676
OS 19.98435932 38.40621732
OS 20.00747332 38.38402788
OS 20.0194926 38.37385772
OS 20.02966276 38.36461212
OS 20.03983292 38.35629108
OS 20.04815396 38.3488946
OS 20.05462588 38.34334724
OS 20.06017324 38.33872444
OS 20.06387148 38.33595076
OS 20.06479604 38.3350262
OS 20.08791004 38.31561044
OS 20.10917492 38.29711924
OS 20.12674156 38.28047716
OS 20.14060996 38.26660876
OS 20.15262924 38.25458948
OS 20.16095028 38.24626844
OS 20.16557308 38.24072108
OS 20.1674222 38.23979652
OS 20.1674222 38.23887196
OS 20.18036604 38.22315444
OS 20.1905362 38.20836148
OS 20.1997818 38.19356852
OS 20.20717828 38.18062468
OS 20.21272564 38.16952996
OS 20.21642388 38.16120892
OS 20.218273 38.15566156
OS 20.21919756 38.154737
OS 20.21919756 38.15381244
OS 20.2228958 38.14364228
OS 20.22474492 38.13439668
OS 20.22659404 38.12515108
OS 20.2275186 38.11683004
OS 20.22844316 38.10943356
OS 20.22844316 38.1038862
OS 20.22844316 38.10018796
OS 20.22844316 38.0992634
OS 19.80407012 38.0992634
OS 19.80407012 38.17507732
OS 20.11934508 38.17507732
OS 20.10825036 38.19079484
OS 20.102703 38.19726676
OS 20.0980802 38.20373868
OS 20.0934574 38.20928604
OS 20.08975916 38.21298428
OS 20.08698548 38.21575796
OS 20.08606092 38.21668252
OS 20.08143812 38.22130532
OS 20.07589076 38.22592812
OS 20.06294692 38.2379474
OS 20.04815396 38.2518158
OS 20.03243644 38.2656842
OS 20.01764348 38.27770348
OS 20.01117156 38.28325084
OS 20.0056242 38.2887982
OS 20.0010014 38.29249644
OS 19.99730316 38.29527012
OS 19.99545404 38.29711924
OS 19.99452948 38.2980438
OS 19.97973652 38.31098764
OS 19.96494356 38.32300692
OS 19.95199972 38.3350262
OS 19.93998044 38.34519636
OS 19.92888572 38.35536652
OS 19.91964012 38.36461212
OS 19.91039452 38.37293316
OS 19.90299804 38.38032964
OS 19.89560156 38.38772612
OS 19.8900542 38.39327348
OS 19.8854314 38.39789628
OS 19.8808086 38.40251908
OS 19.8761858 38.40806644
OS 19.87433668 38.40991556
OS 19.86139284 38.42563308
OS 19.85029812 38.43950148
OS 19.84105252 38.45336988
OS 19.83365604 38.4644646
OS 19.82810868 38.47463476
OS 19.82441044 38.48203124
OS 19.82256132 38.48665404
OS 19.82163676 38.48850316
OS 19.8160894 38.50237156
OS 19.81239116 38.51623996
OS 19.80869292 38.5291838
OS 19.8068438 38.54027852
OS 19.80591924 38.55044868
OS 19.80499468 38.55784516
OS 19.80499468 38.56246796
OS 19.80499468 38.56431708
OS 19.80591924 38.57818548
OS 19.80776836 38.59112932
OS 19.80961748 38.60407316
OS 19.81331572 38.61516788
OS 19.82256132 38.63735732
OS 19.83180692 38.65492396
OS 19.83735428 38.663245
OS 19.84197708 38.66971692
OS 19.84659988 38.67618884
OS 19.85122268 38.68081164
OS 19.85492092 38.68450988
OS 19.85677004 38.68820812
OS 19.85861916 38.68913268
OS 19.85954372 38.69005724
OS 19.86971388 38.69930284
OS 19.8808086 38.70762388
OS 19.89282788 38.7140958
OS 19.90484716 38.71964316
OS 19.92888572 38.72888876
OS 19.95292428 38.73536068
OS 19.96309444 38.7372098
OS 19.9732646 38.73905892
OS 19.9825102 38.73998348
OS 19.98990668 38.74090804
OE
SE
S P 0
OB 20.46496288 2.62766556 I
OS 20.46496288 3.06405788
OS 20.5500224 3.06405788
OS 20.5500224 2.62304276
OS 20.5500224 2.603627
OS 20.55187152 2.58698492
OS 20.55279608 2.57311652
OS 20.5546452 2.5620218
OS 20.55649432 2.55370076
OS 20.55741888 2.54722884
OS 20.559268 2.5435306
OS 20.559268 2.54260604
OS 20.56296624 2.53336044
OS 20.56758904 2.52596396
OS 20.5731364 2.51949204
OS 20.5777592 2.51302012
OS 20.58330656 2.50932188
OS 20.5870048 2.50562364
OS 20.58977848 2.50377452
OS 20.59070304 2.50284996
OS 20.59994864 2.49822716
OS 20.60919424 2.49452892
OS 20.61843984 2.4926798
OS 20.62676088 2.49083068
OS 20.63508192 2.48990612
OS 20.64062928 2.48898156
OS 20.64617664 2.48898156
OS 20.6609696 2.48990612
OS 20.674838 2.49360436
OS 20.68593272 2.4973026
OS 20.69610288 2.50284996
OS 20.70349936 2.50747276
OS 20.70904672 2.51209556
OS 20.71274496 2.51486924
OS 20.71366952 2.5157938
OS 20.71829232 2.52134116
OS 20.72199056 2.52781308
OS 20.72753792 2.54260604
OS 20.73308528 2.55924812
OS 20.73585896 2.5758902
OS 20.73863264 2.59160772
OS 20.73863264 2.59807964
OS 20.7395572 2.603627
OS 20.74048176 2.60917436
OS 20.74048176 2.6128726
OS 20.74048176 2.61472172
OS 20.74048176 2.61564628
OS 20.81722024 2.60455156
OS 20.81722024 2.58698492
OS 20.81629568 2.5712674
OS 20.813522 2.55554988
OS 20.81167288 2.54168148
OS 20.80797464 2.52873764
OS 20.8042764 2.51764292
OS 20.80057816 2.5065482
OS 20.79687992 2.4973026
OS 20.79225712 2.48898156
OS 20.78855888 2.48158508
OS 20.78486064 2.47511316
OS 20.7811624 2.47049036
OS 20.77838872 2.46679212
OS 20.7765396 2.46309388
OS 20.77561504 2.46216932
OS 20.77469048 2.46124476
OS 20.76544488 2.45292372
OS 20.75619928 2.44552724
OS 20.74602912 2.43905532
OS 20.7349344 2.43350796
OS 20.71366952 2.42518692
OS 20.6933292 2.41963956
OS 20.67391344 2.41594132
OS 20.66651696 2.41501676
OS 20.65912048 2.4140922
OS 20.65357312 2.41316764
OS 20.64525208 2.41316764
OS 20.62491176 2.4140922
OS 20.60642056 2.41686588
OS 20.58977848 2.42056412
OS 20.57498552 2.42518692
OS 20.56296624 2.42888516
OS 20.5546452 2.4325834
OS 20.54909784 2.43535708
OS 20.54724872 2.43628164
OS 20.53245576 2.44552724
OS 20.51951192 2.45662196
OS 20.50934176 2.46771668
OS 20.50009616 2.47788684
OS 20.49362424 2.488057
OS 20.48900144 2.49545348
OS 20.48622776 2.50100084
OS 20.4853032 2.5019254
OS 20.4853032 2.50284996
OS 20.47883128 2.52134116
OS 20.47328392 2.54075692
OS 20.46958568 2.5620218
OS 20.46773656 2.58236212
OS 20.46588744 2.59992876
OS 20.46588744 2.60732524
OS 20.46496288 2.61472172
OS 20.46496288 2.62026908
OS 20.46496288 2.62396732
OS 20.46496288 2.626741
OS 20.46496288 2.62766556
OE
OB 20.06277928 2.42426236 I
OS 20.06277928 3.06683156
OS 20.11363008 3.06683156
OS 20.12287568 3.05111404
OS 20.13304584 3.03632108
OS 20.14506512 3.02152812
OS 20.15615984 3.00858428
OS 20.16725456 2.99748956
OS 20.1755756 2.98824396
OS 20.17927384 2.98547028
OS 20.18204752 2.9826966
OS 20.18297208 2.98177204
OS 20.18389664 2.98084748
OS 20.2033124 2.96512996
OS 20.22272816 2.950337
OS 20.24121936 2.93739316
OS 20.25971056 2.927223
OS 20.27542808 2.9179774
OS 20.2819 2.91427916
OS 20.28744736 2.91150548
OS 20.29207016 2.9087318
OS 20.2957684 2.90780724
OS 20.29761752 2.90595812
OS 20.29854208 2.90595812
OS 20.29854208 2.8301442
OS 20.28467368 2.83569156
OS 20.27080528 2.84216348
OS 20.25693688 2.8486354
OS 20.24399304 2.85510732
OS 20.23289832 2.86065468
OS 20.22365272 2.86527748
OS 20.21810536 2.86897572
OS 20.2171808 2.86990028
OS 20.21625624 2.86990028
OS 20.19961416 2.88007044
OS 20.1848212 2.8902406
OS 20.17187736 2.8994862
OS 20.1617072 2.90780724
OS 20.1524616 2.91427916
OS 20.14691424 2.91982652
OS 20.14229144 2.92352476
OS 20.14136688 2.92444932
OS 20.14136688 2.42426236
OS 20.06277928 2.42426236
OE
SE
S P 0
OB 26.66511558 8.12007012 I
OS 26.6715875 8.12099468
OS 26.6808331 8.12099468
OS 26.71134358 8.11914556
OS 26.7409295 8.11452276
OS 26.76681718 8.1089754
OS 26.77883646 8.10527716
OS 26.78993118 8.10157892
OS 26.80010134 8.09788068
OS 26.80934694 8.09418244
OS 26.81674342 8.09140876
OS 26.8241399 8.08863508
OS 26.8287627 8.0858614
OS 26.83246094 8.08401228
OS 26.83523462 8.08308772
OS 26.83615918 8.08216316
OS 26.8611223 8.06644564
OS 26.88238718 8.04795444
OS 26.90087838 8.02946324
OS 26.9165959 8.01097204
OS 26.92861518 7.99432996
OS 26.93323798 7.98693348
OS 26.93693622 7.98046156
OS 26.94063446 7.97583876
OS 26.94248358 7.97214052
OS 26.94340814 7.96936684
OS 26.9443327 7.96844228
OS 26.95727654 7.93978092
OS 26.96652214 7.910195
OS 26.97299406 7.88060908
OS 26.97761686 7.85379684
OS 26.97946598 7.84177756
OS 26.98039054 7.82975828
OS 26.9813151 7.82051268
OS 26.9813151 7.81126708
OS 26.98223966 7.80479516
OS 26.98223966 7.7992478
OS 26.98223966 7.79554956
OS 26.98223966 7.794625
OS 26.98039054 7.76134084
OS 26.9766923 7.72898124
OS 26.9720695 7.70031988
OS 26.96837126 7.68645148
OS 26.96559758 7.6744322
OS 26.9628239 7.66333748
OS 26.95912566 7.65316732
OS 26.95635198 7.64392172
OS 26.95450286 7.63652524
OS 26.95172918 7.63097788
OS 26.95080462 7.62635508
OS 26.9489555 7.6235814
OS 26.9489555 7.62265684
OS 26.9350871 7.59492004
OS 26.91936958 7.56995692
OS 26.9027275 7.54869204
OS 26.89440646 7.540371
OS 26.88700998 7.53204996
OS 26.8796135 7.52465348
OS 26.87221702 7.51818156
OS 26.8657451 7.5126342
OS 26.86019774 7.50893596
OS 26.8564995 7.50523772
OS 26.85280126 7.50246404
OS 26.85095214 7.50153948
OS 26.85002758 7.50061492
OS 26.83708374 7.49321844
OS 26.8241399 7.48674652
OS 26.7964031 7.47657636
OS 26.7686663 7.46917988
OS 26.74185406 7.46455708
OS 26.72891022 7.46270796
OS 26.7178155 7.46085884
OS 26.70764534 7.45993428
OS 26.6993243 7.45993428
OS 26.69192782 7.45900972
OS 26.68175766 7.45900972
OS 26.66326646 7.45993428
OS 26.64569982 7.4617834
OS 26.62905774 7.46363252
OS 26.61334022 7.46733076
OS 26.59854726 7.47195356
OS 26.58467886 7.47657636
OS 26.57173502 7.48119916
OS 26.55971574 7.48674652
OS 26.54954558 7.49136932
OS 26.53937542 7.49599212
OS 26.53197894 7.50061492
OS 26.52458246 7.50523772
OS 26.51995966 7.50893596
OS 26.51533686 7.51078508
OS 26.51348774 7.5126342
OS 26.51256318 7.51355876
OS 26.49961934 7.52465348
OS 26.48852462 7.5357482
OS 26.47835446 7.54869204
OS 26.4681843 7.56163588
OS 26.45154222 7.58752356
OS 26.43859838 7.61341124
OS 26.43305102 7.62543052
OS 26.42842822 7.63652524
OS 26.42472998 7.6466954
OS 26.4219563 7.65501644
OS 26.41918262 7.66241292
OS 26.4173335 7.66796028
OS 26.41640894 7.67165852
OS 26.41640894 7.67258308
OS 26.50146846 7.69384796
OS 26.5051667 7.679055
OS 26.5097895 7.6651866
OS 26.5144123 7.65224276
OS 26.5190351 7.64022348
OS 26.52458246 7.62912876
OS 26.53012982 7.61988316
OS 26.53660174 7.61063756
OS 26.5421491 7.60231652
OS 26.5467719 7.59492004
OS 26.55231926 7.58937268
OS 26.55694206 7.58382532
OS 26.5606403 7.57920252
OS 26.56433854 7.57642884
OS 26.56711222 7.57365516
OS 26.56803678 7.5727306
OS 26.56896134 7.57180604
OS 26.57820694 7.56440956
OS 26.5883771 7.5588622
OS 26.60871742 7.54869204
OS 26.62813318 7.54129556
OS 26.64754894 7.53667276
OS 26.66419102 7.53297452
OS 26.67066294 7.53204996
OS 26.67713486 7.53204996
OS 26.68268222 7.5311254
OS 26.68915414 7.5311254
OS 26.71041902 7.53204996
OS 26.73075934 7.5357482
OS 26.74925054 7.540371
OS 26.76589262 7.54591836
OS 26.77883646 7.55146572
OS 26.78438382 7.5542394
OS 26.78900662 7.55608852
OS 26.79270486 7.55793764
OS 26.79547854 7.55978676
OS 26.79732766 7.56071132
OS 26.79825222 7.56071132
OS 26.81581886 7.57365516
OS 26.83061182 7.58752356
OS 26.84355566 7.60324108
OS 26.85372582 7.61803404
OS 26.86204686 7.63097788
OS 26.86759422 7.6420726
OS 26.86944334 7.6466954
OS 26.87129246 7.64946908
OS 26.87221702 7.6513182
OS 26.87221702 7.65224276
OS 26.8796135 7.67628132
OS 26.88516086 7.70031988
OS 26.88978366 7.72435844
OS 26.89255734 7.74654788
OS 26.8934819 7.75671804
OS 26.89440646 7.76596364
OS 26.89440646 7.77428468
OS 26.89533102 7.7807566
OS 26.89533102 7.78630396
OS 26.89533102 7.79092676
OS 26.89533102 7.79370044
OS 26.89533102 7.794625
OS 26.89440646 7.81866356
OS 26.89255734 7.840853
OS 26.8888591 7.86119332
OS 26.88516086 7.87968452
OS 26.88238718 7.89540204
OS 26.88053806 7.90187396
OS 26.87868894 7.90742132
OS 26.87776438 7.91204412
OS 26.87683982 7.9148178
OS 26.87591526 7.91666692
OS 26.87591526 7.91759148
OS 26.86666966 7.93885636
OS 26.8564995 7.95827212
OS 26.84540478 7.97398964
OS 26.8333855 7.98785804
OS 26.82321534 7.99895276
OS 26.8148943 8.00634924
OS 26.80842238 8.01097204
OS 26.80749782 8.01282116
OS 26.80657326 8.01282116
OS 26.7871575 8.02484044
OS 26.76589262 8.03408604
OS 26.7455523 8.04055796
OS 26.72613654 8.0442562
OS 26.7085699 8.04702988
OS 26.70117342 8.04795444
OS 26.6947015 8.04795444
OS 26.6900787 8.048879
OS 26.68268222 8.048879
OS 26.65956822 8.04795444
OS 26.63830334 8.0442562
OS 26.6207367 8.03870884
OS 26.60501918 8.03316148
OS 26.5929999 8.02668956
OS 26.5837543 8.02206676
OS 26.57820694 8.01836852
OS 26.57635782 8.0165194
OS 26.56156486 8.002651
OS 26.54769646 7.98693348
OS 26.53660174 7.9702914
OS 26.52735614 7.95364932
OS 26.51995966 7.93885636
OS 26.51718598 7.93145988
OS 26.51533686 7.92591252
OS 26.51348774 7.92128972
OS 26.51163862 7.91759148
OS 26.51071406 7.91574236
OS 26.51071406 7.9148178
OS 26.42750366 7.93423356
OS 26.43305102 7.95087564
OS 26.43859838 7.9656686
OS 26.44599486 7.979537
OS 26.45246678 7.9934054
OS 26.45986326 8.00542468
OS 26.4681843 8.0165194
OS 26.47558078 8.02761412
OS 26.48297726 8.03685972
OS 26.49037374 8.0442562
OS 26.49684566 8.05165268
OS 26.50331758 8.0581246
OS 26.50794038 8.0627474
OS 26.51256318 8.0673702
OS 26.51626142 8.07014388
OS 26.51811054 8.07106844
OS 26.5190351 8.071993
OS 26.53197894 8.08031404
OS 26.54492278 8.08863508
OS 26.55786662 8.095107
OS 26.57173502 8.10065436
OS 26.59947182 8.1089754
OS 26.62443494 8.11452276
OS 26.63645422 8.11729644
OS 26.64662438 8.118221
OS 26.65679454 8.11914556
OS 26.66511558 8.12007012
OE
OB 26.04843406 7.47010444 I
OS 26.04843406 8.11267364
OS 26.09928486 8.11267364
OS 26.10853046 8.09695612
OS 26.11870062 8.08216316
OS 26.1307199 8.0673702
OS 26.14181462 8.05442636
OS 26.15290934 8.04333164
OS 26.16123038 8.03408604
OS 26.16492862 8.03131236
OS 26.1677023 8.02853868
OS 26.16862686 8.02761412
OS 26.16955142 8.02668956
OS 26.18896718 8.01097204
OS 26.20838294 7.99617908
OS 26.22687414 7.98323524
OS 26.24536534 7.97306508
OS 26.26108286 7.96381948
OS 26.26755478 7.96012124
OS 26.27310214 7.95734756
OS 26.27772494 7.95457388
OS 26.28142318 7.95364932
OS 26.2832723 7.9518002
OS 26.28419686 7.9518002
OS 26.28419686 7.87598628
OS 26.27032846 7.88153364
OS 26.25646006 7.88800556
OS 26.24259166 7.89447748
OS 26.22964782 7.9009494
OS 26.2185531 7.90649676
OS 26.2093075 7.91111956
OS 26.20376014 7.9148178
OS 26.20283558 7.91574236
OS 26.20191102 7.91574236
OS 26.18526894 7.92591252
OS 26.17047598 7.93608268
OS 26.15753214 7.94532828
OS 26.14736198 7.95364932
OS 26.13811638 7.96012124
OS 26.13256902 7.9656686
OS 26.12794622 7.96936684
OS 26.12702166 7.9702914
OS 26.12702166 7.47010444
OS 26.04843406 7.47010444
OE
OB 25.55102078 7.47010444 I
OS 25.55102078 8.11267364
OS 25.60187158 8.11267364
OS 25.61111718 8.09695612
OS 25.62128734 8.08216316
OS 25.63330662 8.0673702
OS 25.64440134 8.05442636
OS 25.65549606 8.04333164
OS 25.6638171 8.03408604
OS 25.66751534 8.03131236
OS 25.67028902 8.02853868
OS 25.67121358 8.02761412
OS 25.67213814 8.02668956
OS 25.6915539 8.01097204
OS 25.71096966 7.99617908
OS 25.72946086 7.98323524
OS 25.74795206 7.97306508
OS 25.76366958 7.96381948
OS 25.7701415 7.96012124
OS 25.77568886 7.95734756
OS 25.78031166 7.95457388
OS 25.7840099 7.95364932
OS 25.78585902 7.9518002
OS 25.78678358 7.9518002
OS 25.78678358 7.87598628
OS 25.77291518 7.88153364
OS 25.75904678 7.88800556
OS 25.74517838 7.89447748
OS 25.73223454 7.9009494
OS 25.72113982 7.90649676
OS 25.71189422 7.91111956
OS 25.70634686 7.9148178
OS 25.7054223 7.91574236
OS 25.70449774 7.91574236
OS 25.68785566 7.92591252
OS 25.6730627 7.93608268
OS 25.66011886 7.94532828
OS 25.6499487 7.95364932
OS 25.6407031 7.96012124
OS 25.63515574 7.9656686
OS 25.63053294 7.96936684
OS 25.62960838 7.9702914
OS 25.62960838 7.47010444
OS 25.55102078 7.47010444
OE
SE
S P 0
OB 26.72382514 12.62006874 I
OS 26.73029706 12.6209933
OS 26.73954266 12.6209933
OS 26.77005314 12.61914418
OS 26.79963906 12.61452138
OS 26.82552674 12.60897402
OS 26.83754602 12.60527578
OS 26.84864074 12.60157754
OS 26.8588109 12.5978793
OS 26.8680565 12.59418106
OS 26.87545298 12.59140738
OS 26.88284946 12.5886337
OS 26.88747226 12.58586002
OS 26.8911705 12.5840109
OS 26.89394418 12.58308634
OS 26.89486874 12.58216178
OS 26.91983186 12.56644426
OS 26.94109674 12.54795306
OS 26.95958794 12.52946186
OS 26.97530546 12.51097066
OS 26.98732474 12.49432858
OS 26.99194754 12.4869321
OS 26.99564578 12.48046018
OS 26.99934402 12.47583738
OS 27.00119314 12.47213914
OS 27.0021177 12.46936546
OS 27.00304226 12.4684409
OS 27.0159861 12.43977954
OS 27.0252317 12.41019362
OS 27.03170362 12.3806077
OS 27.03632642 12.35379546
OS 27.03817554 12.34177618
OS 27.0391001 12.3297569
OS 27.04002466 12.3205113
OS 27.04002466 12.3112657
OS 27.04094922 12.30479378
OS 27.04094922 12.29924642
OS 27.04094922 12.29554818
OS 27.04094922 12.29462362
OS 27.0391001 12.26133946
OS 27.03540186 12.22897986
OS 27.03077906 12.2003185
OS 27.02708082 12.1864501
OS 27.02430714 12.17443082
OS 27.02153346 12.1633361
OS 27.01783522 12.15316594
OS 27.01506154 12.14392034
OS 27.01321242 12.13652386
OS 27.01043874 12.1309765
OS 27.00951418 12.1263537
OS 27.00766506 12.12358002
OS 27.00766506 12.12265546
OS 26.99379666 12.09491866
OS 26.97807914 12.06995554
OS 26.96143706 12.04869066
OS 26.95311602 12.04036962
OS 26.94571954 12.03204858
OS 26.93832306 12.0246521
OS 26.93092658 12.01818018
OS 26.92445466 12.01263282
OS 26.9189073 12.00893458
OS 26.91520906 12.00523634
OS 26.91151082 12.00246266
OS 26.9096617 12.0015381
OS 26.90873714 12.00061354
OS 26.8957933 11.99321706
OS 26.88284946 11.98674514
OS 26.85511266 11.97657498
OS 26.82737586 11.9691785
OS 26.80056362 11.9645557
OS 26.78761978 11.96270658
OS 26.77652506 11.96085746
OS 26.7663549 11.9599329
OS 26.75803386 11.9599329
OS 26.75063738 11.95900834
OS 26.74046722 11.95900834
OS 26.72197602 11.9599329
OS 26.70440938 11.96178202
OS 26.6877673 11.96363114
OS 26.67204978 11.96732938
OS 26.65725682 11.97195218
OS 26.64338842 11.97657498
OS 26.63044458 11.98119778
OS 26.6184253 11.98674514
OS 26.60825514 11.99136794
OS 26.59808498 11.99599074
OS 26.5906885 12.00061354
OS 26.58329202 12.00523634
OS 26.57866922 12.00893458
OS 26.57404642 12.0107837
OS 26.5721973 12.01263282
OS 26.57127274 12.01355738
OS 26.5583289 12.0246521
OS 26.54723418 12.03574682
OS 26.53706402 12.04869066
OS 26.52689386 12.0616345
OS 26.51025178 12.08752218
OS 26.49730794 12.11340986
OS 26.49176058 12.12542914
OS 26.48713778 12.13652386
OS 26.48343954 12.14669402
OS 26.48066586 12.15501506
OS 26.47789218 12.16241154
OS 26.47604306 12.1679589
OS 26.4751185 12.17165714
OS 26.4751185 12.1725817
OS 26.56017802 12.19384658
OS 26.56387626 12.17905362
OS 26.56849906 12.16518522
OS 26.57312186 12.15224138
OS 26.57774466 12.1402221
OS 26.58329202 12.12912738
OS 26.58883938 12.11988178
OS 26.5953113 12.11063618
OS 26.60085866 12.10231514
OS 26.60548146 12.09491866
OS 26.61102882 12.0893713
OS 26.61565162 12.08382394
OS 26.61934986 12.07920114
OS 26.6230481 12.07642746
OS 26.62582178 12.07365378
OS 26.62674634 12.07272922
OS 26.6276709 12.07180466
OS 26.6369165 12.06440818
OS 26.64708666 12.05886082
OS 26.66742698 12.04869066
OS 26.68684274 12.04129418
OS 26.7062585 12.03667138
OS 26.72290058 12.03297314
OS 26.7293725 12.03204858
OS 26.73584442 12.03204858
OS 26.74139178 12.03112402
OS 26.7478637 12.03112402
OS 26.76912858 12.03204858
OS 26.7894689 12.03574682
OS 26.8079601 12.04036962
OS 26.82460218 12.04591698
OS 26.83754602 12.05146434
OS 26.84309338 12.05423802
OS 26.84771618 12.05608714
OS 26.85141442 12.05793626
OS 26.8541881 12.05978538
OS 26.85603722 12.06070994
OS 26.85696178 12.06070994
OS 26.87452842 12.07365378
OS 26.88932138 12.08752218
OS 26.90226522 12.1032397
OS 26.91243538 12.11803266
OS 26.92075642 12.1309765
OS 26.92630378 12.14207122
OS 26.9281529 12.14669402
OS 26.93000202 12.1494677
OS 26.93092658 12.15131682
OS 26.93092658 12.15224138
OS 26.93832306 12.17627994
OS 26.94387042 12.2003185
OS 26.94849322 12.22435706
OS 26.9512669 12.2465465
OS 26.95219146 12.25671666
OS 26.95311602 12.26596226
OS 26.95311602 12.2742833
OS 26.95404058 12.28075522
OS 26.95404058 12.28630258
OS 26.95404058 12.29092538
OS 26.95404058 12.29369906
OS 26.95404058 12.29462362
OS 26.95311602 12.31866218
OS 26.9512669 12.34085162
OS 26.94756866 12.36119194
OS 26.94387042 12.37968314
OS 26.94109674 12.39540066
OS 26.93924762 12.40187258
OS 26.9373985 12.40741994
OS 26.93647394 12.41204274
OS 26.93554938 12.41481642
OS 26.93462482 12.41666554
OS 26.93462482 12.4175901
OS 26.92537922 12.43885498
OS 26.91520906 12.45827074
OS 26.90411434 12.47398826
OS 26.89209506 12.48785666
OS 26.8819249 12.49895138
OS 26.87360386 12.50634786
OS 26.86713194 12.51097066
OS 26.86620738 12.51281978
OS 26.86528282 12.51281978
OS 26.84586706 12.52483906
OS 26.82460218 12.53408466
OS 26.80426186 12.54055658
OS 26.7848461 12.54425482
OS 26.76727946 12.5470285
OS 26.75988298 12.54795306
OS 26.75341106 12.54795306
OS 26.74878826 12.54887762
OS 26.74139178 12.54887762
OS 26.71827778 12.54795306
OS 26.6970129 12.54425482
OS 26.67944626 12.53870746
OS 26.66372874 12.5331601
OS 26.65170946 12.52668818
OS 26.64246386 12.52206538
OS 26.6369165 12.51836714
OS 26.63506738 12.51651802
OS 26.62027442 12.50264962
OS 26.60640602 12.4869321
OS 26.5953113 12.47029002
OS 26.5860657 12.45364794
OS 26.57866922 12.43885498
OS 26.57589554 12.4314585
OS 26.57404642 12.42591114
OS 26.5721973 12.42128834
OS 26.57034818 12.4175901
OS 26.56942362 12.41574098
OS 26.56942362 12.41481642
OS 26.48621322 12.43423218
OS 26.49176058 12.45087426
OS 26.49730794 12.46566722
OS 26.50470442 12.47953562
OS 26.51117634 12.49340402
OS 26.51857282 12.5054233
OS 26.52689386 12.51651802
OS 26.53429034 12.52761274
OS 26.54168682 12.53685834
OS 26.5490833 12.54425482
OS 26.55555522 12.5516513
OS 26.56202714 12.55812322
OS 26.56664994 12.56274602
OS 26.57127274 12.56736882
OS 26.57497098 12.5701425
OS 26.5768201 12.57106706
OS 26.57774466 12.57199162
OS 26.5906885 12.58031266
OS 26.60363234 12.5886337
OS 26.61657618 12.59510562
OS 26.63044458 12.60065298
OS 26.65818138 12.60897402
OS 26.6831445 12.61452138
OS 26.69516378 12.61729506
OS 26.70533394 12.61821962
OS 26.7155041 12.61914418
OS 26.72382514 12.62006874
OE
OB 26.10714362 11.97010306 I
OS 26.10714362 12.61267226
OS 26.15799442 12.61267226
OS 26.16724002 12.59695474
OS 26.17741018 12.58216178
OS 26.18942946 12.56736882
OS 26.20052418 12.55442498
OS 26.2116189 12.54333026
OS 26.21993994 12.53408466
OS 26.22363818 12.53131098
OS 26.22641186 12.5285373
OS 26.22733642 12.52761274
OS 26.22826098 12.52668818
OS 26.24767674 12.51097066
OS 26.2670925 12.4961777
OS 26.2855837 12.48323386
OS 26.3040749 12.4730637
OS 26.31979242 12.4638181
OS 26.32626434 12.46011986
OS 26.3318117 12.45734618
OS 26.3364345 12.4545725
OS 26.34013274 12.45364794
OS 26.34198186 12.45179882
OS 26.34290642 12.45179882
OS 26.34290642 12.3759849
OS 26.32903802 12.38153226
OS 26.31516962 12.38800418
OS 26.30130122 12.3944761
OS 26.28835738 12.40094802
OS 26.27726266 12.40649538
OS 26.26801706 12.41111818
OS 26.2624697 12.41481642
OS 26.26154514 12.41574098
OS 26.26062058 12.41574098
OS 26.2439785 12.42591114
OS 26.22918554 12.4360813
OS 26.2162417 12.4453269
OS 26.20607154 12.45364794
OS 26.19682594 12.46011986
OS 26.19127858 12.46566722
OS 26.18665578 12.46936546
OS 26.18573122 12.47029002
OS 26.18573122 11.97010306
OS 26.10714362 11.97010306
OE
OB 25.67814778 12.6117477 I
OS 25.6846197 12.61267226
OS 25.6938653 12.61267226
OS 25.71050738 12.6117477
OS 25.7262249 12.61082314
OS 25.74101786 12.60804946
OS 25.75488626 12.60527578
OS 25.7678301 12.60157754
OS 25.77984938 12.5978793
OS 25.7909441 12.5932565
OS 25.80111426 12.5886337
OS 25.81035986 12.5840109
OS 25.81775634 12.5793881
OS 25.82422826 12.57568986
OS 25.82977562 12.57199162
OS 25.83439842 12.56921794
OS 25.8371721 12.56644426
OS 25.83902122 12.5655197
OS 25.83994578 12.56459514
OS 25.84919138 12.55534954
OS 25.85751242 12.54517938
OS 25.86583346 12.53408466
OS 25.87230538 12.52298994
OS 25.8834001 12.5008005
OS 25.89079658 12.47861106
OS 25.89357026 12.4684409
OS 25.89634394 12.45827074
OS 25.89819306 12.4499497
OS 25.90004218 12.44255322
OS 25.90096674 12.4360813
OS 25.90096674 12.4314585
OS 25.9018913 12.42868482
OS 25.9018913 12.42776026
OS 25.82145458 12.41943922
OS 25.81960546 12.4407041
OS 25.81590722 12.4591953
OS 25.81035986 12.47583738
OS 25.80388794 12.48878122
OS 25.79834058 12.49987594
OS 25.79279322 12.50727242
OS 25.78909498 12.51189522
OS 25.78724586 12.51374434
OS 25.77337746 12.52483906
OS 25.7585845 12.5331601
OS 25.74286698 12.53963202
OS 25.72899858 12.54333026
OS 25.71605474 12.54610394
OS 25.70496002 12.5470285
OS 25.70126178 12.54795306
OS 25.69571442 12.54795306
OS 25.67629866 12.5470285
OS 25.65873202 12.54333026
OS 25.64393906 12.5377829
OS 25.63099522 12.53223554
OS 25.62082506 12.52576362
OS 25.61435314 12.52114082
OS 25.60973034 12.51744258
OS 25.60788122 12.51559346
OS 25.5967865 12.50264962
OS 25.58846546 12.48970578
OS 25.58199354 12.47676194
OS 25.5782953 12.4638181
OS 25.57552162 12.45364794
OS 25.57459706 12.44440234
OS 25.5736725 12.43885498
OS 25.5736725 12.43793042
OS 25.5736725 12.43700586
OS 25.57552162 12.42036378
OS 25.57921986 12.40279714
OS 25.58569178 12.38707962
OS 25.5921637 12.37228666
OS 25.59956018 12.36026738
OS 25.6060321 12.35009722
OS 25.60788122 12.34639898
OS 25.60973034 12.3436253
OS 25.61157946 12.34270074
OS 25.61157946 12.34177618
OS 25.61897594 12.33160602
OS 25.62822154 12.32143586
OS 25.6383917 12.31034114
OS 25.64948642 12.29924642
OS 25.67260042 12.27705698
OS 25.69571442 12.25486754
OS 25.7077337 12.24469738
OS 25.71790386 12.23545178
OS 25.72807402 12.22713074
OS 25.73639506 12.21973426
OS 25.74286698 12.2141869
OS 25.74841434 12.2095641
OS 25.75211258 12.20679042
OS 25.75303714 12.20586586
OS 25.77615114 12.1864501
OS 25.79741602 12.1679589
OS 25.81498266 12.15131682
OS 25.82885106 12.13744842
OS 25.84087034 12.12542914
OS 25.84919138 12.1171081
OS 25.85381418 12.11156074
OS 25.8556633 12.11063618
OS 25.8556633 12.10971162
OS 25.86860714 12.0939941
OS 25.8787773 12.07920114
OS 25.8880229 12.06440818
OS 25.89541938 12.05146434
OS 25.90096674 12.04036962
OS 25.90466498 12.03204858
OS 25.9065141 12.02650122
OS 25.90743866 12.02557666
OS 25.90743866 12.0246521
OS 25.9111369 12.01448194
OS 25.91298602 12.00523634
OS 25.91483514 11.99599074
OS 25.9157597 11.9876697
OS 25.91668426 11.98027322
OS 25.91668426 11.97472586
OS 25.91668426 11.97102762
OS 25.91668426 11.97010306
OS 25.49231122 11.97010306
OS 25.49231122 12.04591698
OS 25.80758618 12.04591698
OS 25.79649146 12.0616345
OS 25.7909441 12.06810642
OS 25.7863213 12.07457834
OS 25.7816985 12.0801257
OS 25.77800026 12.08382394
OS 25.77522658 12.08659762
OS 25.77430202 12.08752218
OS 25.76967922 12.09214498
OS 25.76413186 12.09676778
OS 25.75118802 12.10878706
OS 25.73639506 12.12265546
OS 25.72067754 12.13652386
OS 25.70588458 12.14854314
OS 25.69941266 12.1540905
OS 25.6938653 12.15963786
OS 25.6892425 12.1633361
OS 25.68554426 12.16610978
OS 25.68369514 12.1679589
OS 25.68277058 12.16888346
OS 25.66797762 12.1818273
OS 25.65318466 12.19384658
OS 25.64024082 12.20586586
OS 25.62822154 12.21603602
OS 25.61712682 12.22620618
OS 25.60788122 12.23545178
OS 25.59863562 12.24377282
OS 25.59123914 12.2511693
OS 25.58384266 12.25856578
OS 25.5782953 12.26411314
OS 25.5736725 12.26873594
OS 25.5690497 12.27335874
OS 25.5644269 12.2789061
OS 25.56257778 12.28075522
OS 25.54963394 12.29647274
OS 25.53853922 12.31034114
OS 25.52929362 12.32420954
OS 25.52189714 12.33530426
OS 25.51634978 12.34547442
OS 25.51265154 12.3528709
OS 25.51080242 12.3574937
OS 25.50987786 12.35934282
OS 25.5043305 12.37321122
OS 25.50063226 12.38707962
OS 25.49693402 12.40002346
OS 25.4950849 12.41111818
OS 25.49416034 12.42128834
OS 25.49323578 12.42868482
OS 25.49323578 12.43330762
OS 25.49323578 12.43515674
OS 25.49416034 12.44902514
OS 25.49600946 12.46196898
OS 25.49785858 12.47491282
OS 25.50155682 12.48600754
OS 25.51080242 12.50819698
OS 25.52004802 12.52576362
OS 25.52559538 12.53408466
OS 25.53021818 12.54055658
OS 25.53484098 12.5470285
OS 25.53946378 12.5516513
OS 25.54316202 12.55534954
OS 25.54501114 12.55904778
OS 25.54686026 12.55997234
OS 25.54778482 12.5608969
OS 25.55795498 12.5701425
OS 25.5690497 12.57846354
OS 25.58106898 12.58493546
OS 25.59308826 12.59048282
OS 25.61712682 12.59972842
OS 25.64116538 12.60620034
OS 25.65133554 12.60804946
OS 25.6615057 12.60989858
OS 25.6707513 12.61082314
OS 25.67814778 12.6117477
OE
SE
S P 0
OB 26.10945502 9.97010452 I
OS 26.10945502 10.61267372
OS 26.16030582 10.61267372
OS 26.16955142 10.5969562
OS 26.17972158 10.58216324
OS 26.19174086 10.56737028
OS 26.20283558 10.55442644
OS 26.2139303 10.54333172
OS 26.22225134 10.53408612
OS 26.22594958 10.53131244
OS 26.22872326 10.52853876
OS 26.22964782 10.5276142
OS 26.23057238 10.52668964
OS 26.24998814 10.51097212
OS 26.2694039 10.49617916
OS 26.2878951 10.48323532
OS 26.3063863 10.47306516
OS 26.32210382 10.46381956
OS 26.32857574 10.46012132
OS 26.3341231 10.45734764
OS 26.3387459 10.45457396
OS 26.34244414 10.4536494
OS 26.34429326 10.45180028
OS 26.34521782 10.45180028
OS 26.34521782 10.37598636
OS 26.33134942 10.38153372
OS 26.31748102 10.38800564
OS 26.30361262 10.39447756
OS 26.29066878 10.40094948
OS 26.27957406 10.40649684
OS 26.27032846 10.41111964
OS 26.2647811 10.41481788
OS 26.26385654 10.41574244
OS 26.26293198 10.41574244
OS 26.2462899 10.4259126
OS 26.23149694 10.43608276
OS 26.2185531 10.44532836
OS 26.20838294 10.4536494
OS 26.19913734 10.46012132
OS 26.19358998 10.46566868
OS 26.18896718 10.46936692
OS 26.18804262 10.47029148
OS 26.18804262 9.97010452
OS 26.10945502 9.97010452
OE
OB 26.72613654 10.6200702 I
OS 26.73260846 10.62099476
OS 26.74185406 10.62099476
OS 26.77236454 10.61914564
OS 26.80195046 10.61452284
OS 26.82783814 10.60897548
OS 26.83985742 10.60527724
OS 26.85095214 10.601579
OS 26.8611223 10.59788076
OS 26.8703679 10.59418252
OS 26.87776438 10.59140884
OS 26.88516086 10.58863516
OS 26.88978366 10.58586148
OS 26.8934819 10.58401236
OS 26.89625558 10.5830878
OS 26.89718014 10.58216324
OS 26.92214326 10.56644572
OS 26.94340814 10.54795452
OS 26.96189934 10.52946332
OS 26.97761686 10.51097212
OS 26.98963614 10.49433004
OS 26.99425894 10.48693356
OS 26.99795718 10.48046164
OS 27.00165542 10.47583884
OS 27.00350454 10.4721406
OS 27.0044291 10.46936692
OS 27.00535366 10.46844236
OS 27.0182975 10.439781
OS 27.0275431 10.41019508
OS 27.03401502 10.38060916
OS 27.03863782 10.35379692
OS 27.04048694 10.34177764
OS 27.0414115 10.32975836
OS 27.04233606 10.32051276
OS 27.04233606 10.31126716
OS 27.04326062 10.30479524
OS 27.04326062 10.29924788
OS 27.04326062 10.29554964
OS 27.04326062 10.29462508
OS 27.0414115 10.26134092
OS 27.03771326 10.22898132
OS 27.03309046 10.20031996
OS 27.02939222 10.18645156
OS 27.02661854 10.17443228
OS 27.02384486 10.16333756
OS 27.02014662 10.1531674
OS 27.01737294 10.1439218
OS 27.01552382 10.13652532
OS 27.01275014 10.13097796
OS 27.01182558 10.12635516
OS 27.00997646 10.12358148
OS 27.00997646 10.12265692
OS 26.99610806 10.09492012
OS 26.98039054 10.069957
OS 26.96374846 10.04869212
OS 26.95542742 10.04037108
OS 26.94803094 10.03205004
OS 26.94063446 10.02465356
OS 26.93323798 10.01818164
OS 26.92676606 10.01263428
OS 26.9212187 10.00893604
OS 26.91752046 10.0052378
OS 26.91382222 10.00246412
OS 26.9119731 10.00153956
OS 26.91104854 10.000615
OS 26.8981047 9.99321852
OS 26.88516086 9.9867466
OS 26.85742406 9.97657644
OS 26.82968726 9.96917996
OS 26.80287502 9.96455716
OS 26.78993118 9.96270804
OS 26.77883646 9.96085892
OS 26.7686663 9.95993436
OS 26.76034526 9.95993436
OS 26.75294878 9.9590098
OS 26.74277862 9.9590098
OS 26.72428742 9.95993436
OS 26.70672078 9.96178348
OS 26.6900787 9.9636326
OS 26.67436118 9.96733084
OS 26.65956822 9.97195364
OS 26.64569982 9.97657644
OS 26.63275598 9.98119924
OS 26.6207367 9.9867466
OS 26.61056654 9.9913694
OS 26.60039638 9.9959922
OS 26.5929999 10.000615
OS 26.58560342 10.0052378
OS 26.58098062 10.00893604
OS 26.57635782 10.01078516
OS 26.5745087 10.01263428
OS 26.57358414 10.01355884
OS 26.5606403 10.02465356
OS 26.54954558 10.03574828
OS 26.53937542 10.04869212
OS 26.52920526 10.06163596
OS 26.51256318 10.08752364
OS 26.49961934 10.11341132
OS 26.49407198 10.1254306
OS 26.48944918 10.13652532
OS 26.48575094 10.14669548
OS 26.48297726 10.15501652
OS 26.48020358 10.162413
OS 26.47835446 10.16796036
OS 26.4774299 10.1716586
OS 26.4774299 10.17258316
OS 26.56248942 10.19384804
OS 26.56618766 10.17905508
OS 26.57081046 10.16518668
OS 26.57543326 10.15224284
OS 26.58005606 10.14022356
OS 26.58560342 10.12912884
OS 26.59115078 10.11988324
OS 26.5976227 10.11063764
OS 26.60317006 10.1023166
OS 26.60779286 10.09492012
OS 26.61334022 10.08937276
OS 26.61796302 10.0838254
OS 26.62166126 10.0792026
OS 26.6253595 10.07642892
OS 26.62813318 10.07365524
OS 26.62905774 10.07273068
OS 26.6299823 10.07180612
OS 26.6392279 10.06440964
OS 26.64939806 10.05886228
OS 26.66973838 10.04869212
OS 26.68915414 10.04129564
OS 26.7085699 10.03667284
OS 26.72521198 10.0329746
OS 26.7316839 10.03205004
OS 26.73815582 10.03205004
OS 26.74370318 10.03112548
OS 26.7501751 10.03112548
OS 26.77143998 10.03205004
OS 26.7917803 10.03574828
OS 26.8102715 10.04037108
OS 26.82691358 10.04591844
OS 26.83985742 10.0514658
OS 26.84540478 10.05423948
OS 26.85002758 10.0560886
OS 26.85372582 10.05793772
OS 26.8564995 10.05978684
OS 26.85834862 10.0607114
OS 26.85927318 10.0607114
OS 26.87683982 10.07365524
OS 26.89163278 10.08752364
OS 26.90457662 10.10324116
OS 26.91474678 10.11803412
OS 26.92306782 10.13097796
OS 26.92861518 10.14207268
OS 26.9304643 10.14669548
OS 26.93231342 10.14946916
OS 26.93323798 10.15131828
OS 26.93323798 10.15224284
OS 26.94063446 10.1762814
OS 26.94618182 10.20031996
OS 26.95080462 10.22435852
OS 26.9535783 10.24654796
OS 26.95450286 10.25671812
OS 26.95542742 10.26596372
OS 26.95542742 10.27428476
OS 26.95635198 10.28075668
OS 26.95635198 10.28630404
OS 26.95635198 10.29092684
OS 26.95635198 10.29370052
OS 26.95635198 10.29462508
OS 26.95542742 10.31866364
OS 26.9535783 10.34085308
OS 26.94988006 10.3611934
OS 26.94618182 10.3796846
OS 26.94340814 10.39540212
OS 26.94155902 10.40187404
OS 26.9397099 10.4074214
OS 26.93878534 10.4120442
OS 26.93786078 10.41481788
OS 26.93693622 10.416667
OS 26.93693622 10.41759156
OS 26.92769062 10.43885644
OS 26.91752046 10.4582722
OS 26.90642574 10.47398972
OS 26.89440646 10.48785812
OS 26.8842363 10.49895284
OS 26.87591526 10.50634932
OS 26.86944334 10.51097212
OS 26.86851878 10.51282124
OS 26.86759422 10.51282124
OS 26.84817846 10.52484052
OS 26.82691358 10.53408612
OS 26.80657326 10.54055804
OS 26.7871575 10.54425628
OS 26.76959086 10.54702996
OS 26.76219438 10.54795452
OS 26.75572246 10.54795452
OS 26.75109966 10.54887908
OS 26.74370318 10.54887908
OS 26.72058918 10.54795452
OS 26.6993243 10.54425628
OS 26.68175766 10.53870892
OS 26.66604014 10.53316156
OS 26.65402086 10.52668964
OS 26.64477526 10.52206684
OS 26.6392279 10.5183686
OS 26.63737878 10.51651948
OS 26.62258582 10.50265108
OS 26.60871742 10.48693356
OS 26.5976227 10.47029148
OS 26.5883771 10.4536494
OS 26.58098062 10.43885644
OS 26.57820694 10.43145996
OS 26.57635782 10.4259126
OS 26.5745087 10.4212898
OS 26.57265958 10.41759156
OS 26.57173502 10.41574244
OS 26.57173502 10.41481788
OS 26.48852462 10.43423364
OS 26.49407198 10.45087572
OS 26.49961934 10.46566868
OS 26.50701582 10.47953708
OS 26.51348774 10.49340548
OS 26.52088422 10.50542476
OS 26.52920526 10.51651948
OS 26.53660174 10.5276142
OS 26.54399822 10.5368598
OS 26.5513947 10.54425628
OS 26.55786662 10.55165276
OS 26.56433854 10.55812468
OS 26.56896134 10.56274748
OS 26.57358414 10.56737028
OS 26.57728238 10.57014396
OS 26.5791315 10.57106852
OS 26.58005606 10.57199308
OS 26.5929999 10.58031412
OS 26.60594374 10.58863516
OS 26.61888758 10.59510708
OS 26.63275598 10.60065444
OS 26.66049278 10.60897548
OS 26.6854559 10.61452284
OS 26.69747518 10.61729652
OS 26.70764534 10.61822108
OS 26.7178155 10.61914564
OS 26.72613654 10.6200702
OE
OB 25.68045918 10.61174916 I
OS 25.69062934 10.61267372
OS 25.69895038 10.61267372
OS 25.7239135 10.6108246
OS 25.7470275 10.60712636
OS 25.76644326 10.60065444
OS 25.78308534 10.59418252
OS 25.79695374 10.58678604
OS 25.8025011 10.58401236
OS 25.8071239 10.58031412
OS 25.81082214 10.578465
OS 25.81359582 10.57661588
OS 25.81452038 10.57476676
OS 25.81544494 10.57476676
OS 25.83208702 10.5599738
OS 25.84595542 10.54240716
OS 25.8579747 10.52484052
OS 25.8672203 10.50819844
OS 25.87461678 10.49248092
OS 25.87831502 10.486009
OS 25.88016414 10.47953708
OS 25.88201326 10.47491428
OS 25.88386238 10.47121604
OS 25.88478694 10.46936692
OS 25.88478694 10.46844236
OS 25.88848518 10.45457396
OS 25.89218342 10.44070556
OS 25.89773078 10.41019508
OS 25.90235358 10.3796846
OS 25.90512726 10.35102324
OS 25.90605182 10.33715484
OS 25.90697638 10.32513556
OS 25.90697638 10.31404084
OS 25.90790094 10.30387068
OS 25.90790094 10.2964742
OS 25.90790094 10.29000228
OS 25.90790094 10.28630404
OS 25.90790094 10.28537948
OS 25.90697638 10.25301988
OS 25.90512726 10.2225094
OS 25.90235358 10.1947726
OS 25.89773078 10.16888492
OS 25.89310798 10.14484636
OS 25.88756062 10.12358148
OS 25.88201326 10.10416572
OS 25.8764659 10.08752364
OS 25.87091854 10.07273068
OS 25.86444662 10.05978684
OS 25.85982382 10.04869212
OS 25.85520102 10.04037108
OS 25.85057822 10.0329746
OS 25.84780454 10.0283518
OS 25.84595542 10.02557812
OS 25.84503086 10.02465356
OS 25.8348607 10.01355884
OS 25.82376598 10.00338868
OS 25.8117467 9.99414308
OS 25.79972742 9.9867466
OS 25.78770814 9.98027468
OS 25.77568886 9.97472732
OS 25.76366958 9.97102908
OS 25.75257486 9.96733084
OS 25.74148014 9.96455716
OS 25.73130998 9.96270804
OS 25.72206438 9.96085892
OS 25.7146679 9.95993436
OS 25.70819598 9.9590098
OS 25.69895038 9.9590098
OS 25.67398726 9.96085892
OS 25.65087326 9.96455716
OS 25.6314575 9.97102908
OS 25.61481542 9.977501
OS 25.60094702 9.98397292
OS 25.59632422 9.98767116
OS 25.59170142 9.99044484
OS 25.58800318 9.99229396
OS 25.5852295 9.99414308
OS 25.58430494 9.9959922
OS 25.58338038 9.9959922
OS 25.5667383 10.01170972
OS 25.5528699 10.0283518
OS 25.54085062 10.046843
OS 25.53160502 10.06348508
OS 25.52420854 10.0792026
OS 25.5205103 10.08567452
OS 25.51866118 10.09214644
OS 25.51681206 10.09676924
OS 25.51496294 10.10046748
OS 25.51403838 10.1023166
OS 25.51403838 10.10324116
OS 25.50941558 10.11710956
OS 25.50571734 10.13097796
OS 25.50016998 10.16056388
OS 25.49554718 10.19107436
OS 25.4927735 10.22066028
OS 25.49184894 10.23360412
OS 25.49092438 10.2456234
OS 25.49092438 10.25671812
OS 25.48999982 10.26688828
OS 25.48999982 10.27428476
OS 25.48999982 10.28075668
OS 25.48999982 10.28445492
OS 25.48999982 10.28537948
OS 25.48999982 10.30294612
OS 25.49092438 10.3195882
OS 25.49092438 10.33438116
OS 25.49184894 10.34917412
OS 25.49369806 10.36211796
OS 25.49462262 10.3750618
OS 25.49554718 10.38615652
OS 25.4973963 10.39632668
OS 25.49832086 10.40557228
OS 25.50016998 10.41389332
OS 25.50109454 10.42036524
OS 25.5020191 10.4259126
OS 25.50294366 10.4305354
OS 25.50386822 10.43330908
OS 25.50479278 10.4351582
OS 25.50479278 10.43608276
OS 25.51034014 10.45642308
OS 25.51681206 10.47491428
OS 25.52420854 10.4906318
OS 25.5297559 10.5045002
OS 25.53622782 10.51651948
OS 25.53992606 10.52484052
OS 25.5436243 10.52946332
OS 25.54454886 10.53131244
OS 25.55471902 10.54518084
OS 25.56488918 10.55720012
OS 25.5759839 10.56737028
OS 25.58615406 10.57661588
OS 25.59539966 10.5830878
OS 25.60279614 10.5877106
OS 25.60741894 10.59048428
OS 25.6083435 10.59140884
OS 25.60926806 10.59140884
OS 25.62406102 10.59880532
OS 25.63977854 10.60342812
OS 25.6545715 10.60712636
OS 25.6684399 10.60990004
OS 25.68045918 10.61174916
OE
OB 25.69987494 10.54795452 H
OS 25.68970478 10.54702996
OS 25.67953462 10.5461054
OS 25.67028902 10.54333172
OS 25.66196798 10.53963348
OS 25.64625046 10.53131244
OS 25.63238206 10.52206684
OS 25.6222119 10.51189668
OS 25.61389086 10.50357564
OS 25.61111718 10.4998774
OS 25.60926806 10.49710372
OS 25.60741894 10.49617916
OS 25.60741894 10.4952546
OS 25.60094702 10.48415988
OS 25.59539966 10.47121604
OS 25.5898523 10.45642308
OS 25.58615406 10.44070556
OS 25.58245582 10.42406348
OS 25.57968214 10.40649684
OS 25.57505934 10.37136356
OS 25.57321022 10.35379692
OS 25.57228566 10.3380794
OS 25.5713611 10.32328644
OS 25.5713611 10.31126716
OS 25.57043654 10.30017244
OS 25.57043654 10.2918514
OS 25.57043654 10.2872286
OS 25.57043654 10.28630404
OS 25.57043654 10.28537948
OS 25.57043654 10.25671812
OS 25.57228566 10.23083044
OS 25.57413478 10.20771644
OS 25.5759839 10.185527
OS 25.57875758 10.1670358
OS 25.58245582 10.14946916
OS 25.58615406 10.1346762
OS 25.58892774 10.1208078
OS 25.59262598 10.10971308
OS 25.59632422 10.10046748
OS 25.5990979 10.09214644
OS 25.60279614 10.08567452
OS 25.60464526 10.08105172
OS 25.60649438 10.07827804
OS 25.6083435 10.07642892
OS 25.6083435 10.07550436
OS 25.61573998 10.06625876
OS 25.62313646 10.05886228
OS 25.63053294 10.0514658
OS 25.63792942 10.04591844
OS 25.65364694 10.03667284
OS 25.66751534 10.03020092
OS 25.68045918 10.02650268
OS 25.68970478 10.02465356
OS 25.69340302 10.023729
OS 25.69895038 10.023729
OS 25.70912054 10.02465356
OS 25.71836614 10.02557812
OS 25.73593278 10.03205004
OS 25.7516503 10.04037108
OS 25.7655187 10.04961668
OS 25.77568886 10.05886228
OS 25.7840099 10.06718332
OS 25.7886327 10.07365524
OS 25.79048182 10.0745798
OS 25.79048182 10.07550436
OS 25.79695374 10.08659908
OS 25.8025011 10.09954292
OS 25.80804846 10.11433588
OS 25.8117467 10.1300534
OS 25.81544494 10.14669548
OS 25.81821862 10.16426212
OS 25.82284142 10.20031996
OS 25.82469054 10.21696204
OS 25.8256151 10.23267956
OS 25.82653966 10.24747252
OS 25.82653966 10.2594918
OS 25.82746422 10.27058652
OS 25.82746422 10.27890756
OS 25.82746422 10.28353036
OS 25.82746422 10.28537948
OS 25.82653966 10.31404084
OS 25.8256151 10.33992852
OS 25.82376598 10.36396708
OS 25.8209923 10.38615652
OS 25.81821862 10.40557228
OS 25.81452038 10.42313892
OS 25.81082214 10.43885644
OS 25.8071239 10.45272484
OS 25.80342566 10.46474412
OS 25.80065198 10.47491428
OS 25.79695374 10.48323532
OS 25.79418006 10.4906318
OS 25.79140638 10.4952546
OS 25.78955726 10.49895284
OS 25.78770814 10.50080196
OS 25.78770814 10.50172652
OS 25.78123622 10.51004756
OS 25.7747643 10.51744404
OS 25.76736782 10.5229914
OS 25.75997134 10.52853876
OS 25.74517838 10.5368598
OS 25.73130998 10.54240716
OS 25.7192907 10.54518084
OS 25.70912054 10.54702996
OS 25.7054223 10.54795452
OS 25.69987494 10.54795452
OE
SE
S P 0
OB 28.83724484 16.54452876 I
OS 28.83724484 17.10851036
OS 28.92230436 17.10851036
OS 28.92230436 16.46871484
OS 28.52196988 16.46871484
OS 28.52196988 16.54452876
OS 28.83724484 16.54452876
OE
OB 28.15769324 16.46871484 I
OS 28.15769324 17.11128404
OS 28.20854404 17.11128404
OS 28.21778964 17.09556652
OS 28.2279598 17.08077356
OS 28.23997908 17.0659806
OS 28.2510738 17.05303676
OS 28.26216852 17.04194204
OS 28.27048956 17.03269644
OS 28.2741878 17.02992276
OS 28.27696148 17.02714908
OS 28.27788604 17.02622452
OS 28.2788106 17.02529996
OS 28.29822636 17.00958244
OS 28.31764212 16.99478948
OS 28.33613332 16.98184564
OS 28.35462452 16.97167548
OS 28.37034204 16.96242988
OS 28.37681396 16.95873164
OS 28.38236132 16.95595796
OS 28.38698412 16.95318428
OS 28.39068236 16.95225972
OS 28.39253148 16.9504106
OS 28.39345604 16.9504106
OS 28.39345604 16.87459668
OS 28.37958764 16.88014404
OS 28.36571924 16.88661596
OS 28.35185084 16.89308788
OS 28.338907 16.8995598
OS 28.32781228 16.90510716
OS 28.31856668 16.90972996
OS 28.31301932 16.9134282
OS 28.31209476 16.91435276
OS 28.3111702 16.91435276
OS 28.29452812 16.92452292
OS 28.27973516 16.93469308
OS 28.26679132 16.94393868
OS 28.25662116 16.95225972
OS 28.24737556 16.95873164
OS 28.2418282 16.964279
OS 28.2372054 16.96797724
OS 28.23628084 16.9689018
OS 28.23628084 16.46871484
OS 28.15769324 16.46871484
OE
SE
S P 0
OB 35.73690338 -37.45999874 I
OS 35.61486146 -37.45999874
OS 35.61486146 -36.65701838
OS 35.33471978 -37.45999874
OS 35.2209989 -37.45999874
OS 34.9436309 -36.64314998
OS 34.9436309 -37.45999874
OS 34.82158898 -37.45999874
OS 34.82158898 -36.50030546
OS 35.01158606 -36.50030546
OS 35.23902782 -37.1812439
OS 35.23902782 -37.18263074
OS 35.24041466 -37.18540442
OS 35.2418015 -37.18956494
OS 35.24457518 -37.19649914
OS 35.25012254 -37.21314122
OS 35.25705674 -37.23394382
OS 35.26399094 -37.2575201
OS 35.27231198 -37.28109638
OS 35.27924618 -37.30328582
OS 35.28479354 -37.32270158
OS 35.28618038 -37.3199279
OS 35.28756722 -37.3129937
OS 35.29172774 -37.30051214
OS 35.2972751 -37.28387006
OS 35.3042093 -37.26168062
OS 35.31391718 -37.23533066
OS 35.32362506 -37.20482018
OS 35.33610662 -37.16876234
OS 35.56632206 -36.50030546
OS 35.73690338 -36.50030546
OS 35.73690338 -37.45999874
OE
OB 34.61356298 -37.05504146 I
OS 34.61356298 -37.0564283
OS 34.61356298 -37.06197566
OS 34.61356298 -37.06890986
OS 34.61356298 -37.07861774
OS 34.61217614 -37.0910993
OS 34.61217614 -37.1049677
OS 34.6107893 -37.12160978
OS 34.60940246 -37.13825186
OS 34.60524194 -37.17569654
OS 34.59969458 -37.21452806
OS 34.59137354 -37.25197274
OS 34.58582618 -37.27000166
OS 34.58027882 -37.28664374
OS 34.58027882 -37.28803058
OS 34.57889198 -37.29080426
OS 34.5761183 -37.29496478
OS 34.57334462 -37.30051214
OS 34.56502358 -37.31576738
OS 34.55254202 -37.33518314
OS 34.53589994 -37.35737258
OS 34.51648418 -37.37956202
OS 34.49152106 -37.4031383
OS 34.46101058 -37.4239409
OS 34.45962374 -37.4239409
OS 34.45685006 -37.42671458
OS 34.45268954 -37.42810142
OS 34.44575534 -37.43226194
OS 34.4374343 -37.43642246
OS 34.42633958 -37.44058298
OS 34.41524486 -37.4447435
OS 34.40137646 -37.45029086
OS 34.38612122 -37.45583822
OS 34.36947914 -37.45999874
OS 34.35145022 -37.46415926
OS 34.33064762 -37.46831978
OS 34.30984502 -37.47109346
OS 34.28765558 -37.47386714
OS 34.23772934 -37.47664082
OS 34.22524778 -37.47664082
OS 34.2155399 -37.47525398
OS 34.20444518 -37.47525398
OS 34.19057678 -37.47386714
OS 34.17532154 -37.4724803
OS 34.1600663 -37.47109346
OS 34.1253953 -37.4655461
OS 34.08795062 -37.45722506
OS 34.05189278 -37.44613034
OS 34.01722178 -37.4308751
OS 34.01583494 -37.4308751
OS 34.01306126 -37.42810142
OS 34.00890074 -37.42532774
OS 34.00335338 -37.42255406
OS 33.98809814 -37.41145934
OS 33.97006922 -37.3962041
OS 33.94926662 -37.37678834
OS 33.92985086 -37.3545989
OS 33.9104351 -37.3268621
OS 33.89517986 -37.29635162
OS 33.89517986 -37.29496478
OS 33.89379302 -37.2921911
OS 33.89240618 -37.28664374
OS 33.8896325 -37.27970954
OS 33.88685882 -37.2713885
OS 33.88408514 -37.26029378
OS 33.87992462 -37.24781222
OS 33.87715094 -37.23255698
OS 33.87437726 -37.2159149
OS 33.87021674 -37.19788598
OS 33.86744306 -37.17847022
OS 33.86466938 -37.15766762
OS 33.8618957 -37.13409134
OS 33.86050886 -37.10912822
OS 33.85912202 -37.08277826
OS 33.85912202 -37.05504146
OS 33.85912202 -36.50030546
OS 33.9867113 -36.50030546
OS 33.9867113 -37.05504146
OS 33.9867113 -37.0564283
OS 33.9867113 -37.06058882
OS 33.9867113 -37.06752302
OS 33.9867113 -37.07584406
OS 33.98809814 -37.08555194
OS 33.98809814 -37.0980335
OS 33.98948498 -37.12438346
OS 33.99225866 -37.15489394
OS 33.99641918 -37.18540442
OS 34.00196654 -37.21452806
OS 34.00474022 -37.22700962
OS 34.00890074 -37.23949118
OS 34.01028758 -37.24226486
OS 34.01306126 -37.24919906
OS 34.01999546 -37.25890694
OS 34.0283165 -37.27277534
OS 34.03802438 -37.28664374
OS 34.05189278 -37.30189898
OS 34.06853486 -37.31715422
OS 34.08795062 -37.32963578
OS 34.0907243 -37.33102262
OS 34.0976585 -37.33518314
OS 34.11014006 -37.33934366
OS 34.12678214 -37.34489102
OS 34.1461979 -37.35182522
OS 34.17116102 -37.35598574
OS 34.19751098 -37.36014626
OS 34.22663462 -37.3615331
OS 34.24050302 -37.3615331
OS 34.24882406 -37.36014626
OS 34.26130562 -37.36014626
OS 34.27378718 -37.35875942
OS 34.30429766 -37.35321206
OS 34.33758182 -37.34627786
OS 34.36947914 -37.33518314
OS 34.39998962 -37.3199279
OS 34.41385802 -37.31022002
OS 34.42633958 -37.2991253
OS 34.42772642 -37.29773846
OS 34.42911326 -37.29635162
OS 34.43188694 -37.2921911
OS 34.43604746 -37.28664374
OS 34.44020798 -37.2783227
OS 34.44575534 -37.27000166
OS 34.4513027 -37.2575201
OS 34.45685006 -37.24503854
OS 34.46239742 -37.2297833
OS 34.46655794 -37.21175438
OS 34.4721053 -37.19095178
OS 34.47626582 -37.16876234
OS 34.48042634 -37.14379922
OS 34.48320002 -37.11744926
OS 34.4859737 -37.08693878
OS 34.4859737 -37.05504146
OS 34.4859737 -36.50030546
OS 34.61356298 -36.50030546
OS 34.61356298 -37.05504146
OE
OB 33.64416182 -37.45999874 I
OS 33.51241202 -37.45999874
OS 33.01037594 -36.70694462
OS 33.01037594 -37.45999874
OS 32.88833402 -37.45999874
OS 32.88833402 -36.50030546
OS 33.01869698 -36.50030546
OS 33.5221199 -37.25474642
OS 33.5221199 -36.50030546
OS 33.64416182 -36.50030546
OS 33.64416182 -37.45999874
OE
OB 38.19022334 -36.5016923 I
OS 38.2027049 -36.5016923
OS 38.23182854 -36.50307914
OS 38.26233902 -36.50723966
OS 38.29562318 -36.51140018
OS 38.32613366 -36.51833438
OS 38.3413889 -36.5224949
OS 38.35387046 -36.52665542
OS 38.3552573 -36.52665542
OS 38.35664414 -36.52804226
OS 38.36496518 -36.53220278
OS 38.37744674 -36.53775014
OS 38.39270198 -36.54745802
OS 38.40934406 -36.55993958
OS 38.42737298 -36.57658166
OS 38.44401506 -36.59599742
OS 38.46065714 -36.61818686
OS 38.46065714 -36.6195737
OS 38.46204398 -36.62096054
OS 38.46759134 -36.62928158
OS 38.4731387 -36.64314998
OS 38.48145974 -36.6611789
OS 38.48839394 -36.6819815
OS 38.49532814 -36.70694462
OS 38.49948866 -36.73329458
OS 38.5008755 -36.76241822
OS 38.5008755 -36.76380506
OS 38.5008755 -36.76657874
OS 38.5008755 -36.7721261
OS 38.49948866 -36.7790603
OS 38.49948866 -36.78876818
OS 38.49810182 -36.79847606
OS 38.49255446 -36.82205234
OS 38.48423342 -36.84978914
OS 38.4731387 -36.87891278
OS 38.45649662 -36.90803642
OS 38.4454019 -36.92190482
OS 38.43430718 -36.93577322
OS 38.43292034 -36.93716006
OS 38.4315335 -36.9385469
OS 38.42737298 -36.94270742
OS 38.42182562 -36.94686794
OS 38.41489142 -36.9524153
OS 38.40657038 -36.95796266
OS 38.39547566 -36.96489686
OS 38.38438094 -36.9732179
OS 38.37051254 -36.9801521
OS 38.3552573 -36.9870863
OS 38.33861522 -36.99540734
OS 38.3205863 -37.00234154
OS 38.2997837 -37.0078889
OS 38.2789811 -37.0148231
OS 38.25540482 -37.01898362
OS 38.2304417 -37.02314414
OS 38.23321538 -37.02453098
OS 38.23876274 -37.02730466
OS 38.24708378 -37.03285202
OS 38.2581785 -37.03839938
OS 38.28314162 -37.05365462
OS 38.29562318 -37.0633625
OS 38.3067179 -37.07168354
OS 38.30949158 -37.07445722
OS 38.31642578 -37.08139142
OS 38.3275205 -37.09248614
OS 38.3413889 -37.10635454
OS 38.35664414 -37.1257703
OS 38.37467306 -37.1465729
OS 38.39270198 -37.17153602
OS 38.41211774 -37.19927282
OS 38.5771517 -37.45999874
OS 38.41905194 -37.45999874
OS 38.2928495 -37.26029378
OS 38.2928495 -37.25890694
OS 38.29007582 -37.25613326
OS 38.28730214 -37.25197274
OS 38.28314162 -37.24642538
OS 38.27343374 -37.23117014
OS 38.26095218 -37.21175438
OS 38.24569694 -37.19095178
OS 38.2304417 -37.16876234
OS 38.21518646 -37.14795974
OS 38.20131806 -37.12854398
OS 38.19993122 -37.12715714
OS 38.1957707 -37.12160978
OS 38.1888365 -37.11328874
OS 38.17912862 -37.10358086
OS 38.15832602 -37.08277826
OS 38.1472313 -37.07307038
OS 38.13613658 -37.06474934
OS 38.13474974 -37.0633625
OS 38.13197606 -37.06197566
OS 38.1264287 -37.05920198
OS 38.11810766 -37.05504146
OS 38.10978662 -37.05088094
OS 38.10007874 -37.04672042
OS 38.0778893 -37.03978622
OS 38.07650246 -37.03978622
OS 38.07372878 -37.03839938
OS 38.06818142 -37.03839938
OS 38.06124722 -37.03701254
OS 38.05153934 -37.0356257
OS 38.04044462 -37.0356257
OS 38.02518938 -37.03423886
OS 37.86154226 -37.03423886
OS 37.86154226 -37.45999874
OS 37.73395298 -37.45999874
OS 37.73395298 -36.50030546
OS 38.17912862 -36.50030546
OS 38.19022334 -36.5016923
OE
OB 37.53424802 -36.61402634 I
OS 36.96703046 -36.61402634
OS 36.96703046 -36.90664958
OS 37.49819018 -36.90664958
OS 37.49819018 -37.02037046
OS 36.96703046 -37.02037046
OS 36.96703046 -37.34627786
OS 37.55643746 -37.34627786
OS 37.55643746 -37.45999874
OS 36.83944118 -37.45999874
OS 36.83944118 -36.50030546
OS 37.53424802 -36.50030546
OS 37.53424802 -36.61402634
OE
OB 36.32492354 -36.5016923 I
OS 36.33601826 -36.5016923
OS 36.36098138 -36.50446598
OS 36.38871818 -36.50723966
OS 36.41784182 -36.51278702
OS 36.44696546 -36.51972122
OS 36.47331542 -36.5294291
OS 36.47470226 -36.5294291
OS 36.4760891 -36.53081594
OS 36.48441014 -36.53497646
OS 36.4968917 -36.54191066
OS 36.5107601 -36.55161854
OS 36.52740218 -36.5641001
OS 36.5454311 -36.57935534
OS 36.56207318 -36.5987711
OS 36.57732842 -36.6195737
OS 36.57871526 -36.62234738
OS 36.58287578 -36.63066842
OS 36.58980998 -36.64176314
OS 36.59674418 -36.65840522
OS 36.60367838 -36.67782098
OS 36.61061258 -36.69862358
OS 36.6147731 -36.72219986
OS 36.61615994 -36.74577614
OS 36.61615994 -36.74854982
OS 36.61615994 -36.75548402
OS 36.6147731 -36.76796558
OS 36.61199942 -36.78322082
OS 36.6078389 -36.80124974
OS 36.6009047 -36.8206655
OS 36.59258366 -36.84008126
OS 36.58148894 -36.86088386
OS 36.5801021 -36.86365754
OS 36.57594158 -36.8692049
OS 36.56762054 -36.88029962
OS 36.55652582 -36.89139434
OS 36.54265742 -36.90526274
OS 36.52601534 -36.92051798
OS 36.50521274 -36.93438638
OS 36.48163646 -36.94825478
OS 36.4830233 -36.94825478
OS 36.48579698 -36.94964162
OS 36.4899575 -36.95102846
OS 36.49550486 -36.95380214
OS 36.51214694 -36.9593495
OS 36.5315627 -36.96905738
OS 36.5523653 -36.98153894
OS 36.57594158 -36.99679418
OS 36.59674418 -37.0148231
OS 36.61615994 -37.03701254
OS 36.61754678 -37.03978622
OS 36.62309414 -37.04810726
OS 36.63141518 -37.06058882
OS 36.63973622 -37.0772309
OS 36.64805726 -37.09942034
OS 36.6563783 -37.12299662
OS 36.66192566 -37.15073342
OS 36.6633125 -37.1812439
OS 36.6633125 -37.18263074
OS 36.6633125 -37.18401758
OS 36.6633125 -37.19233862
OS 36.66192566 -37.20620702
OS 36.65915198 -37.2228491
OS 36.6563783 -37.24226486
OS 36.65083094 -37.26306746
OS 36.64389674 -37.2852569
OS 36.63418886 -37.30744634
OS 36.63280202 -37.31022002
OS 36.6286415 -37.31715422
OS 36.62309414 -37.3268621
OS 36.6147731 -37.3407305
OS 36.60367838 -37.3545989
OS 36.59258366 -37.36985414
OS 36.57871526 -37.38510938
OS 36.56346002 -37.39759094
OS 36.56207318 -37.39897778
OS 36.55652582 -37.4031383
OS 36.54681794 -37.40868566
OS 36.53433638 -37.41423302
OS 36.51908114 -37.42255406
OS 36.50105222 -37.4308751
OS 36.48163646 -37.4378093
OS 36.45806018 -37.4447435
OS 36.4552865 -37.4447435
OS 36.44696546 -37.44751718
OS 36.43309706 -37.44890402
OS 36.41506814 -37.4516777
OS 36.3928787 -37.45445138
OS 36.36652874 -37.45722506
OS 36.3374051 -37.4586119
OS 36.30412094 -37.45999874
OS 35.93799518 -37.45999874
OS 35.93799518 -36.50030546
OS 36.31521566 -36.50030546
OS 36.32492354 -36.5016923
OE
OB 32.3849111 -36.61402634 I
OS 32.06871158 -36.61402634
OS 32.06871158 -37.45999874
OS 31.9411223 -37.45999874
OS 31.9411223 -36.61402634
OS 31.62492278 -36.61402634
OS 31.62492278 -36.50030546
OS 32.3849111 -36.50030546
OS 32.3849111 -36.61402634
OE
OB 30.62639798 -37.45999874 I
OS 30.48216662 -37.45999874
OS 30.36983258 -37.16876234
OS 29.96764898 -37.16876234
OS 29.86363598 -37.45999874
OS 29.7291125 -37.45999874
OS 30.09523826 -36.50030546
OS 30.23392226 -36.50030546
OS 30.62639798 -37.45999874
OE
OB 29.3546657 -36.5016923 I
OS 29.37824198 -36.50307914
OS 29.4032051 -36.50446598
OS 29.42678138 -36.50723966
OS 29.44758398 -36.51001334
OS 29.45035766 -36.51001334
OS 29.46006554 -36.51278702
OS 29.4725471 -36.5155607
OS 29.48918918 -36.51972122
OS 29.5072181 -36.52665542
OS 29.52663386 -36.53497646
OS 29.54743646 -36.54468434
OS 29.56546538 -36.55577906
OS 29.56823906 -36.5571659
OS 29.57378642 -36.56132642
OS 29.58210746 -36.56964746
OS 29.59320218 -36.57935534
OS 29.60568374 -36.5918369
OS 29.6181653 -36.60847898
OS 29.6320337 -36.6265079
OS 29.64312842 -36.6473105
OS 29.64451526 -36.65008418
OS 29.64728894 -36.65701838
OS 29.6528363 -36.66949994
OS 29.65838366 -36.68614202
OS 29.66254418 -36.70555778
OS 29.66809154 -36.72774722
OS 29.67086522 -36.75271034
OS 29.67225206 -36.7790603
OS 29.67225206 -36.78044714
OS 29.67225206 -36.78460766
OS 29.67225206 -36.79015502
OS 29.67086522 -36.7998629
OS 29.66947838 -36.80957078
OS 29.66809154 -36.82205234
OS 29.66531786 -36.83592074
OS 29.66254418 -36.85117598
OS 29.6528363 -36.8830733
OS 29.64728894 -36.89971538
OS 29.6389679 -36.9177443
OS 29.62926002 -36.93577322
OS 29.61955214 -36.9524153
OS 29.60707058 -36.96905738
OS 29.59320218 -36.98569946
OS 29.59181534 -36.9870863
OS 29.58904166 -36.98985998
OS 29.58488114 -36.9940205
OS 29.57794694 -36.99818102
OS 29.5696259 -37.00511522
OS 29.55853118 -37.01204942
OS 29.54466278 -37.02037046
OS 29.52940754 -37.02730466
OS 29.51137862 -37.0356257
OS 29.49057602 -37.04394674
OS 29.46838658 -37.05088094
OS 29.44203662 -37.0564283
OS 29.41429982 -37.06197566
OS 29.38378934 -37.06613618
OS 29.34911834 -37.06890986
OS 29.3130605 -37.0702967
OS 29.06758982 -37.0702967
OS 29.06758982 -37.45999874
OS 28.94000054 -37.45999874
OS 28.94000054 -36.50030546
OS 29.3338631 -36.50030546
OS 29.3546657 -36.5016923
OE
OB 31.18668134 -36.5016923 I
OS 31.1991629 -36.5016923
OS 31.22828654 -36.50307914
OS 31.25879702 -36.50723966
OS 31.29208118 -36.51140018
OS 31.32259166 -36.51833438
OS 31.3378469 -36.5224949
OS 31.35032846 -36.52665542
OS 31.3517153 -36.52665542
OS 31.35310214 -36.52804226
OS 31.36142318 -36.53220278
OS 31.37390474 -36.53775014
OS 31.38915998 -36.54745802
OS 31.40580206 -36.55993958
OS 31.42383098 -36.57658166
OS 31.44047306 -36.59599742
OS 31.45711514 -36.61818686
OS 31.45711514 -36.6195737
OS 31.45850198 -36.62096054
OS 31.46404934 -36.62928158
OS 31.4695967 -36.64314998
OS 31.47791774 -36.6611789
OS 31.48485194 -36.6819815
OS 31.49178614 -36.70694462
OS 31.49594666 -36.73329458
OS 31.4973335 -36.76241822
OS 31.4973335 -36.76380506
OS 31.4973335 -36.76657874
OS 31.4973335 -36.7721261
OS 31.49594666 -36.7790603
OS 31.49594666 -36.78876818
OS 31.49455982 -36.79847606
OS 31.48901246 -36.82205234
OS 31.48069142 -36.84978914
OS 31.4695967 -36.87891278
OS 31.45295462 -36.90803642
OS 31.4418599 -36.92190482
OS 31.43076518 -36.93577322
OS 31.42937834 -36.93716006
OS 31.4279915 -36.9385469
OS 31.42383098 -36.94270742
OS 31.41828362 -36.94686794
OS 31.41134942 -36.9524153
OS 31.40302838 -36.95796266
OS 31.39193366 -36.96489686
OS 31.38083894 -36.9732179
OS 31.36697054 -36.9801521
OS 31.3517153 -36.9870863
OS 31.33507322 -36.99540734
OS 31.3170443 -37.00234154
OS 31.2962417 -37.0078889
OS 31.2754391 -37.0148231
OS 31.25186282 -37.01898362
OS 31.2268997 -37.02314414
OS 31.22967338 -37.02453098
OS 31.23522074 -37.02730466
OS 31.24354178 -37.03285202
OS 31.2546365 -37.03839938
OS 31.27959962 -37.05365462
OS 31.29208118 -37.0633625
OS 31.3031759 -37.07168354
OS 31.30594958 -37.07445722
OS 31.31288378 -37.08139142
OS 31.3239785 -37.09248614
OS 31.3378469 -37.10635454
OS 31.35310214 -37.1257703
OS 31.37113106 -37.1465729
OS 31.38915998 -37.17153602
OS 31.40857574 -37.19927282
OS 31.5736097 -37.45999874
OS 31.41550994 -37.45999874
OS 31.2893075 -37.26029378
OS 31.2893075 -37.25890694
OS 31.28653382 -37.25613326
OS 31.28376014 -37.25197274
OS 31.27959962 -37.24642538
OS 31.26989174 -37.23117014
OS 31.25741018 -37.21175438
OS 31.24215494 -37.19095178
OS 31.2268997 -37.16876234
OS 31.21164446 -37.14795974
OS 31.19777606 -37.12854398
OS 31.19638922 -37.12715714
OS 31.1922287 -37.12160978
OS 31.1852945 -37.11328874
OS 31.17558662 -37.10358086
OS 31.15478402 -37.08277826
OS 31.1436893 -37.07307038
OS 31.13259458 -37.06474934
OS 31.13120774 -37.0633625
OS 31.12843406 -37.06197566
OS 31.1228867 -37.05920198
OS 31.11456566 -37.05504146
OS 31.10624462 -37.05088094
OS 31.09653674 -37.04672042
OS 31.0743473 -37.03978622
OS 31.07296046 -37.03978622
OS 31.07018678 -37.03839938
OS 31.06463942 -37.03839938
OS 31.05770522 -37.03701254
OS 31.04799734 -37.0356257
OS 31.03690262 -37.0356257
OS 31.02164738 -37.03423886
OS 30.85800026 -37.03423886
OS 30.85800026 -37.45999874
OS 30.73041098 -37.45999874
OS 30.73041098 -36.50030546
OS 31.17558662 -36.50030546
OS 31.18668134 -36.5016923
OE
OB 38.16387338 -36.60709214 H
OS 37.86154226 -36.60709214
OS 37.86154226 -36.9246785
OS 38.1472313 -36.9246785
OS 38.16387338 -36.92329166
OS 38.18328914 -36.92190482
OS 38.20547858 -36.92051798
OS 38.22766802 -36.9177443
OS 38.24985746 -36.91358378
OS 38.26927322 -36.90803642
OS 38.2720469 -36.90664958
OS 38.27759426 -36.9038759
OS 38.2859153 -36.89971538
OS 38.29701002 -36.89416802
OS 38.30949158 -36.88584698
OS 38.32197314 -36.8761391
OS 38.3344547 -36.86365754
OS 38.34416258 -36.84978914
OS 38.34554942 -36.8484023
OS 38.3483231 -36.84285494
OS 38.35248362 -36.8345339
OS 38.35803098 -36.82343918
OS 38.3621915 -36.81095762
OS 38.36635202 -36.79708922
OS 38.3691257 -36.78044714
OS 38.37051254 -36.76380506
OS 38.37051254 -36.76241822
OS 38.37051254 -36.76103138
OS 38.3691257 -36.75271034
OS 38.36773886 -36.74022878
OS 38.36496518 -36.7235867
OS 38.35803098 -36.70694462
OS 38.34970994 -36.68752886
OS 38.33722838 -36.66949994
OS 38.3205863 -36.65147102
OS 38.31781262 -36.65008418
OS 38.31087842 -36.64453682
OS 38.2997837 -36.63760262
OS 38.28175478 -36.62928158
OS 38.26095218 -36.62096054
OS 38.23321538 -36.61402634
OS 38.20131806 -36.60847898
OS 38.16387338 -36.60709214
OE
OB 29.34218414 -36.61402634 H
OS 29.06758982 -36.61402634
OS 29.06758982 -36.95657582
OS 29.32554206 -36.95657582
OS 29.33524994 -36.95518898
OS 29.34495782 -36.95518898
OS 29.35605254 -36.95380214
OS 29.3824025 -36.95102846
OS 29.41152614 -36.9454811
OS 29.44064978 -36.93716006
OS 29.46699974 -36.92606534
OS 29.4794813 -36.91913114
OS 29.48918918 -36.9108101
OS 29.49196286 -36.90803642
OS 29.49751022 -36.90248906
OS 29.50583126 -36.89139434
OS 29.51553914 -36.87752594
OS 29.52524702 -36.85949702
OS 29.53356806 -36.83730758
OS 29.53911542 -36.81234446
OS 29.5418891 -36.78322082
OS 29.5418891 -36.78183398
OS 29.5418891 -36.78044714
OS 29.5418891 -36.77351294
OS 29.54050226 -36.76103138
OS 29.53772858 -36.74716298
OS 29.5349549 -36.73190774
OS 29.52940754 -36.71387882
OS 29.5210865 -36.69723674
OS 29.51137862 -36.68059466
OS 29.50999178 -36.67920782
OS 29.50583126 -36.67366046
OS 29.49889706 -36.66672626
OS 29.49057602 -36.65701838
OS 29.47809446 -36.6473105
OS 29.46422606 -36.63898946
OS 29.44897082 -36.63066842
OS 29.4309419 -36.62373422
OS 29.42955506 -36.62373422
OS 29.4240077 -36.62234738
OS 29.41568666 -36.62096054
OS 29.40459194 -36.61818686
OS 29.38794986 -36.61680002
OS 29.36714726 -36.61541318
OS 29.34218414 -36.61402634
OE
OB 30.16180658 -36.60015794 H
OS 30.16180658 -36.60154478
OS 30.16041974 -36.60431846
OS 30.16041974 -36.60986582
OS 30.15764606 -36.61541318
OS 30.15625922 -36.62512106
OS 30.15348554 -36.63482894
OS 30.14793818 -36.65840522
OS 30.14100398 -36.68614202
OS 30.1312961 -36.7166525
OS 30.12158822 -36.74993666
OS 30.10910666 -36.78460766
OS 30.00509366 -37.06474934
OS 30.32961422 -37.06474934
OS 30.22976174 -36.80124974
OS 30.22976174 -36.7998629
OS 30.2283749 -36.79570238
OS 30.22560122 -36.78876818
OS 30.22282754 -36.78044714
OS 30.21866702 -36.77073926
OS 30.2145065 -36.7582577
OS 30.21034598 -36.7443893
OS 30.20479862 -36.7305209
OS 30.1937039 -36.69862358
OS 30.18260918 -36.66533942
OS 30.17151446 -36.63205526
OS 30.16180658 -36.60015794
OE
OB 31.16033138 -36.60709214 H
OS 30.85800026 -36.60709214
OS 30.85800026 -36.9246785
OS 31.1436893 -36.9246785
OS 31.16033138 -36.92329166
OS 31.17974714 -36.92190482
OS 31.20193658 -36.92051798
OS 31.22412602 -36.9177443
OS 31.24631546 -36.91358378
OS 31.26573122 -36.90803642
OS 31.2685049 -36.90664958
OS 31.27405226 -36.9038759
OS 31.2823733 -36.89971538
OS 31.29346802 -36.89416802
OS 31.30594958 -36.88584698
OS 31.31843114 -36.8761391
OS 31.3309127 -36.86365754
OS 31.34062058 -36.84978914
OS 31.34200742 -36.8484023
OS 31.3447811 -36.84285494
OS 31.34894162 -36.8345339
OS 31.35448898 -36.82343918
OS 31.3586495 -36.81095762
OS 31.36281002 -36.79708922
OS 31.3655837 -36.78044714
OS 31.36697054 -36.76380506
OS 31.36697054 -36.76241822
OS 31.36697054 -36.76103138
OS 31.3655837 -36.75271034
OS 31.36419686 -36.74022878
OS 31.36142318 -36.7235867
OS 31.35448898 -36.70694462
OS 31.34616794 -36.68752886
OS 31.33368638 -36.66949994
OS 31.3170443 -36.65147102
OS 31.31427062 -36.65008418
OS 31.30733642 -36.64453682
OS 31.2962417 -36.63760262
OS 31.27821278 -36.62928158
OS 31.25741018 -36.62096054
OS 31.22967338 -36.61402634
OS 31.19777606 -36.60847898
OS 31.16033138 -36.60709214
OE
OB 36.29302622 -36.61402634 H
OS 36.06558446 -36.61402634
OS 36.06558446 -36.90248906
OS 36.30134726 -36.90248906
OS 36.31937618 -36.90110222
OS 36.33879194 -36.89971538
OS 36.3582077 -36.89832854
OS 36.37762346 -36.89555486
OS 36.3928787 -36.89278118
OS 36.39565238 -36.89139434
OS 36.40119974 -36.8900075
OS 36.40952078 -36.88584698
OS 36.4206155 -36.88029962
OS 36.43171022 -36.87475226
OS 36.44419178 -36.86643122
OS 36.45667334 -36.8553365
OS 36.46638122 -36.84424178
OS 36.46776806 -36.84285494
OS 36.47054174 -36.83869442
OS 36.47470226 -36.83037338
OS 36.47886278 -36.8206655
OS 36.4830233 -36.80957078
OS 36.48718382 -36.79570238
OS 36.4899575 -36.7790603
OS 36.49134434 -36.76103138
OS 36.49134434 -36.7582577
OS 36.49134434 -36.75271034
OS 36.4899575 -36.7443893
OS 36.48857066 -36.73329458
OS 36.48579698 -36.71942618
OS 36.48163646 -36.70555778
OS 36.4760891 -36.69168938
OS 36.46776806 -36.67782098
OS 36.46638122 -36.67643414
OS 36.46360754 -36.67227362
OS 36.45806018 -36.66533942
OS 36.45112598 -36.65840522
OS 36.4414181 -36.65008418
OS 36.43032338 -36.64176314
OS 36.41645498 -36.6334421
OS 36.40119974 -36.62789474
OS 36.3998129 -36.62789474
OS 36.3928787 -36.62512106
OS 36.38317082 -36.62373422
OS 36.36791558 -36.62096054
OS 36.34711298 -36.61818686
OS 36.3235367 -36.61680002
OS 36.29302622 -36.61402634
OE
OB 36.31798934 -37.01620994 H
OS 36.06558446 -37.01620994
OS 36.06558446 -37.34627786
OS 36.33879194 -37.34627786
OS 36.36791558 -37.34489102
OS 36.38039714 -37.34350418
OS 36.39149186 -37.34211734
OS 36.3928787 -37.34211734
OS 36.39842606 -37.3407305
OS 36.4067471 -37.33934366
OS 36.41645498 -37.33656998
OS 36.44003126 -37.32824894
OS 36.46360754 -37.31715422
OS 36.46499438 -37.31576738
OS 36.4691549 -37.3129937
OS 36.47470226 -37.30883318
OS 36.48163646 -37.30328582
OS 36.48857066 -37.29496478
OS 36.49827854 -37.28664374
OS 36.50521274 -37.27554902
OS 36.51353378 -37.26306746
OS 36.51492062 -37.26168062
OS 36.51630746 -37.2575201
OS 36.51908114 -37.24919906
OS 36.52324166 -37.23949118
OS 36.52740218 -37.22839646
OS 36.53017586 -37.21452806
OS 36.5315627 -37.19788598
OS 36.53294954 -37.1812439
OS 36.53294954 -37.17847022
OS 36.53294954 -37.17292286
OS 36.5315627 -37.16182814
OS 36.52878902 -37.14934658
OS 36.52601534 -37.13547818
OS 36.52046798 -37.12022294
OS 36.51353378 -37.1049677
OS 36.5038259 -37.08971246
OS 36.50243906 -37.08832562
OS 36.49827854 -37.08277826
OS 36.49273118 -37.07584406
OS 36.48441014 -37.06752302
OS 36.47331542 -37.05781514
OS 36.45944702 -37.04810726
OS 36.44419178 -37.03978622
OS 36.42616286 -37.03285202
OS 36.42338918 -37.03146518
OS 36.41784182 -37.03007834
OS 36.40536026 -37.02730466
OS 36.39010502 -37.02453098
OS 36.37068926 -37.0217573
OS 36.34711298 -37.01898362
OS 36.31798934 -37.01620994
OE
SE
S P 0
OB 40.9056459 -38.32112732 I
OS 40.92136342 -38.32205188
OS 40.9380055 -38.32297644
OS 40.95372302 -38.32482556
OS 40.96759142 -38.32667468
OS 40.96944054 -38.32667468
OS 40.97591246 -38.3285238
OS 40.9842335 -38.33037292
OS 40.99532822 -38.3331466
OS 41.0073475 -38.3377694
OS 41.02029134 -38.34331676
OS 41.03415974 -38.34978868
OS 41.04617902 -38.35718516
OS 41.04802814 -38.35810972
OS 41.05172638 -38.3608834
OS 41.05727374 -38.36643076
OS 41.06467022 -38.37290268
OS 41.07299126 -38.38122372
OS 41.0813123 -38.39231844
OS 41.0905579 -38.40433772
OS 41.09795438 -38.41820612
OS 41.09887894 -38.42005524
OS 41.10072806 -38.42467804
OS 41.1044263 -38.43299908
OS 41.10812454 -38.4440938
OS 41.11089822 -38.45703764
OS 41.11459646 -38.4718306
OS 41.11644558 -38.48847268
OS 41.11737014 -38.50603932
OS 41.11737014 -38.50696388
OS 41.11737014 -38.50973756
OS 41.11737014 -38.5134358
OS 41.11644558 -38.51990772
OS 41.11552102 -38.52637964
OS 41.11459646 -38.53470068
OS 41.11274734 -38.54394628
OS 41.11089822 -38.55411644
OS 41.1044263 -38.57538132
OS 41.10072806 -38.58647604
OS 41.0951807 -38.59849532
OS 41.08870878 -38.6105146
OS 41.08223686 -38.62160932
OS 41.07391582 -38.63270404
OS 41.06467022 -38.64379876
OS 41.06374566 -38.64472332
OS 41.06189654 -38.64657244
OS 41.05912286 -38.64934612
OS 41.05450006 -38.6521198
OS 41.0489527 -38.6567426
OS 41.04155622 -38.6613654
OS 41.03231062 -38.66691276
OS 41.02214046 -38.67153556
OS 41.01012118 -38.67708292
OS 40.99625278 -38.68263028
OS 40.98145982 -38.68725308
OS 40.96389318 -38.69095132
OS 40.94540198 -38.69464956
OS 40.92506166 -38.69742324
OS 40.90194766 -38.69927236
OS 40.8779091 -38.70019692
OS 40.71426198 -38.70019692
OS 40.71426198 -38.95999828
OS 40.62920246 -38.95999828
OS 40.62920246 -38.32020276
OS 40.8917775 -38.32020276
OS 40.9056459 -38.32112732
OE
OB 40.49791494 -38.98403684 I
OS 40.49791494 -38.9849614
OS 40.49791494 -38.98773508
OS 40.49791494 -38.99235788
OS 40.49791494 -38.99790524
OS 40.49699038 -39.00530172
OS 40.49699038 -39.0126982
OS 40.49514126 -39.0311894
OS 40.49236758 -39.05060516
OS 40.48866934 -39.07094548
OS 40.48312198 -39.08851212
OS 40.47942374 -39.09683316
OS 40.4757255 -39.10330508
OS 40.4757255 -39.10422964
OS 40.47480094 -39.1051542
OS 40.47017814 -39.109777
OS 40.46278166 -39.11717348
OS 40.45353606 -39.12549452
OS 40.44059222 -39.13381556
OS 40.42395014 -39.14028748
OS 40.40453438 -39.14583484
OS 40.39343966 -39.1467594
OS 40.38142038 -39.14768396
OS 40.37587302 -39.14768396
OS 40.37032566 -39.1467594
OS 40.36200462 -39.1467594
OS 40.35275902 -39.14583484
OS 40.34258886 -39.14398572
OS 40.32039942 -39.13843836
OS 40.33519238 -39.07187004
OS 40.33611694 -39.07187004
OS 40.33889062 -39.0727946
OS 40.34351342 -39.07371916
OS 40.34813622 -39.07464372
OS 40.3601555 -39.0774174
OS 40.36570286 -39.07834196
OS 40.37494846 -39.07834196
OS 40.37957126 -39.0774174
OS 40.38511862 -39.07649284
OS 40.39066598 -39.07464372
OS 40.39621334 -39.07094548
OS 40.40268526 -39.06724724
OS 40.40730806 -39.06169988
OS 40.40823262 -39.06077532
OS 40.40915718 -39.05800164
OS 40.4110063 -39.05337884
OS 40.41377998 -39.04598236
OS 40.4156291 -39.0358122
OS 40.41655366 -39.02841572
OS 40.41747822 -39.0219438
OS 40.41840278 -39.01362276
OS 40.41840278 -39.0034526
OS 40.41932734 -38.99328244
OS 40.41932734 -38.98218772
OS 40.41932734 -38.49586916
OS 40.49791494 -38.49586916
OS 40.49791494 -38.98403684
OE
OB 41.51770462 -38.3100326 I
OS 41.52602566 -38.31095716
OS 41.53619582 -38.31188172
OS 41.54636598 -38.31280628
OS 41.55838526 -38.31557996
OS 41.58334838 -38.32112732
OS 41.61108518 -38.32944836
OS 41.62495358 -38.33499572
OS 41.63789742 -38.34146764
OS 41.65084126 -38.34978868
OS 41.6637851 -38.35810972
OS 41.66470966 -38.35903428
OS 41.66655878 -38.35995884
OS 41.67025702 -38.36273252
OS 41.67487982 -38.36735532
OS 41.67950262 -38.37197812
OS 41.68597454 -38.37845004
OS 41.69244646 -38.38584652
OS 41.69984294 -38.393243
OS 41.70723942 -38.4024886
OS 41.7146359 -38.41358332
OS 41.72295694 -38.42467804
OS 41.73035342 -38.43669732
OS 41.73682534 -38.45056572
OS 41.74422182 -38.46443412
OS 41.74976918 -38.47922708
OS 41.75531654 -38.49586916
OS 41.67210614 -38.51528492
OS 41.67210614 -38.51436036
OS 41.67118158 -38.51251124
OS 41.66933246 -38.508813
OS 41.66748334 -38.5041902
OS 41.66563422 -38.49864284
OS 41.66286054 -38.49124636
OS 41.65546406 -38.4764534
OS 41.64621846 -38.45981132
OS 41.63512374 -38.44316924
OS 41.62125534 -38.42745172
OS 41.60646238 -38.41358332
OS 41.60461326 -38.4117342
OS 41.5990659 -38.40803596
OS 41.5898203 -38.40341316
OS 41.57780102 -38.39694124
OS 41.5620835 -38.39139388
OS 41.54451686 -38.38584652
OS 41.52325198 -38.38214828
OS 41.50013798 -38.38122372
OS 41.4927415 -38.38122372
OS 41.4881187 -38.38214828
OS 41.48164678 -38.38214828
OS 41.4742503 -38.38307284
OS 41.45668366 -38.38584652
OS 41.4372679 -38.38954476
OS 41.41692758 -38.39601668
OS 41.3956627 -38.40526228
OS 41.37624694 -38.41728156
OS 41.37532238 -38.41728156
OS 41.37439782 -38.41913068
OS 41.3679259 -38.42375348
OS 41.35960486 -38.43114996
OS 41.3494347 -38.44224468
OS 41.33741542 -38.45611308
OS 41.3263207 -38.4718306
OS 41.31615054 -38.49124636
OS 41.30690494 -38.51251124
OS 41.30690494 -38.5134358
OS 41.30598038 -38.51528492
OS 41.30505582 -38.5180586
OS 41.30413126 -38.5226814
OS 41.30228214 -38.52822876
OS 41.30043302 -38.53470068
OS 41.29765934 -38.5504182
OS 41.2939611 -38.5689094
OS 41.29026286 -38.58924972
OS 41.28841374 -38.61143916
OS 41.28748918 -38.63547772
OS 41.28748918 -38.63640228
OS 41.28748918 -38.63917596
OS 41.28748918 -38.64379876
OS 41.28748918 -38.64934612
OS 41.28841374 -38.65581804
OS 41.28841374 -38.66413908
OS 41.2893383 -38.67338468
OS 41.29026286 -38.68355484
OS 41.29303654 -38.70574428
OS 41.29765934 -38.72978284
OS 41.3032067 -38.7538214
OS 41.31060318 -38.77785996
OS 41.31060318 -38.77878452
OS 41.31152774 -38.78063364
OS 41.31337686 -38.78340732
OS 41.31522598 -38.78803012
OS 41.32077334 -38.79912484
OS 41.32909438 -38.81206868
OS 41.33926454 -38.82686164
OS 41.35220838 -38.84257916
OS 41.36700134 -38.85644756
OS 41.38456798 -38.8693914
OS 41.38549254 -38.8693914
OS 41.38734166 -38.87031596
OS 41.39011534 -38.87216508
OS 41.39381358 -38.8740142
OS 41.39843638 -38.87586332
OS 41.40398374 -38.878637
OS 41.41692758 -38.88418436
OS 41.43356966 -38.88973172
OS 41.45206086 -38.89435452
OS 41.47240118 -38.89805276
OS 41.49366606 -38.89897732
OS 41.50013798 -38.89897732
OS 41.50568534 -38.89805276
OS 41.51215726 -38.89805276
OS 41.51862918 -38.8971282
OS 41.53527126 -38.89342996
OS 41.55468702 -38.88880716
OS 41.57410278 -38.88141068
OS 41.5944431 -38.87124052
OS 41.60461326 -38.86569316
OS 41.61385886 -38.85829668
OS 41.61478342 -38.85737212
OS 41.61570798 -38.85644756
OS 41.61848166 -38.85367388
OS 41.6221799 -38.8509002
OS 41.62587814 -38.8462774
OS 41.63050094 -38.84073004
OS 41.6360483 -38.83518268
OS 41.6406711 -38.8277862
OS 41.64621846 -38.81946516
OS 41.65269038 -38.81021956
OS 41.65823774 -38.80097396
OS 41.6637851 -38.78987924
OS 41.6684079 -38.77785996
OS 41.6730307 -38.76491612
OS 41.6776535 -38.75104772
OS 41.68135174 -38.73625476
OS 41.76641126 -38.75751964
OS 41.76641126 -38.7584442
OS 41.7654867 -38.76214244
OS 41.76363758 -38.7676898
OS 41.7608639 -38.77508628
OS 41.75809022 -38.78340732
OS 41.75439198 -38.79357748
OS 41.74976918 -38.8046722
OS 41.74422182 -38.81669148
OS 41.73127798 -38.84257916
OS 41.7146359 -38.86846684
OS 41.70446574 -38.88141068
OS 41.69429558 -38.89435452
OS 41.68320086 -38.90544924
OS 41.67025702 -38.91654396
OS 41.66933246 -38.91746852
OS 41.66748334 -38.91931764
OS 41.66286054 -38.92116676
OS 41.65823774 -38.924865
OS 41.65084126 -38.9294878
OS 41.64344478 -38.9341106
OS 41.63327462 -38.9387334
OS 41.62310446 -38.9433562
OS 41.61108518 -38.94890356
OS 41.59814134 -38.95352636
OS 41.58427294 -38.95814916
OS 41.56947998 -38.96277196
OS 41.55376246 -38.9664702
OS 41.53712038 -38.96831932
OS 41.51955374 -38.97016844
OS 41.50106254 -38.971093
OS 41.49089238 -38.971093
OS 41.4834959 -38.97016844
OS 41.47517486 -38.97016844
OS 41.4650047 -38.96924388
OS 41.45390998 -38.96739476
OS 41.44096614 -38.96554564
OS 41.4141539 -38.96092284
OS 41.3864171 -38.95352636
OS 41.3586803 -38.9433562
OS 41.34573646 -38.93688428
OS 41.33279262 -38.9294878
OS 41.33186806 -38.92856324
OS 41.33001894 -38.92763868
OS 41.3263207 -38.924865
OS 41.32262246 -38.92116676
OS 41.3170751 -38.91746852
OS 41.31060318 -38.91192116
OS 41.3032067 -38.90544924
OS 41.29581022 -38.89805276
OS 41.28841374 -38.88973172
OS 41.2800927 -38.88141068
OS 41.26345062 -38.8601458
OS 41.2477331 -38.83518268
OS 41.2338647 -38.80744588
OS 41.2338647 -38.80652132
OS 41.23201558 -38.80374764
OS 41.23109102 -38.79912484
OS 41.22831734 -38.79357748
OS 41.22646822 -38.786181
OS 41.22369454 -38.7769354
OS 41.2199963 -38.76676524
OS 41.21722262 -38.75567052
OS 41.21444894 -38.74365124
OS 41.2107507 -38.72978284
OS 41.2061279 -38.70112148
OS 41.20242966 -38.66876188
OS 41.20058054 -38.63547772
OS 41.20058054 -38.63455316
OS 41.20058054 -38.63085492
OS 41.20058054 -38.62530756
OS 41.2015051 -38.61883564
OS 41.2015051 -38.60959004
OS 41.20242966 -38.60034444
OS 41.20335422 -38.58832516
OS 41.20520334 -38.57630588
OS 41.20982614 -38.54949364
OS 41.21629806 -38.51990772
OS 41.22554366 -38.4903218
OS 41.2384875 -38.46166044
OS 41.23941206 -38.46073588
OS 41.24033662 -38.4579622
OS 41.24218574 -38.45426396
OS 41.24588398 -38.44964116
OS 41.24958222 -38.44316924
OS 41.25420502 -38.43577276
OS 41.2662243 -38.41913068
OS 41.28194182 -38.40063948
OS 41.30043302 -38.38214828
OS 41.3216979 -38.36365708
OS 41.34666102 -38.34793956
OS 41.34758558 -38.347015
OS 41.35035926 -38.34609044
OS 41.3540575 -38.34424132
OS 41.3586803 -38.34146764
OS 41.36607678 -38.33869396
OS 41.37347326 -38.33592028
OS 41.38271886 -38.33222204
OS 41.39288902 -38.3285238
OS 41.40398374 -38.32482556
OS 41.41600302 -38.32112732
OS 41.4418907 -38.31557996
OS 41.47147662 -38.31095716
OS 41.5019871 -38.30910804
OS 41.5112327 -38.30910804
OS 41.51770462 -38.3100326
OE
OB 42.90454462 -39.1375138 I
OS 42.38401734 -39.1375138
OS 42.38401734 -39.08111564
OS 42.90454462 -39.08111564
OS 42.90454462 -39.1375138
OE
OB 42.12514054 -38.32112732 I
OS 42.13253702 -38.32112732
OS 42.1491791 -38.32297644
OS 42.1676703 -38.32482556
OS 42.18708606 -38.3285238
OS 42.20650182 -38.3331466
OS 42.22406846 -38.33961852
OS 42.22499302 -38.33961852
OS 42.22591758 -38.34054308
OS 42.23146494 -38.34331676
OS 42.23978598 -38.34793956
OS 42.24903158 -38.35441148
OS 42.2601263 -38.36273252
OS 42.27214558 -38.37290268
OS 42.2832403 -38.38584652
OS 42.29341046 -38.39971492
OS 42.29433502 -38.40156404
OS 42.2971087 -38.4071114
OS 42.3017315 -38.41450788
OS 42.3063543 -38.4256026
OS 42.3109771 -38.43854644
OS 42.3155999 -38.45241484
OS 42.31837358 -38.46813236
OS 42.31929814 -38.48384988
OS 42.31929814 -38.485699
OS 42.31929814 -38.4903218
OS 42.31837358 -38.49864284
OS 42.31652446 -38.508813
OS 42.31375078 -38.52083228
OS 42.30912798 -38.53377612
OS 42.30358062 -38.54671996
OS 42.29618414 -38.56058836
OS 42.29525958 -38.56243748
OS 42.2924859 -38.56613572
OS 42.28693854 -38.5735322
OS 42.27954206 -38.58092868
OS 42.27029646 -38.59017428
OS 42.25920174 -38.60034444
OS 42.24533334 -38.60959004
OS 42.22961582 -38.61883564
OS 42.23054038 -38.61883564
OS 42.2323895 -38.6197602
OS 42.23516318 -38.62068476
OS 42.23886142 -38.62253388
OS 42.24995614 -38.62623212
OS 42.26289998 -38.63270404
OS 42.27676838 -38.64102508
OS 42.2924859 -38.65119524
OS 42.3063543 -38.66321452
OS 42.31929814 -38.67800748
OS 42.3202227 -38.6798566
OS 42.32392094 -38.68540396
OS 42.3294683 -38.693725
OS 42.33501566 -38.70481972
OS 42.34056302 -38.71961268
OS 42.34611038 -38.7353302
OS 42.34980862 -38.7538214
OS 42.35073318 -38.77416172
OS 42.35073318 -38.77508628
OS 42.35073318 -38.77601084
OS 42.35073318 -38.7815582
OS 42.34980862 -38.7908038
OS 42.3479595 -38.80189852
OS 42.34611038 -38.81484236
OS 42.34241214 -38.82871076
OS 42.33778934 -38.84350372
OS 42.33131742 -38.85829668
OS 42.33039286 -38.8601458
OS 42.32761918 -38.8647686
OS 42.32392094 -38.87124052
OS 42.31837358 -38.88048612
OS 42.3109771 -38.88973172
OS 42.30358062 -38.89990188
OS 42.29433502 -38.91007204
OS 42.28416486 -38.91839308
OS 42.2832403 -38.91931764
OS 42.27954206 -38.92209132
OS 42.27307014 -38.92578956
OS 42.2647491 -38.9294878
OS 42.25457894 -38.93503516
OS 42.24255966 -38.94058252
OS 42.22961582 -38.94520532
OS 42.2138983 -38.94982812
OS 42.21204918 -38.94982812
OS 42.20650182 -38.95167724
OS 42.19725622 -38.9526018
OS 42.18523694 -38.95445092
OS 42.17044398 -38.95630004
OS 42.15287734 -38.95814916
OS 42.13346158 -38.95907372
OS 42.11127214 -38.95999828
OS 41.8671883 -38.95999828
OS 41.8671883 -38.32020276
OS 42.11866862 -38.32020276
OS 42.12514054 -38.32112732
OE
OB 40.30745558 -38.48662356 I
OS 40.31762574 -38.48847268
OS 40.32964502 -38.49217092
OS 40.34258886 -38.49679372
OS 40.35738182 -38.50326564
OS 40.37309934 -38.51158668
OS 40.34443798 -38.58370236
OS 40.34351342 -38.5827778
OS 40.33981518 -38.58092868
OS 40.33426782 -38.578155
OS 40.32687134 -38.57538132
OS 40.3185503 -38.57260764
OS 40.30838014 -38.56983396
OS 40.29820998 -38.56798484
OS 40.28803982 -38.56706028
OS 40.28341702 -38.56706028
OS 40.27879422 -38.56798484
OS 40.2723223 -38.5689094
OS 40.26585038 -38.57075852
OS 40.25752934 -38.5735322
OS 40.2492083 -38.57723044
OS 40.24181182 -38.5827778
OS 40.24088726 -38.58370236
OS 40.23811358 -38.58555148
OS 40.2353399 -38.58924972
OS 40.2307171 -38.59387252
OS 40.2260943 -38.60034444
OS 40.2214715 -38.60774092
OS 40.2168487 -38.61606196
OS 40.21315046 -38.62623212
OS 40.2122259 -38.62808124
OS 40.21130134 -38.6336286
OS 40.20945222 -38.64194964
OS 40.20667854 -38.65304436
OS 40.20390486 -38.66691276
OS 40.20205574 -38.68263028
OS 40.20113118 -38.69927236
OS 40.20020662 -38.71776356
OS 40.20020662 -38.95999828
OS 40.12161902 -38.95999828
OS 40.12161902 -38.49586916
OS 40.19281014 -38.49586916
OS 40.19281014 -38.56613572
OS 40.1937347 -38.56521116
OS 40.19743294 -38.55873924
OS 40.20205574 -38.5504182
OS 40.20945222 -38.54024804
OS 40.2168487 -38.53007788
OS 40.22516974 -38.51898316
OS 40.23349078 -38.50973756
OS 40.24181182 -38.50234108
OS 40.24273638 -38.50141652
OS 40.24551006 -38.4995674
OS 40.25105742 -38.49679372
OS 40.25660478 -38.49402004
OS 40.26400126 -38.49124636
OS 40.27324686 -38.48847268
OS 40.28249246 -38.48662356
OS 40.29266262 -38.485699
OS 40.29913454 -38.485699
OS 40.30745558 -38.48662356
OE
OB 39.48829542 -38.95999828 I
OS 39.3986131 -38.95999828
OS 39.3986131 -38.87031596
OS 39.48829542 -38.87031596
OS 39.48829542 -38.95999828
OE
OB 38.6404739 -38.95999828 I
OS 38.55171614 -38.95999828
OS 38.30393406 -38.32020276
OS 38.39639006 -38.32020276
OS 38.56281086 -38.78525644
OS 38.56281086 -38.786181
OS 38.56373542 -38.78803012
OS 38.56465998 -38.7908038
OS 38.5665091 -38.79450204
OS 38.56743366 -38.8000494
OS 38.56928278 -38.80559676
OS 38.57390558 -38.81946516
OS 38.57945294 -38.83518268
OS 38.5850003 -38.85274932
OS 38.59609502 -38.88973172
OS 38.59609502 -38.88880716
OS 38.59701958 -38.88695804
OS 38.59794414 -38.88418436
OS 38.5988687 -38.88048612
OS 38.60164238 -38.87031596
OS 38.60626518 -38.85644756
OS 38.61088798 -38.84073004
OS 38.61643534 -38.8231634
OS 38.62290726 -38.8046722
OS 38.63030374 -38.78525644
OS 38.80412102 -38.32020276
OS 38.8901051 -38.32020276
OS 38.6404739 -38.95999828
OE
OB 39.27564662 -38.42745172 I
OS 39.25438174 -38.54671996
OS 39.20538006 -38.54671996
OS 39.1859643 -38.42745172
OS 39.1859643 -38.32020276
OS 39.27564662 -38.32020276
OS 39.27564662 -38.42745172
OE
OB 40.49791494 -38.4117342 I
OS 40.41932734 -38.4117342
OS 40.41932734 -38.32020276
OS 40.49791494 -38.32020276
OS 40.49791494 -38.4117342
OE
OB 39.84517558 -38.48662356 I
OS 39.8516475 -38.48754812
OS 39.8655159 -38.48939724
OS 39.88215798 -38.49309548
OS 39.89972462 -38.49864284
OS 39.91729126 -38.50696388
OS 39.9348579 -38.51713404
OS 39.93578246 -38.51713404
OS 39.93670702 -38.51898316
OS 39.94225438 -38.5226814
OS 39.95057542 -38.53007788
OS 39.96074558 -38.53932348
OS 39.9718403 -38.55134276
OS 39.98293502 -38.56613572
OS 39.99402974 -38.58370236
OS 40.00327534 -38.60311812
OS 40.00327534 -38.60404268
OS 40.0041999 -38.6058918
OS 40.00512446 -38.60866548
OS 40.00697358 -38.61236372
OS 40.0088227 -38.61791108
OS 40.01067182 -38.624383
OS 40.01529462 -38.63917596
OS 40.01991742 -38.65766716
OS 40.02361566 -38.67800748
OS 40.02638934 -38.70112148
OS 40.0273139 -38.72516004
OS 40.0273139 -38.7260846
OS 40.0273139 -38.72793372
OS 40.0273139 -38.73163196
OS 40.0273139 -38.73717932
OS 40.02638934 -38.74365124
OS 40.02638934 -38.75104772
OS 40.02454022 -38.7676898
OS 40.02084198 -38.78803012
OS 40.01621918 -38.809295
OS 40.00974726 -38.83148444
OS 40.00142622 -38.85367388
OS 40.00142622 -38.85459844
OS 40.00050166 -38.85644756
OS 39.99865254 -38.85922124
OS 39.99680342 -38.86291948
OS 39.9903315 -38.87308964
OS 39.98201046 -38.88603348
OS 39.9718403 -38.89990188
OS 39.95889646 -38.91377028
OS 39.9441035 -38.92763868
OS 39.92653686 -38.94058252
OS 39.9256123 -38.94058252
OS 39.92468774 -38.94150708
OS 39.92191406 -38.9433562
OS 39.91821582 -38.94520532
OS 39.90897022 -38.94982812
OS 39.89602638 -38.95537548
OS 39.88030886 -38.96092284
OS 39.86366678 -38.96554564
OS 39.84425102 -38.96924388
OS 39.82483526 -38.97016844
OS 39.81836334 -38.97016844
OS 39.81096686 -38.96924388
OS 39.80172126 -38.96831932
OS 39.79062654 -38.9664702
OS 39.77860726 -38.96369652
OS 39.76658798 -38.95999828
OS 39.7545687 -38.95445092
OS 39.75364414 -38.95352636
OS 39.74902134 -38.95167724
OS 39.74347398 -38.947979
OS 39.7360775 -38.94243164
OS 39.72868102 -38.93688428
OS 39.71943542 -38.9294878
OS 39.71111438 -38.92116676
OS 39.7037179 -38.91192116
OS 39.7037179 -39.1375138
OS 39.6251303 -39.1375138
OS 39.6251303 -38.49586916
OS 39.69632142 -38.49586916
OS 39.69632142 -38.55689012
OS 39.69724598 -38.555041
OS 39.70094422 -38.55134276
OS 39.70556702 -38.54487084
OS 39.7129635 -38.53747436
OS 39.72128454 -38.52822876
OS 39.73053014 -38.51990772
OS 39.74162486 -38.51158668
OS 39.75271958 -38.5041902
OS 39.7545687 -38.50326564
OS 39.75826694 -38.50141652
OS 39.76566342 -38.49864284
OS 39.77490902 -38.4949446
OS 39.78600374 -38.49124636
OS 39.79894758 -38.48847268
OS 39.81374054 -38.48662356
OS 39.83038262 -38.485699
OS 39.84055278 -38.485699
OS 39.84517558 -38.48662356
OE
OB 44.92193454 -38.40988508 I
OS 44.84334694 -38.40988508
OS 44.84334694 -38.32020276
OS 44.92193454 -38.32020276
OS 44.92193454 -38.40988508
OE
OB 45.24553054 -38.48662356 I
OS 45.25385158 -38.48754812
OS 45.26309718 -38.48939724
OS 45.27326734 -38.49124636
OS 45.28528662 -38.49309548
OS 45.31024974 -38.50141652
OS 45.32319358 -38.50603932
OS 45.33613742 -38.51251124
OS 45.34908126 -38.51898316
OS 45.3620251 -38.52822876
OS 45.37404438 -38.53747436
OS 45.38606366 -38.54856908
OS 45.38698822 -38.54949364
OS 45.38883734 -38.55134276
OS 45.39161102 -38.555041
OS 45.39530926 -38.5596638
OS 45.39993206 -38.56613572
OS 45.40547942 -38.57445676
OS 45.41102678 -38.58370236
OS 45.41657414 -38.59387252
OS 45.4221215 -38.60496724
OS 45.42766886 -38.61883564
OS 45.43321622 -38.63270404
OS 45.43783902 -38.64842156
OS 45.44153726 -38.66506364
OS 45.44431094 -38.68263028
OS 45.44616006 -38.70112148
OS 45.44708462 -38.7214618
OS 45.44708462 -38.72238636
OS 45.44708462 -38.72516004
OS 45.44708462 -38.72978284
OS 45.44708462 -38.73625476
OS 45.44616006 -38.74365124
OS 45.4452355 -38.75289684
OS 45.4452355 -38.76214244
OS 45.44338638 -38.7723126
OS 45.4406127 -38.7954266
OS 45.43506534 -38.8185406
OS 45.42859342 -38.8416546
OS 45.41934782 -38.86291948
OS 45.41934782 -38.86384404
OS 45.41842326 -38.8647686
OS 45.41657414 -38.86754228
OS 45.41472502 -38.87124052
OS 45.4082531 -38.88048612
OS 45.39993206 -38.89158084
OS 45.38883734 -38.90452468
OS 45.37496894 -38.91746852
OS 45.35925142 -38.93041236
OS 45.34076022 -38.94243164
OS 45.33983566 -38.94243164
OS 45.3389111 -38.9433562
OS 45.33613742 -38.94520532
OS 45.33151462 -38.94705444
OS 45.32689182 -38.94890356
OS 45.32134446 -38.95075268
OS 45.30747606 -38.95630004
OS 45.29175854 -38.96092284
OS 45.27234278 -38.96554564
OS 45.25200246 -38.96924388
OS 45.22981302 -38.97016844
OS 45.22056742 -38.97016844
OS 45.21317094 -38.96924388
OS 45.2048499 -38.96831932
OS 45.1956043 -38.9664702
OS 45.18450958 -38.96462108
OS 45.17341486 -38.96277196
OS 45.14845174 -38.95537548
OS 45.13458334 -38.94982812
OS 45.1216395 -38.94428076
OS 45.10869566 -38.93688428
OS 45.09575182 -38.92856324
OS 45.08373254 -38.91931764
OS 45.07171326 -38.90822292
OS 45.0707887 -38.90729836
OS 45.06893958 -38.90544924
OS 45.0661659 -38.901751
OS 45.06246766 -38.89620364
OS 45.05784486 -38.88973172
OS 45.05322206 -38.88233524
OS 45.0476747 -38.87308964
OS 45.04212734 -38.86199492
OS 45.03657998 -38.84997564
OS 45.03103262 -38.83610724
OS 45.02640982 -38.82131428
OS 45.02178702 -38.80559676
OS 45.01808878 -38.78803012
OS 45.0153151 -38.76953892
OS 45.01346598 -38.7491986
OS 45.01254142 -38.72793372
OS 45.01254142 -38.7260846
OS 45.01254142 -38.72238636
OS 45.01346598 -38.71591444
OS 45.01346598 -38.70666884
OS 45.01439054 -38.69649868
OS 45.01623966 -38.68355484
OS 45.01808878 -38.670611
OS 45.02178702 -38.65581804
OS 45.02548526 -38.64102508
OS 45.03010806 -38.62530756
OS 45.03565542 -38.60866548
OS 45.0430519 -38.59294796
OS 45.05044838 -38.578155
OS 45.06061854 -38.56336204
OS 45.0707887 -38.54949364
OS 45.08373254 -38.53747436
OS 45.0846571 -38.5365498
OS 45.08650622 -38.53562524
OS 45.09020446 -38.53285156
OS 45.09482726 -38.52915332
OS 45.10037462 -38.52545508
OS 45.1077711 -38.52083228
OS 45.11516758 -38.51620948
OS 45.12441318 -38.51158668
OS 45.13458334 -38.50696388
OS 45.14567806 -38.50234108
OS 45.17064118 -38.49402004
OS 45.19930254 -38.48754812
OS 45.2140955 -38.48662356
OS 45.22981302 -38.485699
OS 45.23905862 -38.485699
OS 45.24553054 -38.48662356
OE
OB 44.92193454 -38.95999828 I
OS 44.84334694 -38.95999828
OS 44.84334694 -38.49586916
OS 44.92193454 -38.49586916
OS 44.92193454 -38.95999828
OE
OB 46.10722046 -38.42745172 I
OS 46.08595558 -38.54671996
OS 46.0369539 -38.54671996
OS 46.01753814 -38.42745172
OS 46.01753814 -38.32020276
OS 46.10722046 -38.32020276
OS 46.10722046 -38.42745172
OE
OB 45.77160518 -38.48662356 I
OS 45.78177534 -38.48754812
OS 45.79379462 -38.48939724
OS 45.80673846 -38.49217092
OS 45.82060686 -38.49586916
OS 45.8335507 -38.50141652
OS 45.83539982 -38.50234108
OS 45.83909806 -38.5041902
OS 45.84556998 -38.50696388
OS 45.85296646 -38.51158668
OS 45.86221206 -38.51713404
OS 45.8705331 -38.52453052
OS 45.87885414 -38.531927
OS 45.88625062 -38.5411726
OS 45.88717518 -38.54209716
OS 45.8890243 -38.5457954
OS 45.89179798 -38.5504182
OS 45.89642078 -38.55689012
OS 45.90011902 -38.56613572
OS 45.90381726 -38.57538132
OS 45.90844006 -38.58647604
OS 45.91121374 -38.59849532
OS 45.91121374 -38.59941988
OS 45.9121383 -38.60311812
OS 45.91306286 -38.60866548
OS 45.91398742 -38.61606196
OS 45.91398742 -38.62715668
OS 45.91491198 -38.64010052
OS 45.91583654 -38.65581804
OS 45.91583654 -38.6752338
OS 45.91583654 -38.95999828
OS 45.83724894 -38.95999828
OS 45.83724894 -38.67893204
OS 45.83724894 -38.67800748
OS 45.83724894 -38.67708292
OS 45.83724894 -38.670611
OS 45.83724894 -38.66228996
OS 45.83632438 -38.6521198
OS 45.83539982 -38.64010052
OS 45.8335507 -38.62808124
OS 45.83077702 -38.61698652
OS 45.82800334 -38.60681636
OS 45.82800334 -38.6058918
OS 45.82615422 -38.60311812
OS 45.82338054 -38.59849532
OS 45.82060686 -38.59294796
OS 45.81598406 -38.5874006
OS 45.8104367 -38.58092868
OS 45.80304022 -38.57445676
OS 45.79471918 -38.5689094
OS 45.79379462 -38.56798484
OS 45.79102094 -38.56613572
OS 45.78547358 -38.5642866
OS 45.77900166 -38.56151292
OS 45.77160518 -38.55873924
OS 45.76235958 -38.55596556
OS 45.75126486 -38.555041
OS 45.74017014 -38.55411644
OS 45.73554734 -38.55411644
OS 45.7318491 -38.555041
OS 45.7226035 -38.55596556
OS 45.71058422 -38.55781468
OS 45.69764038 -38.56243748
OS 45.68284742 -38.56798484
OS 45.66805446 -38.57538132
OS 45.65418606 -38.58647604
OS 45.65233694 -38.58832516
OS 45.6486387 -38.59294796
OS 45.64586502 -38.5966462
OS 45.64309134 -38.601269
OS 45.6393931 -38.60681636
OS 45.63661942 -38.61328828
OS 45.63292118 -38.62068476
OS 45.62922294 -38.62993036
OS 45.62644926 -38.64010052
OS 45.62367558 -38.65119524
OS 45.62182646 -38.66321452
OS 45.61997734 -38.67615836
OS 45.61812822 -38.69187588
OS 45.61812822 -38.7075934
OS 45.61812822 -38.95999828
OS 45.53954062 -38.95999828
OS 45.53954062 -38.49586916
OS 45.60980718 -38.49586916
OS 45.60980718 -38.56243748
OS 45.61073174 -38.56151292
OS 45.61258086 -38.55873924
OS 45.61535454 -38.555041
OS 45.61905278 -38.5504182
OS 45.62460014 -38.54487084
OS 45.63107206 -38.53839892
OS 45.63846854 -38.53100244
OS 45.64771414 -38.52360596
OS 45.65695974 -38.51713404
OS 45.66805446 -38.50973756
OS 45.68007374 -38.50326564
OS 45.69301758 -38.49771828
OS 45.70781054 -38.49309548
OS 45.7226035 -38.48939724
OS 45.73924558 -38.48662356
OS 45.75681222 -38.485699
OS 45.7642087 -38.485699
OS 45.77160518 -38.48662356
OE
OB 44.2756671 -38.95999828 I
OS 44.1970795 -38.95999828
OS 44.1970795 -38.49586916
OS 44.2756671 -38.49586916
OS 44.2756671 -38.95999828
OE
OB 43.4574315 -38.48662356 I
OS 43.46482798 -38.48754812
OS 43.47407358 -38.48939724
OS 43.48424374 -38.49124636
OS 43.49626302 -38.49402004
OS 43.50735774 -38.49679372
OS 43.52030158 -38.50141652
OS 43.53232086 -38.50603932
OS 43.5452647 -38.51251124
OS 43.55820854 -38.51990772
OS 43.57115238 -38.52822876
OS 43.58317166 -38.53839892
OS 43.59426638 -38.54949364
OS 43.59519094 -38.5504182
OS 43.59704006 -38.55226732
OS 43.59981374 -38.55596556
OS 43.60351198 -38.56151292
OS 43.60813478 -38.56798484
OS 43.61275758 -38.57538132
OS 43.61830494 -38.58462692
OS 43.6238523 -38.59572164
OS 43.62939966 -38.60774092
OS 43.63494702 -38.62068476
OS 43.63956982 -38.63547772
OS 43.64419262 -38.65119524
OS 43.64789086 -38.66876188
OS 43.65066454 -38.68725308
OS 43.65251366 -38.70666884
OS 43.65343822 -38.72793372
OS 43.65343822 -38.72885828
OS 43.65343822 -38.73255652
OS 43.65343822 -38.73902844
OS 43.65251366 -38.74827404
OS 43.30580366 -38.74827404
OS 43.30580366 -38.7491986
OS 43.30580366 -38.75197228
OS 43.30672822 -38.75567052
OS 43.30672822 -38.76121788
OS 43.30765278 -38.7676898
OS 43.3095019 -38.77508628
OS 43.31227558 -38.79172836
OS 43.31782294 -38.81021956
OS 43.32521942 -38.83055988
OS 43.33538958 -38.84905108
OS 43.34833342 -38.86569316
OS 43.34925798 -38.86569316
OS 43.35018254 -38.86754228
OS 43.3557299 -38.87216508
OS 43.36405094 -38.878637
OS 43.37514566 -38.88510892
OS 43.38993862 -38.8925054
OS 43.4065807 -38.89897732
OS 43.4250719 -38.90360012
OS 43.43524206 -38.90452468
OS 43.44633678 -38.90544924
OS 43.45373326 -38.90544924
OS 43.4620543 -38.90452468
OS 43.47222446 -38.90267556
OS 43.48331918 -38.89990188
OS 43.49626302 -38.89620364
OS 43.5082823 -38.89065628
OS 43.52030158 -38.8832598
OS 43.52122614 -38.88233524
OS 43.52584894 -38.878637
OS 43.5313963 -38.87308964
OS 43.53786822 -38.86569316
OS 43.5452647 -38.855523
OS 43.55358574 -38.84257916
OS 43.56190678 -38.8277862
OS 43.56930326 -38.81021956
OS 43.65066454 -38.82038972
OS 43.65066454 -38.82131428
OS 43.64973998 -38.8231634
OS 43.64881542 -38.82686164
OS 43.6469663 -38.832409
OS 43.64419262 -38.83795636
OS 43.64141894 -38.84535284
OS 43.63402246 -38.86107036
OS 43.62477686 -38.878637
OS 43.61183302 -38.8971282
OS 43.59704006 -38.91469484
OS 43.57854886 -38.93133692
OS 43.5776243 -38.93133692
OS 43.57577518 -38.93318604
OS 43.5730015 -38.93503516
OS 43.56930326 -38.93780884
OS 43.5637559 -38.94058252
OS 43.55820854 -38.9433562
OS 43.55081206 -38.94705444
OS 43.54249102 -38.95075268
OS 43.53324542 -38.95445092
OS 43.52399982 -38.95814916
OS 43.50088582 -38.96369652
OS 43.47499814 -38.96831932
OS 43.44633678 -38.97016844
OS 43.43616662 -38.97016844
OS 43.4296947 -38.96924388
OS 43.42137366 -38.96831932
OS 43.4112035 -38.9664702
OS 43.40010878 -38.96462108
OS 43.3880895 -38.96277196
OS 43.36220182 -38.95537548
OS 43.34833342 -38.94982812
OS 43.33538958 -38.94428076
OS 43.32152118 -38.93688428
OS 43.30857734 -38.92856324
OS 43.29655806 -38.91931764
OS 43.28453878 -38.90822292
OS 43.28361422 -38.90729836
OS 43.2817651 -38.90544924
OS 43.27899142 -38.901751
OS 43.27529318 -38.89620364
OS 43.27067038 -38.88973172
OS 43.26604758 -38.88233524
OS 43.26050022 -38.87308964
OS 43.25495286 -38.86291948
OS 43.2494055 -38.8509002
OS 43.24385814 -38.83795636
OS 43.23923534 -38.8231634
OS 43.23461254 -38.80744588
OS 43.2309143 -38.7908038
OS 43.22814062 -38.7723126
OS 43.2262915 -38.75289684
OS 43.22536694 -38.73255652
OS 43.22536694 -38.73163196
OS 43.22536694 -38.72700916
OS 43.22536694 -38.7214618
OS 43.2262915 -38.71314076
OS 43.22721606 -38.7029706
OS 43.22814062 -38.69187588
OS 43.22998974 -38.67893204
OS 43.23276342 -38.6659882
OS 43.2401599 -38.63640228
OS 43.2447827 -38.62160932
OS 43.25033006 -38.6058918
OS 43.25772654 -38.59109884
OS 43.26604758 -38.57723044
OS 43.27529318 -38.56336204
OS 43.28546334 -38.5504182
OS 43.2863879 -38.54949364
OS 43.28823702 -38.54764452
OS 43.29193526 -38.54487084
OS 43.29655806 -38.54024804
OS 43.30210542 -38.53562524
OS 43.3095019 -38.53007788
OS 43.31782294 -38.52360596
OS 43.3279931 -38.5180586
OS 43.33816326 -38.51158668
OS 43.35018254 -38.50603932
OS 43.36312638 -38.50049196
OS 43.37699478 -38.49586916
OS 43.39178774 -38.49124636
OS 43.40750526 -38.48847268
OS 43.42414734 -38.48662356
OS 43.44171398 -38.485699
OS 43.45095958 -38.485699
OS 43.4574315 -38.48662356
OE
OB 43.13938286 -38.48662356 I
OS 43.14955302 -38.48847268
OS 43.1615723 -38.49217092
OS 43.17451614 -38.49679372
OS 43.1893091 -38.50326564
OS 43.20502662 -38.51158668
OS 43.17636526 -38.58370236
OS 43.1754407 -38.5827778
OS 43.17174246 -38.58092868
OS 43.1661951 -38.578155
OS 43.15879862 -38.57538132
OS 43.15047758 -38.57260764
OS 43.14030742 -38.56983396
OS 43.13013726 -38.56798484
OS 43.1199671 -38.56706028
OS 43.1153443 -38.56706028
OS 43.1107215 -38.56798484
OS 43.10424958 -38.5689094
OS 43.09777766 -38.57075852
OS 43.08945662 -38.5735322
OS 43.08113558 -38.57723044
OS 43.0737391 -38.5827778
OS 43.07281454 -38.58370236
OS 43.07004086 -38.58555148
OS 43.06726718 -38.58924972
OS 43.06264438 -38.59387252
OS 43.05802158 -38.60034444
OS 43.05339878 -38.60774092
OS 43.04877598 -38.61606196
OS 43.04507774 -38.62623212
OS 43.04415318 -38.62808124
OS 43.04322862 -38.6336286
OS 43.0413795 -38.64194964
OS 43.03860582 -38.65304436
OS 43.03583214 -38.66691276
OS 43.03398302 -38.68263028
OS 43.03305846 -38.69927236
OS 43.0321339 -38.71776356
OS 43.0321339 -38.95999828
OS 42.9535463 -38.95999828
OS 42.9535463 -38.49586916
OS 43.02473742 -38.49586916
OS 43.02473742 -38.56613572
OS 43.02566198 -38.56521116
OS 43.02936022 -38.55873924
OS 43.03398302 -38.5504182
OS 43.0413795 -38.54024804
OS 43.04877598 -38.53007788
OS 43.05709702 -38.51898316
OS 43.06541806 -38.50973756
OS 43.0737391 -38.50234108
OS 43.07466366 -38.50141652
OS 43.07743734 -38.4995674
OS 43.0829847 -38.49679372
OS 43.08853206 -38.49402004
OS 43.09592854 -38.49124636
OS 43.10517414 -38.48847268
OS 43.11441974 -38.48662356
OS 43.1245899 -38.485699
OS 43.13106182 -38.485699
OS 43.13938286 -38.48662356
OE
OB 43.95022198 -38.95999828 I
OS 43.87533262 -38.95999828
OS 43.70059078 -38.49586916
OS 43.78380118 -38.49586916
OS 43.88365366 -38.77416172
OS 43.88365366 -38.77508628
OS 43.88457822 -38.77601084
OS 43.88550278 -38.77878452
OS 43.88642734 -38.7815582
OS 43.88920102 -38.7908038
OS 43.89289926 -38.80282308
OS 43.89752206 -38.81669148
OS 43.90306942 -38.832409
OS 43.90769222 -38.84997564
OS 43.91323958 -38.86754228
OS 43.91416414 -38.86569316
OS 43.9150887 -38.86107036
OS 43.91786238 -38.85367388
OS 43.92063606 -38.84257916
OS 43.92525886 -38.83055988
OS 43.92988166 -38.81484236
OS 43.93635358 -38.79820028
OS 43.9428255 -38.77970908
OS 44.04545166 -38.49586916
OS 44.12681294 -38.49586916
OS 43.95022198 -38.95999828
OE
OB 44.2756671 -38.40988508 I
OS 44.1970795 -38.40988508
OS 44.1970795 -38.32020276
OS 44.2756671 -38.32020276
OS 44.2756671 -38.40988508
OE
OB 44.5669035 -38.48662356 I
OS 44.5807719 -38.48754812
OS 44.59556486 -38.48939724
OS 44.61128238 -38.49309548
OS 44.62792446 -38.49679372
OS 44.64364198 -38.50234108
OS 44.64456654 -38.50234108
OS 44.6454911 -38.50326564
OS 44.6501139 -38.50511476
OS 44.65751038 -38.508813
OS 44.66675598 -38.5134358
OS 44.67692614 -38.51990772
OS 44.6870963 -38.5273042
OS 44.6963419 -38.53562524
OS 44.70466294 -38.54487084
OS 44.7055875 -38.5457954
OS 44.70743662 -38.54949364
OS 44.71113486 -38.55596556
OS 44.71575766 -38.56336204
OS 44.72038046 -38.57445676
OS 44.72500326 -38.58647604
OS 44.7287015 -38.60034444
OS 44.73239974 -38.61606196
OS 44.65566126 -38.62623212
OS 44.65566126 -38.624383
OS 44.6547367 -38.62068476
OS 44.65288758 -38.61421284
OS 44.6501139 -38.6058918
OS 44.6454911 -38.59757076
OS 44.63994374 -38.58832516
OS 44.63347182 -38.57907956
OS 44.62422622 -38.57075852
OS 44.62330166 -38.56983396
OS 44.61960342 -38.56798484
OS 44.61405606 -38.5642866
OS 44.60573502 -38.56058836
OS 44.59648942 -38.55689012
OS 44.58447014 -38.55319188
OS 44.56967718 -38.55134276
OS 44.55395966 -38.5504182
OS 44.54471406 -38.5504182
OS 44.53546846 -38.55134276
OS 44.52344918 -38.55226732
OS 44.5114299 -38.555041
OS 44.49848606 -38.55781468
OS 44.48646678 -38.56243748
OS 44.47629662 -38.5689094
OS 44.47537206 -38.56983396
OS 44.47259838 -38.57168308
OS 44.46890014 -38.57538132
OS 44.4652019 -38.58092868
OS 44.4605791 -38.58647604
OS 44.45688086 -38.59387252
OS 44.45410718 -38.60219356
OS 44.45318262 -38.6105146
OS 44.45318262 -38.61143916
OS 44.45318262 -38.61328828
OS 44.45410718 -38.61606196
OS 44.45410718 -38.6197602
OS 44.45688086 -38.6290058
OS 44.46242822 -38.6382514
OS 44.46335278 -38.63917596
OS 44.46427734 -38.64010052
OS 44.46612646 -38.6428742
OS 44.4698247 -38.64564788
OS 44.47352294 -38.64842156
OS 44.4790703 -38.6521198
OS 44.48554222 -38.65489348
OS 44.4929387 -38.65859172
OS 44.49386326 -38.65859172
OS 44.49571238 -38.65951628
OS 44.49941062 -38.66044084
OS 44.50588254 -38.66321452
OS 44.51512814 -38.6659882
OS 44.52714742 -38.66876188
OS 44.5345439 -38.67153556
OS 44.54286494 -38.67338468
OS 44.55211054 -38.67615836
OS 44.5622807 -38.67893204
OS 44.56320526 -38.67893204
OS 44.56597894 -38.6798566
OS 44.57060174 -38.68078116
OS 44.5761491 -38.68263028
OS 44.58262102 -38.6844794
OS 44.59094206 -38.68632852
OS 44.6085087 -38.69187588
OS 44.62792446 -38.69742324
OS 44.64734022 -38.70389516
OS 44.66490686 -38.71036708
OS 44.67230334 -38.71314076
OS 44.67877526 -38.71591444
OS 44.68062438 -38.716839
OS 44.68432262 -38.71868812
OS 44.68986998 -38.7214618
OS 44.69819102 -38.7260846
OS 44.70651206 -38.73163196
OS 44.7148331 -38.73902844
OS 44.72315414 -38.74734948
OS 44.73055062 -38.75659508
OS 44.73147518 -38.75751964
OS 44.7333243 -38.76121788
OS 44.73702254 -38.76676524
OS 44.74072078 -38.77508628
OS 44.74349446 -38.78525644
OS 44.7471927 -38.79635116
OS 44.74904182 -38.809295
OS 44.74996638 -38.82408796
OS 44.74996638 -38.82593708
OS 44.74996638 -38.83055988
OS 44.74904182 -38.83795636
OS 44.7471927 -38.84812652
OS 44.74441902 -38.85922124
OS 44.73979622 -38.87124052
OS 44.73424886 -38.88510892
OS 44.72685238 -38.89805276
OS 44.72592782 -38.89990188
OS 44.72222958 -38.90360012
OS 44.71760678 -38.91007204
OS 44.7102103 -38.91746852
OS 44.70004014 -38.92578956
OS 44.68894542 -38.93503516
OS 44.67600158 -38.9433562
OS 44.66028406 -38.95167724
OS 44.6593595 -38.95167724
OS 44.65843494 -38.9526018
OS 44.65288758 -38.95445092
OS 44.64364198 -38.9572246
OS 44.6316227 -38.96092284
OS 44.61682974 -38.96462108
OS 44.60018766 -38.96739476
OS 44.58262102 -38.96924388
OS 44.5622807 -38.97016844
OS 44.55395966 -38.97016844
OS 44.54748774 -38.96924388
OS 44.54009126 -38.96924388
OS 44.53084566 -38.96831932
OS 44.52160006 -38.96739476
OS 44.5114299 -38.96554564
OS 44.48924046 -38.96092284
OS 44.46612646 -38.95445092
OS 44.44393702 -38.94520532
OS 44.43376686 -38.93965796
OS 44.42452126 -38.93318604
OS 44.4235967 -38.93226148
OS 44.42267214 -38.93133692
OS 44.41712478 -38.92578956
OS 44.40880374 -38.91746852
OS 44.39955814 -38.90452468
OS 44.38938798 -38.88880716
OS 44.37921782 -38.87031596
OS 44.37089678 -38.84720196
OS 44.36442486 -38.82131428
OS 44.4420879 -38.809295
OS 44.4420879 -38.81021956
OS 44.4420879 -38.81114412
OS 44.44393702 -38.81669148
OS 44.44578614 -38.82593708
OS 44.44948438 -38.83610724
OS 44.45410718 -38.84720196
OS 44.45965454 -38.85922124
OS 44.46797558 -38.87124052
OS 44.47814574 -38.88141068
OS 44.47999486 -38.88233524
OS 44.4836931 -38.88510892
OS 44.49108958 -38.88880716
OS 44.50033518 -38.89342996
OS 44.51235446 -38.89805276
OS 44.52622286 -38.901751
OS 44.54286494 -38.90452468
OS 44.5622807 -38.90544924
OS 44.5715263 -38.90544924
OS 44.5807719 -38.90452468
OS 44.59279118 -38.90267556
OS 44.60573502 -38.89990188
OS 44.61960342 -38.89620364
OS 44.6316227 -38.89158084
OS 44.64271742 -38.88418436
OS 44.64364198 -38.8832598
OS 44.64734022 -38.88048612
OS 44.65103846 -38.87586332
OS 44.65658582 -38.8693914
OS 44.66120862 -38.86199492
OS 44.66583142 -38.85274932
OS 44.6686051 -38.84350372
OS 44.66952966 -38.832409
OS 44.66952966 -38.83148444
OS 44.66952966 -38.8277862
OS 44.6686051 -38.8231634
OS 44.66675598 -38.81669148
OS 44.6639823 -38.81021956
OS 44.6593595 -38.80374764
OS 44.65381214 -38.79635116
OS 44.6454911 -38.7908038
OS 44.64456654 -38.78987924
OS 44.64179286 -38.78895468
OS 44.63717006 -38.786181
OS 44.62977358 -38.78340732
OS 44.61867886 -38.77970908
OS 44.61220694 -38.7769354
OS 44.60481046 -38.77508628
OS 44.59648942 -38.7723126
OS 44.58724382 -38.76953892
OS 44.57707366 -38.76676524
OS 44.56505438 -38.76399156
OS 44.56412982 -38.76399156
OS 44.56135614 -38.763067
OS 44.55673334 -38.76214244
OS 44.55118598 -38.76029332
OS 44.5437895 -38.7584442
OS 44.53546846 -38.75567052
OS 44.51790182 -38.75104772
OS 44.4975615 -38.7445758
OS 44.47814574 -38.73902844
OS 44.45965454 -38.73255652
OS 44.4513335 -38.72885828
OS 44.44486158 -38.7260846
OS 44.44301246 -38.72516004
OS 44.43931422 -38.72331092
OS 44.43376686 -38.71961268
OS 44.42637038 -38.71498988
OS 44.41804934 -38.70851796
OS 44.4097283 -38.70112148
OS 44.40140726 -38.69280044
OS 44.39401078 -38.68263028
OS 44.39308622 -38.68170572
OS 44.3912371 -38.67800748
OS 44.38846342 -38.67153556
OS 44.38568974 -38.66413908
OS 44.38291606 -38.65489348
OS 44.38014238 -38.64379876
OS 44.37829326 -38.63270404
OS 44.3773687 -38.6197602
OS 44.3773687 -38.61791108
OS 44.3773687 -38.61421284
OS 44.37829326 -38.60866548
OS 44.37921782 -38.60034444
OS 44.38106694 -38.5920234
OS 44.38291606 -38.58185324
OS 44.3866143 -38.57260764
OS 44.3912371 -38.56243748
OS 44.39216166 -38.56151292
OS 44.39401078 -38.55781468
OS 44.39678446 -38.55319188
OS 44.40140726 -38.54671996
OS 44.40695462 -38.54024804
OS 44.41342654 -38.531927
OS 44.42082302 -38.52453052
OS 44.43006862 -38.5180586
OS 44.43099318 -38.51713404
OS 44.43376686 -38.51620948
OS 44.4374651 -38.5134358
OS 44.44301246 -38.51066212
OS 44.45040894 -38.50696388
OS 44.45872998 -38.50326564
OS 44.46890014 -38.4995674
OS 44.47999486 -38.49586916
OS 44.48184398 -38.4949446
OS 44.48554222 -38.49402004
OS 44.49201414 -38.49217092
OS 44.50033518 -38.4903218
OS 44.51050534 -38.48847268
OS 44.52160006 -38.48754812
OS 44.5345439 -38.485699
OS 44.55673334 -38.485699
OS 44.5669035 -38.48662356
OE
OB 33.15968222 -38.32112732 I
OS 33.17539974 -38.32205188
OS 33.19204182 -38.32297644
OS 33.20775934 -38.32482556
OS 33.22162774 -38.32667468
OS 33.22347686 -38.32667468
OS 33.22994878 -38.3285238
OS 33.23826982 -38.33037292
OS 33.24936454 -38.3331466
OS 33.26138382 -38.3377694
OS 33.27432766 -38.34331676
OS 33.28819606 -38.34978868
OS 33.30021534 -38.35718516
OS 33.30206446 -38.35810972
OS 33.3057627 -38.3608834
OS 33.31131006 -38.36643076
OS 33.31870654 -38.37290268
OS 33.32702758 -38.38122372
OS 33.33534862 -38.39231844
OS 33.34459422 -38.40433772
OS 33.3519907 -38.41820612
OS 33.35291526 -38.42005524
OS 33.35476438 -38.42467804
OS 33.35846262 -38.43299908
OS 33.36216086 -38.4440938
OS 33.36493454 -38.45703764
OS 33.36863278 -38.4718306
OS 33.3704819 -38.48847268
OS 33.37140646 -38.50603932
OS 33.37140646 -38.50696388
OS 33.37140646 -38.50973756
OS 33.37140646 -38.5134358
OS 33.3704819 -38.51990772
OS 33.36955734 -38.52637964
OS 33.36863278 -38.53470068
OS 33.36678366 -38.54394628
OS 33.36493454 -38.55411644
OS 33.35846262 -38.57538132
OS 33.35476438 -38.58647604
OS 33.34921702 -38.59849532
OS 33.3427451 -38.6105146
OS 33.33627318 -38.62160932
OS 33.32795214 -38.63270404
OS 33.31870654 -38.64379876
OS 33.31778198 -38.64472332
OS 33.31593286 -38.64657244
OS 33.31315918 -38.64934612
OS 33.30853638 -38.6521198
OS 33.30298902 -38.6567426
OS 33.29559254 -38.6613654
OS 33.28634694 -38.66691276
OS 33.27617678 -38.67153556
OS 33.2641575 -38.67708292
OS 33.2502891 -38.68263028
OS 33.23549614 -38.68725308
OS 33.2179295 -38.69095132
OS 33.1994383 -38.69464956
OS 33.17909798 -38.69742324
OS 33.15598398 -38.69927236
OS 33.13194542 -38.70019692
OS 32.9682983 -38.70019692
OS 32.9682983 -38.95999828
OS 32.88323878 -38.95999828
OS 32.88323878 -38.32020276
OS 33.14581382 -38.32020276
OS 33.15968222 -38.32112732
OE
OB 32.75195126 -38.98403684 I
OS 32.75195126 -38.9849614
OS 32.75195126 -38.98773508
OS 32.75195126 -38.99235788
OS 32.75195126 -38.99790524
OS 32.7510267 -39.00530172
OS 32.7510267 -39.0126982
OS 32.74917758 -39.0311894
OS 32.7464039 -39.05060516
OS 32.74270566 -39.07094548
OS 32.7371583 -39.08851212
OS 32.73346006 -39.09683316
OS 32.72976182 -39.10330508
OS 32.72976182 -39.10422964
OS 32.72883726 -39.1051542
OS 32.72421446 -39.109777
OS 32.71681798 -39.11717348
OS 32.70757238 -39.12549452
OS 32.69462854 -39.13381556
OS 32.67798646 -39.14028748
OS 32.6585707 -39.14583484
OS 32.64747598 -39.1467594
OS 32.6354567 -39.14768396
OS 32.62990934 -39.14768396
OS 32.62436198 -39.1467594
OS 32.61604094 -39.1467594
OS 32.60679534 -39.14583484
OS 32.59662518 -39.14398572
OS 32.57443574 -39.13843836
OS 32.5892287 -39.07187004
OS 32.59015326 -39.07187004
OS 32.59292694 -39.0727946
OS 32.59754974 -39.07371916
OS 32.60217254 -39.07464372
OS 32.61419182 -39.0774174
OS 32.61973918 -39.07834196
OS 32.62898478 -39.07834196
OS 32.63360758 -39.0774174
OS 32.63915494 -39.07649284
OS 32.6447023 -39.07464372
OS 32.65024966 -39.07094548
OS 32.65672158 -39.06724724
OS 32.66134438 -39.06169988
OS 32.66226894 -39.06077532
OS 32.6631935 -39.05800164
OS 32.66504262 -39.05337884
OS 32.6678163 -39.04598236
OS 32.66966542 -39.0358122
OS 32.67058998 -39.02841572
OS 32.67151454 -39.0219438
OS 32.6724391 -39.01362276
OS 32.6724391 -39.0034526
OS 32.67336366 -38.99328244
OS 32.67336366 -38.98218772
OS 32.67336366 -38.49586916
OS 32.75195126 -38.49586916
OS 32.75195126 -38.98403684
OE
OB 33.77174094 -38.3100326 I
OS 33.78006198 -38.31095716
OS 33.79023214 -38.31188172
OS 33.8004023 -38.31280628
OS 33.81242158 -38.31557996
OS 33.8373847 -38.32112732
OS 33.8651215 -38.32944836
OS 33.8789899 -38.33499572
OS 33.89193374 -38.34146764
OS 33.90487758 -38.34978868
OS 33.91782142 -38.35810972
OS 33.91874598 -38.35903428
OS 33.9205951 -38.35995884
OS 33.92429334 -38.36273252
OS 33.92891614 -38.36735532
OS 33.93353894 -38.37197812
OS 33.94001086 -38.37845004
OS 33.94648278 -38.38584652
OS 33.95387926 -38.393243
OS 33.96127574 -38.4024886
OS 33.96867222 -38.41358332
OS 33.97699326 -38.42467804
OS 33.98438974 -38.43669732
OS 33.99086166 -38.45056572
OS 33.99825814 -38.46443412
OS 34.0038055 -38.47922708
OS 34.00935286 -38.49586916
OS 33.92614246 -38.51528492
OS 33.92614246 -38.51436036
OS 33.9252179 -38.51251124
OS 33.92336878 -38.508813
OS 33.92151966 -38.5041902
OS 33.91967054 -38.49864284
OS 33.91689686 -38.49124636
OS 33.90950038 -38.4764534
OS 33.90025478 -38.45981132
OS 33.88916006 -38.44316924
OS 33.87529166 -38.42745172
OS 33.8604987 -38.41358332
OS 33.85864958 -38.4117342
OS 33.85310222 -38.40803596
OS 33.84385662 -38.40341316
OS 33.83183734 -38.39694124
OS 33.81611982 -38.39139388
OS 33.79855318 -38.38584652
OS 33.7772883 -38.38214828
OS 33.7541743 -38.38122372
OS 33.74677782 -38.38122372
OS 33.74215502 -38.38214828
OS 33.7356831 -38.38214828
OS 33.72828662 -38.38307284
OS 33.71071998 -38.38584652
OS 33.69130422 -38.38954476
OS 33.6709639 -38.39601668
OS 33.64969902 -38.40526228
OS 33.63028326 -38.41728156
OS 33.6293587 -38.41728156
OS 33.62843414 -38.41913068
OS 33.62196222 -38.42375348
OS 33.61364118 -38.43114996
OS 33.60347102 -38.44224468
OS 33.59145174 -38.45611308
OS 33.58035702 -38.4718306
OS 33.57018686 -38.49124636
OS 33.56094126 -38.51251124
OS 33.56094126 -38.5134358
OS 33.5600167 -38.51528492
OS 33.55909214 -38.5180586
OS 33.55816758 -38.5226814
OS 33.55631846 -38.52822876
OS 33.55446934 -38.53470068
OS 33.55169566 -38.5504182
OS 33.54799742 -38.5689094
OS 33.54429918 -38.58924972
OS 33.54245006 -38.61143916
OS 33.5415255 -38.63547772
OS 33.5415255 -38.63640228
OS 33.5415255 -38.63917596
OS 33.5415255 -38.64379876
OS 33.5415255 -38.64934612
OS 33.54245006 -38.65581804
OS 33.54245006 -38.66413908
OS 33.54337462 -38.67338468
OS 33.54429918 -38.68355484
OS 33.54707286 -38.70574428
OS 33.55169566 -38.72978284
OS 33.55724302 -38.7538214
OS 33.5646395 -38.77785996
OS 33.5646395 -38.77878452
OS 33.56556406 -38.78063364
OS 33.56741318 -38.78340732
OS 33.5692623 -38.78803012
OS 33.57480966 -38.79912484
OS 33.5831307 -38.81206868
OS 33.59330086 -38.82686164
OS 33.6062447 -38.84257916
OS 33.62103766 -38.85644756
OS 33.6386043 -38.8693914
OS 33.63952886 -38.8693914
OS 33.64137798 -38.87031596
OS 33.64415166 -38.87216508
OS 33.6478499 -38.8740142
OS 33.6524727 -38.87586332
OS 33.65802006 -38.878637
OS 33.6709639 -38.88418436
OS 33.68760598 -38.88973172
OS 33.70609718 -38.89435452
OS 33.7264375 -38.89805276
OS 33.74770238 -38.89897732
OS 33.7541743 -38.89897732
OS 33.75972166 -38.89805276
OS 33.76619358 -38.89805276
OS 33.7726655 -38.8971282
OS 33.78930758 -38.89342996
OS 33.80872334 -38.88880716
OS 33.8281391 -38.88141068
OS 33.84847942 -38.87124052
OS 33.85864958 -38.86569316
OS 33.86789518 -38.85829668
OS 33.86881974 -38.85737212
OS 33.8697443 -38.85644756
OS 33.87251798 -38.85367388
OS 33.87621622 -38.8509002
OS 33.87991446 -38.8462774
OS 33.88453726 -38.84073004
OS 33.89008462 -38.83518268
OS 33.89470742 -38.8277862
OS 33.90025478 -38.81946516
OS 33.9067267 -38.81021956
OS 33.91227406 -38.80097396
OS 33.91782142 -38.78987924
OS 33.92244422 -38.77785996
OS 33.92706702 -38.76491612
OS 33.93168982 -38.75104772
OS 33.93538806 -38.73625476
OS 34.02044758 -38.75751964
OS 34.02044758 -38.7584442
OS 34.01952302 -38.76214244
OS 34.0176739 -38.7676898
OS 34.01490022 -38.77508628
OS 34.01212654 -38.78340732
OS 34.0084283 -38.79357748
OS 34.0038055 -38.8046722
OS 33.99825814 -38.81669148
OS 33.9853143 -38.84257916
OS 33.96867222 -38.86846684
OS 33.95850206 -38.88141068
OS 33.9483319 -38.89435452
OS 33.93723718 -38.90544924
OS 33.92429334 -38.91654396
OS 33.92336878 -38.91746852
OS 33.92151966 -38.91931764
OS 33.91689686 -38.92116676
OS 33.91227406 -38.924865
OS 33.90487758 -38.9294878
OS 33.8974811 -38.9341106
OS 33.88731094 -38.9387334
OS 33.87714078 -38.9433562
OS 33.8651215 -38.94890356
OS 33.85217766 -38.95352636
OS 33.83830926 -38.95814916
OS 33.8235163 -38.96277196
OS 33.80779878 -38.9664702
OS 33.7911567 -38.96831932
OS 33.77359006 -38.97016844
OS 33.75509886 -38.971093
OS 33.7449287 -38.971093
OS 33.73753222 -38.97016844
OS 33.72921118 -38.97016844
OS 33.71904102 -38.96924388
OS 33.7079463 -38.96739476
OS 33.69500246 -38.96554564
OS 33.66819022 -38.96092284
OS 33.64045342 -38.95352636
OS 33.61271662 -38.9433562
OS 33.59977278 -38.93688428
OS 33.58682894 -38.9294878
OS 33.58590438 -38.92856324
OS 33.58405526 -38.92763868
OS 33.58035702 -38.924865
OS 33.57665878 -38.92116676
OS 33.57111142 -38.91746852
OS 33.5646395 -38.91192116
OS 33.55724302 -38.90544924
OS 33.54984654 -38.89805276
OS 33.54245006 -38.88973172
OS 33.53412902 -38.88141068
OS 33.51748694 -38.8601458
OS 33.50176942 -38.83518268
OS 33.48790102 -38.80744588
OS 33.48790102 -38.80652132
OS 33.4860519 -38.80374764
OS 33.48512734 -38.79912484
OS 33.48235366 -38.79357748
OS 33.48050454 -38.786181
OS 33.47773086 -38.7769354
OS 33.47403262 -38.76676524
OS 33.47125894 -38.75567052
OS 33.46848526 -38.74365124
OS 33.46478702 -38.72978284
OS 33.46016422 -38.70112148
OS 33.45646598 -38.66876188
OS 33.45461686 -38.63547772
OS 33.45461686 -38.63455316
OS 33.45461686 -38.63085492
OS 33.45461686 -38.62530756
OS 33.45554142 -38.61883564
OS 33.45554142 -38.60959004
OS 33.45646598 -38.60034444
OS 33.45739054 -38.58832516
OS 33.45923966 -38.57630588
OS 33.46386246 -38.54949364
OS 33.47033438 -38.51990772
OS 33.47957998 -38.4903218
OS 33.49252382 -38.46166044
OS 33.49344838 -38.46073588
OS 33.49437294 -38.4579622
OS 33.49622206 -38.45426396
OS 33.4999203 -38.44964116
OS 33.50361854 -38.44316924
OS 33.50824134 -38.43577276
OS 33.52026062 -38.41913068
OS 33.53597814 -38.40063948
OS 33.55446934 -38.38214828
OS 33.57573422 -38.36365708
OS 33.60069734 -38.34793956
OS 33.6016219 -38.347015
OS 33.60439558 -38.34609044
OS 33.60809382 -38.34424132
OS 33.61271662 -38.34146764
OS 33.6201131 -38.33869396
OS 33.62750958 -38.33592028
OS 33.63675518 -38.33222204
OS 33.64692534 -38.3285238
OS 33.65802006 -38.32482556
OS 33.67003934 -38.32112732
OS 33.69592702 -38.31557996
OS 33.72551294 -38.31095716
OS 33.75602342 -38.30910804
OS 33.76526902 -38.30910804
OS 33.77174094 -38.3100326
OE
OB 35.15858094 -39.1375138 I
OS 34.63805366 -39.1375138
OS 34.63805366 -39.08111564
OS 35.15858094 -39.08111564
OS 35.15858094 -39.1375138
OE
OB 34.37917686 -38.32112732 I
OS 34.38657334 -38.32112732
OS 34.40321542 -38.32297644
OS 34.42170662 -38.32482556
OS 34.44112238 -38.3285238
OS 34.46053814 -38.3331466
OS 34.47810478 -38.33961852
OS 34.47902934 -38.33961852
OS 34.4799539 -38.34054308
OS 34.48550126 -38.34331676
OS 34.4938223 -38.34793956
OS 34.5030679 -38.35441148
OS 34.51416262 -38.36273252
OS 34.5261819 -38.37290268
OS 34.53727662 -38.38584652
OS 34.54744678 -38.39971492
OS 34.54837134 -38.40156404
OS 34.55114502 -38.4071114
OS 34.55576782 -38.41450788
OS 34.56039062 -38.4256026
OS 34.56501342 -38.43854644
OS 34.56963622 -38.45241484
OS 34.5724099 -38.46813236
OS 34.57333446 -38.48384988
OS 34.57333446 -38.485699
OS 34.57333446 -38.4903218
OS 34.5724099 -38.49864284
OS 34.57056078 -38.508813
OS 34.5677871 -38.52083228
OS 34.5631643 -38.53377612
OS 34.55761694 -38.54671996
OS 34.55022046 -38.56058836
OS 34.5492959 -38.56243748
OS 34.54652222 -38.56613572
OS 34.54097486 -38.5735322
OS 34.53357838 -38.58092868
OS 34.52433278 -38.59017428
OS 34.51323806 -38.60034444
OS 34.49936966 -38.60959004
OS 34.48365214 -38.61883564
OS 34.4845767 -38.61883564
OS 34.48642582 -38.6197602
OS 34.4891995 -38.62068476
OS 34.49289774 -38.62253388
OS 34.50399246 -38.62623212
OS 34.5169363 -38.63270404
OS 34.5308047 -38.64102508
OS 34.54652222 -38.65119524
OS 34.56039062 -38.66321452
OS 34.57333446 -38.67800748
OS 34.57425902 -38.6798566
OS 34.57795726 -38.68540396
OS 34.58350462 -38.693725
OS 34.58905198 -38.70481972
OS 34.59459934 -38.71961268
OS 34.6001467 -38.7353302
OS 34.60384494 -38.7538214
OS 34.6047695 -38.77416172
OS 34.6047695 -38.77508628
OS 34.6047695 -38.77601084
OS 34.6047695 -38.7815582
OS 34.60384494 -38.7908038
OS 34.60199582 -38.80189852
OS 34.6001467 -38.81484236
OS 34.59644846 -38.82871076
OS 34.59182566 -38.84350372
OS 34.58535374 -38.85829668
OS 34.58442918 -38.8601458
OS 34.5816555 -38.8647686
OS 34.57795726 -38.87124052
OS 34.5724099 -38.88048612
OS 34.56501342 -38.88973172
OS 34.55761694 -38.89990188
OS 34.54837134 -38.91007204
OS 34.53820118 -38.91839308
OS 34.53727662 -38.91931764
OS 34.53357838 -38.92209132
OS 34.52710646 -38.92578956
OS 34.51878542 -38.9294878
OS 34.50861526 -38.93503516
OS 34.49659598 -38.94058252
OS 34.48365214 -38.94520532
OS 34.46793462 -38.94982812
OS 34.4660855 -38.94982812
OS 34.46053814 -38.95167724
OS 34.45129254 -38.9526018
OS 34.43927326 -38.95445092
OS 34.4244803 -38.95630004
OS 34.40691366 -38.95814916
OS 34.3874979 -38.95907372
OS 34.36530846 -38.95999828
OS 34.12122462 -38.95999828
OS 34.12122462 -38.32020276
OS 34.37270494 -38.32020276
OS 34.37917686 -38.32112732
OE
OB 31.74233174 -38.95999828 I
OS 31.65264942 -38.95999828
OS 31.65264942 -38.87031596
OS 31.74233174 -38.87031596
OS 31.74233174 -38.95999828
OE
OB 31.52968294 -38.42745172 I
OS 31.50841806 -38.54671996
OS 31.45941638 -38.54671996
OS 31.44000062 -38.42745172
OS 31.44000062 -38.32020276
OS 31.52968294 -38.32020276
OS 31.52968294 -38.42745172
OE
OB 32.0992119 -38.48662356 I
OS 32.10568382 -38.48754812
OS 32.11955222 -38.48939724
OS 32.1361943 -38.49309548
OS 32.15376094 -38.49864284
OS 32.17132758 -38.50696388
OS 32.18889422 -38.51713404
OS 32.18981878 -38.51713404
OS 32.19074334 -38.51898316
OS 32.1962907 -38.5226814
OS 32.20461174 -38.53007788
OS 32.2147819 -38.53932348
OS 32.22587662 -38.55134276
OS 32.23697134 -38.56613572
OS 32.24806606 -38.58370236
OS 32.25731166 -38.60311812
OS 32.25731166 -38.60404268
OS 32.25823622 -38.6058918
OS 32.25916078 -38.60866548
OS 32.2610099 -38.61236372
OS 32.26285902 -38.61791108
OS 32.26470814 -38.624383
OS 32.26933094 -38.63917596
OS 32.27395374 -38.65766716
OS 32.27765198 -38.67800748
OS 32.28042566 -38.70112148
OS 32.28135022 -38.72516004
OS 32.28135022 -38.7260846
OS 32.28135022 -38.72793372
OS 32.28135022 -38.73163196
OS 32.28135022 -38.73717932
OS 32.28042566 -38.74365124
OS 32.28042566 -38.75104772
OS 32.27857654 -38.7676898
OS 32.2748783 -38.78803012
OS 32.2702555 -38.809295
OS 32.26378358 -38.83148444
OS 32.25546254 -38.85367388
OS 32.25546254 -38.85459844
OS 32.25453798 -38.85644756
OS 32.25268886 -38.85922124
OS 32.25083974 -38.86291948
OS 32.24436782 -38.87308964
OS 32.23604678 -38.88603348
OS 32.22587662 -38.89990188
OS 32.21293278 -38.91377028
OS 32.19813982 -38.92763868
OS 32.18057318 -38.94058252
OS 32.17964862 -38.94058252
OS 32.17872406 -38.94150708
OS 32.17595038 -38.9433562
OS 32.17225214 -38.94520532
OS 32.16300654 -38.94982812
OS 32.1500627 -38.95537548
OS 32.13434518 -38.96092284
OS 32.1177031 -38.96554564
OS 32.09828734 -38.96924388
OS 32.07887158 -38.97016844
OS 32.07239966 -38.97016844
OS 32.06500318 -38.96924388
OS 32.05575758 -38.96831932
OS 32.04466286 -38.9664702
OS 32.03264358 -38.96369652
OS 32.0206243 -38.95999828
OS 32.00860502 -38.95445092
OS 32.00768046 -38.95352636
OS 32.00305766 -38.95167724
OS 31.9975103 -38.947979
OS 31.99011382 -38.94243164
OS 31.98271734 -38.93688428
OS 31.97347174 -38.9294878
OS 31.9651507 -38.92116676
OS 31.95775422 -38.91192116
OS 31.95775422 -39.1375138
OS 31.87916662 -39.1375138
OS 31.87916662 -38.49586916
OS 31.95035774 -38.49586916
OS 31.95035774 -38.55689012
OS 31.9512823 -38.555041
OS 31.95498054 -38.55134276
OS 31.95960334 -38.54487084
OS 31.96699982 -38.53747436
OS 31.97532086 -38.52822876
OS 31.98456646 -38.51990772
OS 31.99566118 -38.51158668
OS 32.0067559 -38.5041902
OS 32.00860502 -38.50326564
OS 32.01230326 -38.50141652
OS 32.01969974 -38.49864284
OS 32.02894534 -38.4949446
OS 32.04004006 -38.49124636
OS 32.0529839 -38.48847268
OS 32.06777686 -38.48662356
OS 32.08441894 -38.485699
OS 32.0945891 -38.485699
OS 32.0992119 -38.48662356
OE
OB 32.5614919 -38.48662356 I
OS 32.57166206 -38.48847268
OS 32.58368134 -38.49217092
OS 32.59662518 -38.49679372
OS 32.61141814 -38.50326564
OS 32.62713566 -38.51158668
OS 32.5984743 -38.58370236
OS 32.59754974 -38.5827778
OS 32.5938515 -38.58092868
OS 32.58830414 -38.578155
OS 32.58090766 -38.57538132
OS 32.57258662 -38.57260764
OS 32.56241646 -38.56983396
OS 32.5522463 -38.56798484
OS 32.54207614 -38.56706028
OS 32.53745334 -38.56706028
OS 32.53283054 -38.56798484
OS 32.52635862 -38.5689094
OS 32.5198867 -38.57075852
OS 32.51156566 -38.5735322
OS 32.50324462 -38.57723044
OS 32.49584814 -38.5827778
OS 32.49492358 -38.58370236
OS 32.4921499 -38.58555148
OS 32.48937622 -38.58924972
OS 32.48475342 -38.59387252
OS 32.48013062 -38.60034444
OS 32.47550782 -38.60774092
OS 32.47088502 -38.61606196
OS 32.46718678 -38.62623212
OS 32.46626222 -38.62808124
OS 32.46533766 -38.6336286
OS 32.46348854 -38.64194964
OS 32.46071486 -38.65304436
OS 32.45794118 -38.66691276
OS 32.45609206 -38.68263028
OS 32.4551675 -38.69927236
OS 32.45424294 -38.71776356
OS 32.45424294 -38.95999828
OS 32.37565534 -38.95999828
OS 32.37565534 -38.49586916
OS 32.44684646 -38.49586916
OS 32.44684646 -38.56613572
OS 32.44777102 -38.56521116
OS 32.45146926 -38.55873924
OS 32.45609206 -38.5504182
OS 32.46348854 -38.54024804
OS 32.47088502 -38.53007788
OS 32.47920606 -38.51898316
OS 32.4875271 -38.50973756
OS 32.49584814 -38.50234108
OS 32.4967727 -38.50141652
OS 32.49954638 -38.4995674
OS 32.50509374 -38.49679372
OS 32.5106411 -38.49402004
OS 32.51803758 -38.49124636
OS 32.52728318 -38.48847268
OS 32.53652878 -38.48662356
OS 32.54669894 -38.485699
OS 32.55317086 -38.485699
OS 32.5614919 -38.48662356
OE
OB 32.75195126 -38.4117342 I
OS 32.67336366 -38.4117342
OS 32.67336366 -38.32020276
OS 32.75195126 -38.32020276
OS 32.75195126 -38.4117342
OE
OB 36.56668582 -38.95999828 I
OS 36.47885262 -38.95999828
OS 36.1441619 -38.4579622
OS 36.1441619 -38.95999828
OS 36.06280062 -38.95999828
OS 36.06280062 -38.32020276
OS 36.14970926 -38.32020276
OS 36.48532454 -38.8231634
OS 36.48532454 -38.32020276
OS 36.56668582 -38.32020276
OS 36.56668582 -38.95999828
OE
OB 35.74382742 -38.32112732 I
OS 35.75954494 -38.32205188
OS 35.77618702 -38.32297644
OS 35.79190454 -38.32482556
OS 35.80577294 -38.32667468
OS 35.80762206 -38.32667468
OS 35.81409398 -38.3285238
OS 35.82241502 -38.33037292
OS 35.83350974 -38.3331466
OS 35.84552902 -38.3377694
OS 35.85847286 -38.34331676
OS 35.87234126 -38.34978868
OS 35.88436054 -38.35718516
OS 35.88620966 -38.35810972
OS 35.8899079 -38.3608834
OS 35.89545526 -38.36643076
OS 35.90285174 -38.37290268
OS 35.91117278 -38.38122372
OS 35.91949382 -38.39231844
OS 35.92873942 -38.40433772
OS 35.9361359 -38.41820612
OS 35.93706046 -38.42005524
OS 35.93890958 -38.42467804
OS 35.94260782 -38.43299908
OS 35.94630606 -38.4440938
OS 35.94907974 -38.45703764
OS 35.95277798 -38.4718306
OS 35.9546271 -38.48847268
OS 35.95555166 -38.50603932
OS 35.95555166 -38.50696388
OS 35.95555166 -38.50973756
OS 35.95555166 -38.5134358
OS 35.9546271 -38.51990772
OS 35.95370254 -38.52637964
OS 35.95277798 -38.53470068
OS 35.95092886 -38.54394628
OS 35.94907974 -38.55411644
OS 35.94260782 -38.57538132
OS 35.93890958 -38.58647604
OS 35.93336222 -38.59849532
OS 35.9268903 -38.6105146
OS 35.92041838 -38.62160932
OS 35.91209734 -38.63270404
OS 35.90285174 -38.64379876
OS 35.90192718 -38.64472332
OS 35.90007806 -38.64657244
OS 35.89730438 -38.64934612
OS 35.89268158 -38.6521198
OS 35.88713422 -38.6567426
OS 35.87973774 -38.6613654
OS 35.87049214 -38.66691276
OS 35.86032198 -38.67153556
OS 35.8483027 -38.67708292
OS 35.8344343 -38.68263028
OS 35.81964134 -38.68725308
OS 35.8020747 -38.69095132
OS 35.7835835 -38.69464956
OS 35.76324318 -38.69742324
OS 35.74012918 -38.69927236
OS 35.71609062 -38.70019692
OS 35.5524435 -38.70019692
OS 35.5524435 -38.95999828
OS 35.46738398 -38.95999828
OS 35.46738398 -38.32020276
OS 35.72995902 -38.32020276
OS 35.74382742 -38.32112732
OE
OB 36.76916446 -38.42745172 I
OS 36.74789958 -38.54671996
OS 36.6988979 -38.54671996
OS 36.67948214 -38.42745172
OS 36.67948214 -38.32020276
OS 36.76916446 -38.32020276
OS 36.76916446 -38.42745172
OE
OB 38.2382903 -38.39601668 I
OS 37.86014526 -38.39601668
OS 37.86014526 -38.59109884
OS 38.21425174 -38.59109884
OS 38.21425174 -38.66691276
OS 37.86014526 -38.66691276
OS 37.86014526 -38.88418436
OS 38.25308326 -38.88418436
OS 38.25308326 -38.95999828
OS 37.77508574 -38.95999828
OS 37.77508574 -38.32020276
OS 38.2382903 -38.32020276
OS 38.2382903 -38.39601668
OE
OB 37.4339231 -38.32112732 I
OS 37.44224414 -38.32112732
OS 37.4616599 -38.32205188
OS 37.48200022 -38.32482556
OS 37.50418966 -38.32759924
OS 37.52452998 -38.33222204
OS 37.53470014 -38.33499572
OS 37.54302118 -38.3377694
OS 37.54394574 -38.3377694
OS 37.5448703 -38.33869396
OS 37.55041766 -38.34146764
OS 37.5587387 -38.34516588
OS 37.56890886 -38.3516378
OS 37.58000358 -38.35995884
OS 37.59202286 -38.37105356
OS 37.60311758 -38.3839974
OS 37.6142123 -38.39879036
OS 37.6142123 -38.39971492
OS 37.61513686 -38.40063948
OS 37.6188351 -38.40618684
OS 37.62253334 -38.41543244
OS 37.6280807 -38.42745172
OS 37.6327035 -38.44132012
OS 37.6373263 -38.4579622
OS 37.64009998 -38.47552884
OS 37.64102454 -38.4949446
OS 37.64102454 -38.49586916
OS 37.64102454 -38.49771828
OS 37.64102454 -38.50141652
OS 37.64009998 -38.50603932
OS 37.64009998 -38.51251124
OS 37.63917542 -38.51898316
OS 37.63547718 -38.53470068
OS 37.62992982 -38.55319188
OS 37.62253334 -38.57260764
OS 37.61143862 -38.5920234
OS 37.60404214 -38.601269
OS 37.59664566 -38.6105146
OS 37.5957211 -38.61143916
OS 37.59479654 -38.61236372
OS 37.59202286 -38.6151374
OS 37.58832462 -38.61791108
OS 37.58370182 -38.62160932
OS 37.57815446 -38.62530756
OS 37.57075798 -38.62993036
OS 37.5633615 -38.63547772
OS 37.5541159 -38.64010052
OS 37.54394574 -38.64472332
OS 37.53285102 -38.65027068
OS 37.52083174 -38.65489348
OS 37.50696334 -38.65859172
OS 37.49309494 -38.66321452
OS 37.47737742 -38.6659882
OS 37.46073534 -38.66876188
OS 37.46258446 -38.66968644
OS 37.4662827 -38.67153556
OS 37.47183006 -38.6752338
OS 37.47922654 -38.67893204
OS 37.49586862 -38.6891022
OS 37.50418966 -38.69557412
OS 37.51158614 -38.70112148
OS 37.51343526 -38.7029706
OS 37.51805806 -38.7075934
OS 37.52545454 -38.71498988
OS 37.53470014 -38.72423548
OS 37.5448703 -38.73717932
OS 37.55688958 -38.75104772
OS 37.56890886 -38.7676898
OS 37.5818527 -38.786181
OS 37.69187534 -38.95999828
OS 37.5864755 -38.95999828
OS 37.50234054 -38.82686164
OS 37.50234054 -38.82593708
OS 37.50049142 -38.82408796
OS 37.4986423 -38.82131428
OS 37.49586862 -38.81761604
OS 37.4893967 -38.80744588
OS 37.48107566 -38.79450204
OS 37.4709055 -38.78063364
OS 37.46073534 -38.76584068
OS 37.45056518 -38.75197228
OS 37.44131958 -38.73902844
OS 37.44039502 -38.73810388
OS 37.43762134 -38.73440564
OS 37.43299854 -38.72885828
OS 37.42652662 -38.72238636
OS 37.41265822 -38.70851796
OS 37.40526174 -38.70204604
OS 37.39786526 -38.69649868
OS 37.3969407 -38.69557412
OS 37.39509158 -38.69464956
OS 37.39139334 -38.69280044
OS 37.38584598 -38.69002676
OS 37.38029862 -38.68725308
OS 37.3738267 -38.6844794
OS 37.35903374 -38.6798566
OS 37.35810918 -38.6798566
OS 37.35626006 -38.67893204
OS 37.35256182 -38.67893204
OS 37.34793902 -38.67800748
OS 37.3414671 -38.67708292
OS 37.33407062 -38.67708292
OS 37.32390046 -38.67615836
OS 37.21480238 -38.67615836
OS 37.21480238 -38.95999828
OS 37.12974286 -38.95999828
OS 37.12974286 -38.32020276
OS 37.42652662 -38.32020276
OS 37.4339231 -38.32112732
OE
OB 35.31760526 -38.95999828 I
OS 35.23254574 -38.95999828
OS 35.23254574 -38.32020276
OS 35.31760526 -38.32020276
OS 35.31760526 -38.95999828
OE
OB 42.12051774 -38.66413908 H
OS 41.95224782 -38.66413908
OS 41.95224782 -38.88418436
OS 42.13438614 -38.88418436
OS 42.1538019 -38.8832598
OS 42.16212294 -38.88233524
OS 42.16951942 -38.88141068
OS 42.17044398 -38.88141068
OS 42.17414222 -38.88048612
OS 42.17968958 -38.87956156
OS 42.1861615 -38.87771244
OS 42.20187902 -38.87216508
OS 42.21759654 -38.8647686
OS 42.2185211 -38.86384404
OS 42.22129478 -38.86199492
OS 42.22499302 -38.85922124
OS 42.22961582 -38.855523
OS 42.23423862 -38.84997564
OS 42.24071054 -38.84442828
OS 42.24533334 -38.8370318
OS 42.2508807 -38.82871076
OS 42.25180526 -38.8277862
OS 42.25272982 -38.82501252
OS 42.25457894 -38.81946516
OS 42.25735262 -38.81299324
OS 42.2601263 -38.80559676
OS 42.26197542 -38.79635116
OS 42.26289998 -38.78525644
OS 42.26382454 -38.77416172
OS 42.26382454 -38.7723126
OS 42.26382454 -38.76861436
OS 42.26289998 -38.76121788
OS 42.26105086 -38.75289684
OS 42.25920174 -38.74365124
OS 42.2555035 -38.73348108
OS 42.2508807 -38.72331092
OS 42.24440878 -38.71314076
OS 42.24348422 -38.7122162
OS 42.24071054 -38.70851796
OS 42.2370123 -38.70389516
OS 42.23146494 -38.6983478
OS 42.22406846 -38.69187588
OS 42.21482286 -38.68540396
OS 42.2046527 -38.6798566
OS 42.19263342 -38.6752338
OS 42.1907843 -38.67430924
OS 42.18708606 -38.67338468
OS 42.17876502 -38.67153556
OS 42.16859486 -38.66968644
OS 42.15565102 -38.66783732
OS 42.1399335 -38.6659882
OS 42.12051774 -38.66413908
OE
OB 45.22981302 -38.5504182 H
OS 45.22426566 -38.5504182
OS 45.21964286 -38.55134276
OS 45.2094727 -38.55226732
OS 45.1956043 -38.55596556
OS 45.17988678 -38.56151292
OS 45.1632447 -38.5689094
OS 45.14752718 -38.58000412
OS 45.13920614 -38.5874006
OS 45.13180966 -38.59479708
OS 45.13180966 -38.59572164
OS 45.12996054 -38.5966462
OS 45.12811142 -38.59941988
OS 45.12533774 -38.60311812
OS 45.12256406 -38.60774092
OS 45.11979038 -38.61328828
OS 45.11609214 -38.62068476
OS 45.1123939 -38.62808124
OS 45.10869566 -38.63732684
OS 45.10499742 -38.64657244
OS 45.10222374 -38.65766716
OS 45.09945006 -38.66968644
OS 45.09667638 -38.68263028
OS 45.09482726 -38.69649868
OS 45.0939027 -38.7122162
OS 45.09297814 -38.72793372
OS 45.09297814 -38.72885828
OS 45.09297814 -38.73163196
OS 45.09297814 -38.73625476
OS 45.0939027 -38.74272668
OS 45.0939027 -38.75012316
OS 45.09482726 -38.7584442
OS 45.09760094 -38.77785996
OS 45.10222374 -38.8000494
OS 45.10962022 -38.82223884
OS 45.11886582 -38.84350372
OS 45.12533774 -38.85274932
OS 45.13180966 -38.86199492
OS 45.13273422 -38.86199492
OS 45.13365878 -38.86384404
OS 45.13920614 -38.86846684
OS 45.14752718 -38.87586332
OS 45.1586219 -38.8832598
OS 45.1724903 -38.89158084
OS 45.18913238 -38.89897732
OS 45.20854814 -38.90360012
OS 45.2187183 -38.90452468
OS 45.22981302 -38.90544924
OS 45.23536038 -38.90544924
OS 45.23998318 -38.90452468
OS 45.25015334 -38.90267556
OS 45.26402174 -38.89990188
OS 45.2788147 -38.89435452
OS 45.29545678 -38.88695804
OS 45.3111743 -38.87586332
OS 45.31949534 -38.86846684
OS 45.32689182 -38.86107036
OS 45.32781638 -38.8601458
OS 45.32874094 -38.85922124
OS 45.33059006 -38.85644756
OS 45.33336374 -38.85274932
OS 45.33613742 -38.84812652
OS 45.33983566 -38.84257916
OS 45.3435339 -38.83518268
OS 45.34723214 -38.8277862
OS 45.35093038 -38.8185406
OS 45.35370406 -38.80837044
OS 45.3574023 -38.79727572
OS 45.36017598 -38.78525644
OS 45.36294966 -38.77138804
OS 45.36479878 -38.75751964
OS 45.3666479 -38.74180212
OS 45.3666479 -38.72516004
OS 45.3666479 -38.72423548
OS 45.3666479 -38.7214618
OS 45.3666479 -38.716839
OS 45.36572334 -38.71129164
OS 45.36572334 -38.70389516
OS 45.36479878 -38.69557412
OS 45.3620251 -38.67615836
OS 45.3574023 -38.65581804
OS 45.35000582 -38.6336286
OS 45.33983566 -38.61328828
OS 45.3342883 -38.60311812
OS 45.32689182 -38.59479708
OS 45.32689182 -38.59387252
OS 45.3250427 -38.59294796
OS 45.31949534 -38.5874006
OS 45.3111743 -38.58092868
OS 45.30007958 -38.57260764
OS 45.28621118 -38.5642866
OS 45.2695691 -38.55689012
OS 45.2510779 -38.55226732
OS 45.24090774 -38.55134276
OS 45.22981302 -38.5504182
OE
OB 32.07702246 -38.54764452 H
OS 32.07239966 -38.54764452
OS 32.06870142 -38.54856908
OS 32.05945582 -38.5504182
OS 32.04743654 -38.55319188
OS 32.03356814 -38.55873924
OS 32.01877518 -38.56706028
OS 32.01045414 -38.57260764
OS 32.00305766 -38.57907956
OS 31.99566118 -38.58647604
OS 31.9882647 -38.59479708
OS 31.9882647 -38.59572164
OS 31.98641558 -38.5966462
OS 31.98456646 -38.59941988
OS 31.98271734 -38.60311812
OS 31.97994366 -38.60866548
OS 31.97624542 -38.61421284
OS 31.97254718 -38.62160932
OS 31.9697735 -38.6290058
OS 31.96607526 -38.6382514
OS 31.96237702 -38.64842156
OS 31.95960334 -38.65951628
OS 31.9559051 -38.67153556
OS 31.95405598 -38.68540396
OS 31.95220686 -38.69927236
OS 31.95035774 -38.71406532
OS 31.95035774 -38.7307074
OS 31.95035774 -38.73163196
OS 31.95035774 -38.73440564
OS 31.95035774 -38.73902844
OS 31.9512823 -38.74550036
OS 31.9512823 -38.75289684
OS 31.95220686 -38.76121788
OS 31.95498054 -38.78063364
OS 31.95960334 -38.80282308
OS 31.9651507 -38.82408796
OS 31.9743963 -38.84535284
OS 31.97994366 -38.85459844
OS 31.98641558 -38.86291948
OS 31.9882647 -38.8647686
OS 31.9928875 -38.8693914
OS 32.00028398 -38.87678788
OS 32.01045414 -38.88418436
OS 32.02339798 -38.89158084
OS 32.03819094 -38.89897732
OS 32.05483302 -38.90360012
OS 32.06407862 -38.90452468
OS 32.07332422 -38.90544924
OS 32.07887158 -38.90544924
OS 32.08256982 -38.90452468
OS 32.09181542 -38.90267556
OS 32.10475926 -38.89990188
OS 32.11862766 -38.89435452
OS 32.13342062 -38.88695804
OS 32.14821358 -38.87586332
OS 32.15561006 -38.8693914
OS 32.16300654 -38.86199492
OS 32.16300654 -38.86107036
OS 32.16485566 -38.8601458
OS 32.16670478 -38.85737212
OS 32.1685539 -38.85367388
OS 32.17225214 -38.84905108
OS 32.17502582 -38.84257916
OS 32.17872406 -38.83610724
OS 32.1824223 -38.8277862
OS 32.18519598 -38.81946516
OS 32.18889422 -38.80837044
OS 32.19259246 -38.79727572
OS 32.19536614 -38.78525644
OS 32.19721526 -38.77138804
OS 32.19906438 -38.75659508
OS 32.2009135 -38.74087756
OS 32.2009135 -38.72423548
OS 32.2009135 -38.72331092
OS 32.2009135 -38.72053724
OS 32.2009135 -38.71591444
OS 32.19998894 -38.70944252
OS 32.19998894 -38.70204604
OS 32.19906438 -38.693725
OS 32.1962907 -38.67430924
OS 32.1916679 -38.65304436
OS 32.18519598 -38.63177948
OS 32.17595038 -38.6105146
OS 32.17040302 -38.60034444
OS 32.1639311 -38.5920234
OS 32.1639311 -38.59109884
OS 32.16208198 -38.59017428
OS 32.15745918 -38.58462692
OS 32.1500627 -38.578155
OS 32.13989254 -38.56983396
OS 32.1269487 -38.56151292
OS 32.11215574 -38.55411644
OS 32.09551366 -38.54949364
OS 32.08626806 -38.54856908
OS 32.07702246 -38.54764452
OE
OB 42.10387566 -38.39601668 H
OS 41.95224782 -38.39601668
OS 41.95224782 -38.58832516
OS 42.10942302 -38.58832516
OS 42.1214423 -38.5874006
OS 42.13438614 -38.58647604
OS 42.14732998 -38.58555148
OS 42.16027382 -38.58370236
OS 42.17044398 -38.58185324
OS 42.1722931 -38.58092868
OS 42.17599134 -38.58000412
OS 42.1815387 -38.57723044
OS 42.18893518 -38.5735322
OS 42.19633166 -38.56983396
OS 42.2046527 -38.5642866
OS 42.21297374 -38.55689012
OS 42.21944566 -38.54949364
OS 42.22037022 -38.54856908
OS 42.22221934 -38.5457954
OS 42.22499302 -38.54024804
OS 42.2277667 -38.53377612
OS 42.23054038 -38.52637964
OS 42.23331406 -38.51713404
OS 42.23516318 -38.50603932
OS 42.23608774 -38.49402004
OS 42.23608774 -38.49217092
OS 42.23608774 -38.48847268
OS 42.23516318 -38.48292532
OS 42.23423862 -38.47552884
OS 42.2323895 -38.46628324
OS 42.22961582 -38.45703764
OS 42.22591758 -38.44779204
OS 42.22037022 -38.43854644
OS 42.21944566 -38.43762188
OS 42.21759654 -38.4348482
OS 42.2138983 -38.4302254
OS 42.2092755 -38.4256026
OS 42.20280358 -38.42005524
OS 42.1954071 -38.41450788
OS 42.1861615 -38.40896052
OS 42.17599134 -38.40526228
OS 42.17506678 -38.40526228
OS 42.17044398 -38.40341316
OS 42.16397206 -38.4024886
OS 42.1538019 -38.40063948
OS 42.1399335 -38.39879036
OS 42.12421598 -38.3978658
OS 42.10387566 -38.39601668
OE
OB 37.41635646 -38.39139388 H
OS 37.21480238 -38.39139388
OS 37.21480238 -38.60311812
OS 37.40526174 -38.60311812
OS 37.41635646 -38.60219356
OS 37.4293003 -38.601269
OS 37.44409326 -38.60034444
OS 37.45888622 -38.59849532
OS 37.47367918 -38.59572164
OS 37.48662302 -38.5920234
OS 37.48847214 -38.59109884
OS 37.49217038 -38.58924972
OS 37.49771774 -38.58647604
OS 37.50511422 -38.5827778
OS 37.51343526 -38.57723044
OS 37.5217563 -38.57075852
OS 37.53007734 -38.56243748
OS 37.53654926 -38.55319188
OS 37.53747382 -38.55226732
OS 37.53932294 -38.54856908
OS 37.54209662 -38.54302172
OS 37.54579486 -38.53562524
OS 37.54856854 -38.5273042
OS 37.55134222 -38.5180586
OS 37.55319134 -38.50696388
OS 37.5541159 -38.49586916
OS 37.5541159 -38.4949446
OS 37.5541159 -38.49402004
OS 37.55319134 -38.48847268
OS 37.55226678 -38.48015164
OS 37.55041766 -38.46905692
OS 37.54579486 -38.4579622
OS 37.5402475 -38.44501836
OS 37.53192646 -38.43299908
OS 37.52083174 -38.4209798
OS 37.51898262 -38.42005524
OS 37.51435982 -38.416357
OS 37.50696334 -38.4117342
OS 37.49494406 -38.40618684
OS 37.48107566 -38.40063948
OS 37.46258446 -38.39601668
OS 37.44131958 -38.39231844
OS 37.41635646 -38.39139388
OE
OB 39.82298614 -38.54764452 H
OS 39.81836334 -38.54764452
OS 39.8146651 -38.54856908
OS 39.8054195 -38.5504182
OS 39.79340022 -38.55319188
OS 39.77953182 -38.55873924
OS 39.76473886 -38.56706028
OS 39.75641782 -38.57260764
OS 39.74902134 -38.57907956
OS 39.74162486 -38.58647604
OS 39.73422838 -38.59479708
OS 39.73422838 -38.59572164
OS 39.73237926 -38.5966462
OS 39.73053014 -38.59941988
OS 39.72868102 -38.60311812
OS 39.72590734 -38.60866548
OS 39.7222091 -38.61421284
OS 39.71851086 -38.62160932
OS 39.71573718 -38.6290058
OS 39.71203894 -38.6382514
OS 39.7083407 -38.64842156
OS 39.70556702 -38.65951628
OS 39.70186878 -38.67153556
OS 39.70001966 -38.68540396
OS 39.69817054 -38.69927236
OS 39.69632142 -38.71406532
OS 39.69632142 -38.7307074
OS 39.69632142 -38.73163196
OS 39.69632142 -38.73440564
OS 39.69632142 -38.73902844
OS 39.69724598 -38.74550036
OS 39.69724598 -38.75289684
OS 39.69817054 -38.76121788
OS 39.70094422 -38.78063364
OS 39.70556702 -38.80282308
OS 39.71111438 -38.82408796
OS 39.72035998 -38.84535284
OS 39.72590734 -38.85459844
OS 39.73237926 -38.86291948
OS 39.73422838 -38.8647686
OS 39.73885118 -38.8693914
OS 39.74624766 -38.87678788
OS 39.75641782 -38.88418436
OS 39.76936166 -38.89158084
OS 39.78415462 -38.89897732
OS 39.8007967 -38.90360012
OS 39.8100423 -38.90452468
OS 39.8192879 -38.90544924
OS 39.82483526 -38.90544924
OS 39.8285335 -38.90452468
OS 39.8377791 -38.90267556
OS 39.85072294 -38.89990188
OS 39.86459134 -38.89435452
OS 39.8793843 -38.88695804
OS 39.89417726 -38.87586332
OS 39.90157374 -38.8693914
OS 39.90897022 -38.86199492
OS 39.90897022 -38.86107036
OS 39.91081934 -38.8601458
OS 39.91266846 -38.85737212
OS 39.91451758 -38.85367388
OS 39.91821582 -38.84905108
OS 39.9209895 -38.84257916
OS 39.92468774 -38.83610724
OS 39.92838598 -38.8277862
OS 39.93115966 -38.81946516
OS 39.9348579 -38.80837044
OS 39.93855614 -38.79727572
OS 39.94132982 -38.78525644
OS 39.94317894 -38.77138804
OS 39.94502806 -38.75659508
OS 39.94687718 -38.74087756
OS 39.94687718 -38.72423548
OS 39.94687718 -38.72331092
OS 39.94687718 -38.72053724
OS 39.94687718 -38.71591444
OS 39.94595262 -38.70944252
OS 39.94595262 -38.70204604
OS 39.94502806 -38.693725
OS 39.94225438 -38.67430924
OS 39.93763158 -38.65304436
OS 39.93115966 -38.63177948
OS 39.92191406 -38.6105146
OS 39.9163667 -38.60034444
OS 39.90989478 -38.5920234
OS 39.90989478 -38.59109884
OS 39.90804566 -38.59017428
OS 39.90342286 -38.58462692
OS 39.89602638 -38.578155
OS 39.88585622 -38.56983396
OS 39.87291238 -38.56151292
OS 39.85811942 -38.55411644
OS 39.84147734 -38.54949364
OS 39.83223174 -38.54856908
OS 39.82298614 -38.54764452
OE
OB 35.73550638 -38.39601668 H
OS 35.5524435 -38.39601668
OS 35.5524435 -38.624383
OS 35.72441166 -38.624383
OS 35.73088358 -38.62345844
OS 35.7373555 -38.62345844
OS 35.74475198 -38.62253388
OS 35.76231862 -38.62068476
OS 35.78173438 -38.61698652
OS 35.80115014 -38.61143916
OS 35.81871678 -38.60404268
OS 35.82703782 -38.59941988
OS 35.83350974 -38.59387252
OS 35.83535886 -38.5920234
OS 35.8390571 -38.58832516
OS 35.84460446 -38.58092868
OS 35.85107638 -38.57168308
OS 35.8575483 -38.5596638
OS 35.86309566 -38.54487084
OS 35.8667939 -38.52822876
OS 35.86864302 -38.508813
OS 35.86864302 -38.50788844
OS 35.86864302 -38.50696388
OS 35.86864302 -38.50234108
OS 35.86771846 -38.49402004
OS 35.86586934 -38.48477444
OS 35.86402022 -38.47460428
OS 35.86032198 -38.462585
OS 35.85477462 -38.45149028
OS 35.8483027 -38.44039556
OS 35.84737814 -38.439471
OS 35.84460446 -38.43577276
OS 35.83998166 -38.43114996
OS 35.8344343 -38.42467804
OS 35.82611326 -38.41820612
OS 35.81686766 -38.41265876
OS 35.8066975 -38.4071114
OS 35.79467822 -38.4024886
OS 35.79375366 -38.4024886
OS 35.79005542 -38.40156404
OS 35.78450806 -38.40063948
OS 35.77711158 -38.39879036
OS 35.76601686 -38.3978658
OS 35.75214846 -38.39694124
OS 35.73550638 -38.39601668
OE
OB 43.44263854 -38.5504182 H
OS 43.43709118 -38.5504182
OS 43.43339294 -38.55134276
OS 43.42322278 -38.55226732
OS 43.4112035 -38.555041
OS 43.39641054 -38.5596638
OS 43.38069302 -38.56613572
OS 43.36590006 -38.57538132
OS 43.3511071 -38.5874006
OS 43.34925798 -38.58924972
OS 43.34555974 -38.59387252
OS 43.33908782 -38.60219356
OS 43.3326159 -38.61328828
OS 43.32521942 -38.62623212
OS 43.3187475 -38.6428742
OS 43.31320014 -38.66228996
OS 43.31042646 -38.68355484
OS 43.57022782 -38.68355484
OS 43.57022782 -38.68263028
OS 43.57022782 -38.68078116
OS 43.56930326 -38.67800748
OS 43.56930326 -38.67430924
OS 43.56745414 -38.66321452
OS 43.56468046 -38.65119524
OS 43.56005766 -38.63640228
OS 43.55543486 -38.62253388
OS 43.54803838 -38.60866548
OS 43.53971734 -38.5966462
OS 43.53971734 -38.59572164
OS 43.53786822 -38.59479708
OS 43.53324542 -38.58924972
OS 43.52492438 -38.58185324
OS 43.51382966 -38.5735322
OS 43.49996126 -38.56521116
OS 43.48331918 -38.55781468
OS 43.46390342 -38.55226732
OS 43.45373326 -38.55134276
OS 43.44263854 -38.5504182
OE
OB 34.35791198 -38.39601668 H
OS 34.20628414 -38.39601668
OS 34.20628414 -38.58832516
OS 34.36345934 -38.58832516
OS 34.37547862 -38.5874006
OS 34.38842246 -38.58647604
OS 34.4013663 -38.58555148
OS 34.41431014 -38.58370236
OS 34.4244803 -38.58185324
OS 34.42632942 -38.58092868
OS 34.43002766 -38.58000412
OS 34.43557502 -38.57723044
OS 34.4429715 -38.5735322
OS 34.45036798 -38.56983396
OS 34.45868902 -38.5642866
OS 34.46701006 -38.55689012
OS 34.47348198 -38.54949364
OS 34.47440654 -38.54856908
OS 34.47625566 -38.5457954
OS 34.47902934 -38.54024804
OS 34.48180302 -38.53377612
OS 34.4845767 -38.52637964
OS 34.48735038 -38.51713404
OS 34.4891995 -38.50603932
OS 34.49012406 -38.49402004
OS 34.49012406 -38.49217092
OS 34.49012406 -38.48847268
OS 34.4891995 -38.48292532
OS 34.48827494 -38.47552884
OS 34.48642582 -38.46628324
OS 34.48365214 -38.45703764
OS 34.4799539 -38.44779204
OS 34.47440654 -38.43854644
OS 34.47348198 -38.43762188
OS 34.47163286 -38.4348482
OS 34.46793462 -38.4302254
OS 34.46331182 -38.4256026
OS 34.4568399 -38.42005524
OS 34.44944342 -38.41450788
OS 34.44019782 -38.40896052
OS 34.43002766 -38.40526228
OS 34.4291031 -38.40526228
OS 34.4244803 -38.40341316
OS 34.41800838 -38.4024886
OS 34.40783822 -38.40063948
OS 34.39396982 -38.39879036
OS 34.3782523 -38.3978658
OS 34.35791198 -38.39601668
OE
OB 40.89732486 -38.39601668 H
OS 40.71426198 -38.39601668
OS 40.71426198 -38.624383
OS 40.88623014 -38.624383
OS 40.89270206 -38.62345844
OS 40.89917398 -38.62345844
OS 40.90657046 -38.62253388
OS 40.9241371 -38.62068476
OS 40.94355286 -38.61698652
OS 40.96296862 -38.61143916
OS 40.98053526 -38.60404268
OS 40.9888563 -38.59941988
OS 40.99532822 -38.59387252
OS 40.99717734 -38.5920234
OS 41.00087558 -38.58832516
OS 41.00642294 -38.58092868
OS 41.01289486 -38.57168308
OS 41.01936678 -38.5596638
OS 41.02491414 -38.54487084
OS 41.02861238 -38.52822876
OS 41.0304615 -38.508813
OS 41.0304615 -38.50788844
OS 41.0304615 -38.50696388
OS 41.0304615 -38.50234108
OS 41.02953694 -38.49402004
OS 41.02768782 -38.48477444
OS 41.0258387 -38.47460428
OS 41.02214046 -38.462585
OS 41.0165931 -38.45149028
OS 41.01012118 -38.44039556
OS 41.00919662 -38.439471
OS 41.00642294 -38.43577276
OS 41.00180014 -38.43114996
OS 40.99625278 -38.42467804
OS 40.98793174 -38.41820612
OS 40.97868614 -38.41265876
OS 40.96851598 -38.4071114
OS 40.9564967 -38.4024886
OS 40.95557214 -38.4024886
OS 40.9518739 -38.40156404
OS 40.94632654 -38.40063948
OS 40.93893006 -38.39879036
OS 40.92783534 -38.3978658
OS 40.91396694 -38.39694124
OS 40.89732486 -38.39601668
OE
OB 33.15136118 -38.39601668 H
OS 32.9682983 -38.39601668
OS 32.9682983 -38.624383
OS 33.14026646 -38.624383
OS 33.14673838 -38.62345844
OS 33.1532103 -38.62345844
OS 33.16060678 -38.62253388
OS 33.17817342 -38.62068476
OS 33.19758918 -38.61698652
OS 33.21700494 -38.61143916
OS 33.23457158 -38.60404268
OS 33.24289262 -38.59941988
OS 33.24936454 -38.59387252
OS 33.25121366 -38.5920234
OS 33.2549119 -38.58832516
OS 33.26045926 -38.58092868
OS 33.26693118 -38.57168308
OS 33.2734031 -38.5596638
OS 33.27895046 -38.54487084
OS 33.2826487 -38.52822876
OS 33.28449782 -38.508813
OS 33.28449782 -38.50788844
OS 33.28449782 -38.50696388
OS 33.28449782 -38.50234108
OS 33.28357326 -38.49402004
OS 33.28172414 -38.48477444
OS 33.27987502 -38.47460428
OS 33.27617678 -38.462585
OS 33.27062942 -38.45149028
OS 33.2641575 -38.44039556
OS 33.26323294 -38.439471
OS 33.26045926 -38.43577276
OS 33.25583646 -38.43114996
OS 33.2502891 -38.42467804
OS 33.24196806 -38.41820612
OS 33.23272246 -38.41265876
OS 33.2225523 -38.4071114
OS 33.21053302 -38.4024886
OS 33.20960846 -38.4024886
OS 33.20591022 -38.40156404
OS 33.20036286 -38.40063948
OS 33.19296638 -38.39879036
OS 33.18187166 -38.3978658
OS 33.16800326 -38.39694124
OS 33.15136118 -38.39601668
OE
OB 34.37455406 -38.66413908 H
OS 34.20628414 -38.66413908
OS 34.20628414 -38.88418436
OS 34.38842246 -38.88418436
OS 34.40783822 -38.8832598
OS 34.41615926 -38.88233524
OS 34.42355574 -38.88141068
OS 34.4244803 -38.88141068
OS 34.42817854 -38.88048612
OS 34.4337259 -38.87956156
OS 34.44019782 -38.87771244
OS 34.45591534 -38.87216508
OS 34.47163286 -38.8647686
OS 34.47255742 -38.86384404
OS 34.4753311 -38.86199492
OS 34.47902934 -38.85922124
OS 34.48365214 -38.855523
OS 34.48827494 -38.84997564
OS 34.49474686 -38.84442828
OS 34.49936966 -38.8370318
OS 34.50491702 -38.82871076
OS 34.50584158 -38.8277862
OS 34.50676614 -38.82501252
OS 34.50861526 -38.81946516
OS 34.51138894 -38.81299324
OS 34.51416262 -38.80559676
OS 34.51601174 -38.79635116
OS 34.5169363 -38.78525644
OS 34.51786086 -38.77416172
OS 34.51786086 -38.7723126
OS 34.51786086 -38.76861436
OS 34.5169363 -38.76121788
OS 34.51508718 -38.75289684
OS 34.51323806 -38.74365124
OS 34.50953982 -38.73348108
OS 34.50491702 -38.72331092
OS 34.4984451 -38.71314076
OS 34.49752054 -38.7122162
OS 34.49474686 -38.70851796
OS 34.49104862 -38.70389516
OS 34.48550126 -38.6983478
OS 34.47810478 -38.69187588
OS 34.46885918 -38.68540396
OS 34.45868902 -38.6798566
OS 34.44666974 -38.6752338
OS 34.44482062 -38.67430924
OS 34.44112238 -38.67338468
OS 34.43280134 -38.67153556
OS 34.42263118 -38.66968644
OS 34.40968734 -38.66783732
OS 34.39396982 -38.6659882
OS 34.37455406 -38.66413908
OE
SE
S P 0
OB 32.31422036 39.98905388 I
OS 32.31422036 40.4254462
OS 32.39927988 40.4254462
OS 32.39927988 39.98443108
OS 32.39927988 39.96501532
OS 32.401129 39.94837324
OS 32.40205356 39.93450484
OS 32.40390268 39.92341012
OS 32.4057518 39.91508908
OS 32.40667636 39.90861716
OS 32.40852548 39.90491892
OS 32.40852548 39.90399436
OS 32.41222372 39.89474876
OS 32.41684652 39.88735228
OS 32.42239388 39.88088036
OS 32.42701668 39.87440844
OS 32.43256404 39.8707102
OS 32.43626228 39.86701196
OS 32.43903596 39.86516284
OS 32.43996052 39.86423828
OS 32.44920612 39.85961548
OS 32.45845172 39.85591724
OS 32.46769732 39.85406812
OS 32.47601836 39.852219
OS 32.4843394 39.85129444
OS 32.48988676 39.85036988
OS 32.49543412 39.85036988
OS 32.51022708 39.85129444
OS 32.52409548 39.85499268
OS 32.5351902 39.85869092
OS 32.54536036 39.86423828
OS 32.55275684 39.86886108
OS 32.5583042 39.87348388
OS 32.56200244 39.87625756
OS 32.562927 39.87718212
OS 32.5675498 39.88272948
OS 32.57124804 39.8892014
OS 32.5767954 39.90399436
OS 32.58234276 39.92063644
OS 32.58511644 39.93727852
OS 32.58789012 39.95299604
OS 32.58789012 39.95946796
OS 32.58881468 39.96501532
OS 32.58973924 39.97056268
OS 32.58973924 39.97426092
OS 32.58973924 39.97611004
OS 32.58973924 39.9770346
OS 32.66647772 39.96593988
OS 32.66647772 39.94837324
OS 32.66555316 39.93265572
OS 32.66277948 39.9169382
OS 32.66093036 39.9030698
OS 32.65723212 39.89012596
OS 32.65353388 39.87903124
OS 32.64983564 39.86793652
OS 32.6461374 39.85869092
OS 32.6415146 39.85036988
OS 32.63781636 39.8429734
OS 32.63411812 39.83650148
OS 32.63041988 39.83187868
OS 32.6276462 39.82818044
OS 32.62579708 39.8244822
OS 32.62487252 39.82355764
OS 32.62394796 39.82263308
OS 32.61470236 39.81431204
OS 32.60545676 39.80691556
OS 32.5952866 39.80044364
OS 32.58419188 39.79489628
OS 32.562927 39.78657524
OS 32.54258668 39.78102788
OS 32.52317092 39.77732964
OS 32.51577444 39.77640508
OS 32.50837796 39.77548052
OS 32.5028306 39.77455596
OS 32.49450956 39.77455596
OS 32.47416924 39.77548052
OS 32.45567804 39.7782542
OS 32.43903596 39.78195244
OS 32.424243 39.78657524
OS 32.41222372 39.79027348
OS 32.40390268 39.79397172
OS 32.39835532 39.7967454
OS 32.3965062 39.79766996
OS 32.38171324 39.80691556
OS 32.3687694 39.81801028
OS 32.35859924 39.829105
OS 32.34935364 39.83927516
OS 32.34288172 39.84944532
OS 32.33825892 39.8568418
OS 32.33548524 39.86238916
OS 32.33456068 39.86331372
OS 32.33456068 39.86423828
OS 32.32808876 39.88272948
OS 32.3225414 39.90214524
OS 32.31884316 39.92341012
OS 32.31699404 39.94375044
OS 32.31514492 39.96131708
OS 32.31514492 39.96871356
OS 32.31422036 39.97611004
OS 32.31422036 39.9816574
OS 32.31422036 39.98535564
OS 32.31422036 39.98812932
OS 32.31422036 39.98905388
OE
OB 31.8140334 40.3422358 I
OS 31.8140334 40.41712516
OS 32.13208204 40.41712516
OS 32.19402756 40.0879818
OS 32.12006276 40.07781164
OS 32.11359084 40.0879818
OS 32.1052698 40.09630284
OS 32.09787332 40.10462388
OS 32.09047684 40.1110958
OS 32.08308036 40.1157186
OS 32.077533 40.1203414
OS 32.07383476 40.12219052
OS 32.0729102 40.12311508
OS 32.06089092 40.12866244
OS 32.04887164 40.13328524
OS 32.03777692 40.13605892
OS 32.0266822 40.1388326
OS 32.0174366 40.13975716
OS 32.01004012 40.14068172
OS 31.99247348 40.14068172
OS 31.98137876 40.1388326
OS 31.961963 40.1342098
OS 31.94532092 40.12773788
OS 31.93052796 40.12126596
OS 31.91943324 40.11386948
OS 31.9111122 40.10739756
OS 31.9064894 40.10277476
OS 31.90464028 40.1018502
OS 31.90464028 40.10092564
OS 31.89169644 40.08520812
OS 31.88245084 40.06856604
OS 31.87597892 40.0509994
OS 31.87135612 40.03343276
OS 31.86858244 40.0186398
OS 31.86765788 40.01216788
OS 31.86765788 40.00662052
OS 31.86673332 40.00199772
OS 31.86673332 39.99829948
OS 31.86673332 39.99645036
OS 31.86673332 39.9955258
OS 31.86673332 39.98258196
OS 31.86858244 39.97056268
OS 31.87320524 39.94744868
OS 31.87967716 39.92803292
OS 31.88614908 39.9123154
OS 31.89354556 39.89937156
OS 31.90001748 39.8892014
OS 31.90279116 39.88642772
OS 31.90464028 39.88365404
OS 31.90556484 39.88272948
OS 31.9064894 39.88180492
OS 31.91388588 39.87440844
OS 31.92128236 39.86793652
OS 31.93792444 39.8568418
OS 31.95364196 39.84944532
OS 31.96935948 39.84482252
OS 31.98230332 39.84112428
OS 31.99339804 39.84019972
OS 31.99709628 39.83927516
OS 32.00264364 39.83927516
OS 32.02021028 39.84019972
OS 32.0359278 39.84389796
OS 32.0497962 39.84852076
OS 32.06089092 39.85406812
OS 32.07106108 39.85961548
OS 32.07845756 39.86423828
OS 32.0821558 39.86793652
OS 32.08400492 39.86886108
OS 32.09509964 39.88180492
OS 32.10434524 39.89567332
OS 32.11174172 39.91139084
OS 32.11728908 39.92525924
OS 32.12098732 39.93912764
OS 32.123761 39.9492978
OS 32.12468556 39.9539206
OS 32.12561012 39.95669428
OS 32.12561012 39.9585434
OS 32.12561012 39.95946796
OS 32.20789596 39.95299604
OS 32.20604684 39.93820308
OS 32.20327316 39.92433468
OS 32.19495212 39.898447
OS 32.18478196 39.87625756
OS 32.1792346 39.8660874
OS 32.17368724 39.85776636
OS 32.16906444 39.84944532
OS 32.16351708 39.84204884
OS 32.15889428 39.83650148
OS 32.15427148 39.83187868
OS 32.15057324 39.82818044
OS 32.14872412 39.8244822
OS 32.146875 39.82355764
OS 32.14595044 39.82263308
OS 32.13485572 39.81431204
OS 32.123761 39.80691556
OS 32.11174172 39.80044364
OS 32.09972244 39.79489628
OS 32.07660844 39.78657524
OS 32.05349444 39.78102788
OS 32.04332428 39.7782542
OS 32.03315412 39.77732964
OS 32.02483308 39.77640508
OS 32.0174366 39.77548052
OS 32.01096468 39.77455596
OS 32.00264364 39.77455596
OS 31.98322788 39.77548052
OS 31.96473668 39.7782542
OS 31.94717004 39.78195244
OS 31.93145252 39.78657524
OS 31.91665956 39.79304716
OS 31.90279116 39.79951908
OS 31.88984732 39.805991
OS 31.8787526 39.81338748
OS 31.86858244 39.82078396
OS 31.85933684 39.82725588
OS 31.85194036 39.83465236
OS 31.84546844 39.84019972
OS 31.84084564 39.84482252
OS 31.8371474 39.84852076
OS 31.83529828 39.85129444
OS 31.83437372 39.852219
OS 31.82512812 39.86423828
OS 31.81773164 39.87718212
OS 31.81033516 39.8892014
OS 31.8047878 39.90214524
OS 31.7955422 39.92710836
OS 31.78999484 39.95114692
OS 31.78814572 39.96131708
OS 31.7862966 39.97148724
OS 31.78537204 39.97980828
OS 31.78444748 39.98720476
OS 31.78352292 39.99367668
OS 31.78352292 39.99829948
OS 31.78352292 40.00107316
OS 31.78352292 40.00199772
OS 31.78444748 40.0186398
OS 31.7862966 40.03435732
OS 31.78907028 40.05007484
OS 31.79276852 40.06394324
OS 31.79739132 40.07688708
OS 31.80201412 40.08983092
OS 31.80756148 40.10092564
OS 31.81218428 40.1110958
OS 31.81773164 40.1203414
OS 31.823279 40.12866244
OS 31.8279018 40.13513436
OS 31.8325246 40.14160628
OS 31.83622284 40.14622908
OS 31.83899652 40.14900276
OS 31.84084564 40.15085188
OS 31.8417702 40.15177644
OS 31.85286492 40.1619466
OS 31.86395964 40.1711922
OS 31.87597892 40.17858868
OS 31.8879982 40.1850606
OS 31.90001748 40.19153252
OS 31.91203676 40.19615532
OS 31.9342262 40.20262724
OS 31.94439636 40.20540092
OS 31.95364196 40.20725004
OS 31.961963 40.2081746
OS 31.96935948 40.20909916
OS 31.97490684 40.21002372
OS 31.99524716 40.21002372
OS 32.00634188 40.2081746
OS 32.02853132 40.2035518
OS 32.04887164 40.19707988
OS 32.06736284 40.1896834
OS 32.0821558 40.18228692
OS 32.08862772 40.17858868
OS 32.09417508 40.175815
OS 32.09879788 40.17304132
OS 32.10157156 40.1711922
OS 32.10342068 40.17026764
OS 32.10434524 40.16934308
OS 32.07013652 40.3422358
OS 31.8140334 40.3422358
OE
SE
S P 0
OB 33.95172534 9.95313478 I
OS 33.95912182 9.95405934
OS 34.25590558 9.95405934
OS 34.25590558 9.31426382
OS 34.17084606 9.31426382
OS 34.17084606 9.59810374
OS 34.06174798 9.59810374
OS 34.05157782 9.59717918
OS 34.04418134 9.59717918
OS 34.03770942 9.59625462
OS 34.03308662 9.59533006
OS 34.02938838 9.59533006
OS 34.02753926 9.5944055
OS 34.0266147 9.5944055
OS 34.01182174 9.5897827
OS 34.00534982 9.58700902
OS 33.99980246 9.58423534
OS 33.9942551 9.58146166
OS 33.99055686 9.57961254
OS 33.98870774 9.57868798
OS 33.98778318 9.57776342
OS 33.9803867 9.57221606
OS 33.97299022 9.56574414
OS 33.95912182 9.55187574
OS 33.9526499 9.54540382
OS 33.9480271 9.53985646
OS 33.94525342 9.53615822
OS 33.94432886 9.53523366
OS 33.93508326 9.52228982
OS 33.9249131 9.50842142
OS 33.91474294 9.49362846
OS 33.90457278 9.47976006
OS 33.89625174 9.46681622
OS 33.88977982 9.45664606
OS 33.88700614 9.45294782
OS 33.88515702 9.45017414
OS 33.8833079 9.44832502
OS 33.8833079 9.44740046
OS 33.79917294 9.31426382
OS 33.6937731 9.31426382
OS 33.80379574 9.4880811
OS 33.81673958 9.5065723
OS 33.82875886 9.52321438
OS 33.84077814 9.53708278
OS 33.8509483 9.55002662
OS 33.8601939 9.55927222
OS 33.86759038 9.5666687
OS 33.87221318 9.5712915
OS 33.8740623 9.57314062
OS 33.88145878 9.57868798
OS 33.88977982 9.5851599
OS 33.9064219 9.59533006
OS 33.91381838 9.5990283
OS 33.91936574 9.60272654
OS 33.92306398 9.60457566
OS 33.9249131 9.60550022
OS 33.90827102 9.6082739
OS 33.8925535 9.61104758
OS 33.8786851 9.61567038
OS 33.8648167 9.61936862
OS 33.85279742 9.62399142
OS 33.8417027 9.62953878
OS 33.83153254 9.63416158
OS 33.82228694 9.63878438
OS 33.81489046 9.64433174
OS 33.80749398 9.64895454
OS 33.80194662 9.65265278
OS 33.79732382 9.65635102
OS 33.79362558 9.6591247
OS 33.7908519 9.66189838
OS 33.78992734 9.66282294
OS 33.78900278 9.6637475
OS 33.7816063 9.6729931
OS 33.77420982 9.6822387
OS 33.7631151 9.70165446
OS 33.75571862 9.72107022
OS 33.75017126 9.73956142
OS 33.74647302 9.75527894
OS 33.74554846 9.76175086
OS 33.74554846 9.76822278
OS 33.7446239 9.77284558
OS 33.7446239 9.77654382
OS 33.7446239 9.77839294
OS 33.7446239 9.7793175
OS 33.74554846 9.79873326
OS 33.74832214 9.8162999
OS 33.75294494 9.83294198
OS 33.75756774 9.84681038
OS 33.7631151 9.85882966
OS 33.76681334 9.86807526
OS 33.77051158 9.87362262
OS 33.77143614 9.87454718
OS 33.77143614 9.87547174
OS 33.78253086 9.8902647
OS 33.79362558 9.90320854
OS 33.80564486 9.91430326
OS 33.81673958 9.9226243
OS 33.82690974 9.92909622
OS 33.83523078 9.93279446
OS 33.84077814 9.93556814
OS 33.8417027 9.9364927
OS 33.84262726 9.9364927
OS 33.8509483 9.93926638
OS 33.86111846 9.94204006
OS 33.88145878 9.94666286
OS 33.90364822 9.94943654
OS 33.92398854 9.95221022
OS 33.9434043 9.95313478
OS 33.95172534 9.95313478
OE
OB 33.42380158 9.95590846 I
OS 33.43397174 9.95683302
OS 33.45708574 9.95683302
OS 33.47002958 9.9549839
OS 33.4949927 9.9503611
OS 33.51625758 9.94296462
OS 33.53474878 9.93556814
OS 33.54306982 9.93094534
OS 33.54954174 9.9272471
OS 33.55601366 9.92354886
OS 33.56063646 9.91985062
OS 33.5643347 9.91707694
OS 33.56710838 9.91522782
OS 33.5689575 9.91430326
OS 33.56988206 9.9133787
OS 33.5874487 9.89581206
OS 33.6013171 9.8763963
OS 33.61241182 9.85605598
OS 33.62165742 9.83571566
OS 33.62720478 9.81814902
OS 33.62997846 9.81075254
OS 33.63182758 9.80428062
OS 33.63275214 9.79873326
OS 33.6336767 9.79503502
OS 33.63460126 9.79226134
OS 33.63460126 9.79133678
OS 33.55601366 9.77746838
OS 33.55231542 9.7978087
OS 33.54676806 9.81537534
OS 33.54029614 9.8301683
OS 33.53382422 9.84218758
OS 33.5273523 9.85143318
OS 33.52180494 9.8579051
OS 33.5181067 9.8625279
OS 33.51718214 9.86345246
OS 33.50516286 9.87269806
OS 33.49221902 9.88009454
OS 33.48019974 9.88471734
OS 33.46818046 9.88841558
OS 33.45708574 9.8902647
OS 33.4487647 9.89211382
OS 33.44136822 9.89211382
OS 33.42472614 9.89118926
OS 33.40993318 9.88749102
OS 33.39698934 9.88286822
OS 33.38589462 9.87824542
OS 33.37757358 9.87269806
OS 33.37110166 9.86807526
OS 33.36647886 9.86437702
OS 33.3655543 9.86345246
OS 33.35538414 9.85235774
OS 33.34798766 9.84033846
OS 33.34336486 9.82831918
OS 33.33966662 9.81722446
OS 33.3378175 9.8070543
OS 33.33596838 9.79965782
OS 33.33596838 9.79411046
OS 33.33596838 9.7931859
OS 33.33596838 9.79226134
OS 33.33596838 9.78209118
OS 33.3378175 9.77284558
OS 33.3424403 9.75712806
OS 33.34891222 9.74325966
OS 33.3563087 9.73124038
OS 33.36370518 9.72291934
OS 33.3701771 9.71644742
OS 33.3747999 9.71274918
OS 33.37572446 9.71182462
OS 33.37664902 9.71182462
OS 33.39236654 9.70350358
OS 33.4071595 9.69703166
OS 33.42287702 9.69240886
OS 33.43674542 9.68963518
OS 33.4487647 9.68778606
OS 33.45893486 9.68593694
OS 33.47095414 9.68593694
OS 33.47465238 9.6868615
OS 33.47927518 9.6868615
OS 33.48852078 9.6175195
OS 33.4765015 9.62029318
OS 33.46540678 9.6221423
OS 33.45616118 9.62399142
OS 33.44784014 9.62491598
OS 33.44136822 9.62584054
OS 33.43304718 9.62584054
OS 33.41363142 9.62399142
OS 33.39606478 9.62029318
OS 33.38034726 9.61474582
OS 33.36740342 9.6082739
OS 33.35723326 9.60180198
OS 33.34983678 9.59625462
OS 33.34521398 9.59255638
OS 33.34336486 9.59070726
OS 33.33134558 9.57683886
OS 33.32209998 9.5620459
OS 33.31562806 9.54725294
OS 33.31192982 9.53245998
OS 33.30915614 9.5204407
OS 33.30823158 9.51027054
OS 33.30730702 9.5065723
OS 33.30730702 9.50379862
OS 33.30730702 9.5019495
OS 33.30730702 9.50102494
OS 33.30915614 9.48068462
OS 33.31377894 9.46219342
OS 33.3193263 9.4464759
OS 33.32672278 9.4326075
OS 33.33411926 9.42151278
OS 33.33966662 9.41319174
OS 33.34428942 9.40764438
OS 33.34613854 9.40579526
OS 33.3609315 9.39285142
OS 33.37664902 9.38360582
OS 33.39236654 9.3771339
OS 33.4071595 9.3725111
OS 33.42010334 9.36973742
OS 33.4302735 9.36881286
OS 33.43397174 9.3678883
OS 33.4395191 9.3678883
OS 33.45616118 9.36881286
OS 33.4718787 9.3725111
OS 33.4857471 9.3771339
OS 33.49684182 9.38268126
OS 33.50608742 9.38730406
OS 33.5134839 9.39192686
OS 33.51718214 9.3956251
OS 33.51903126 9.39654966
OS 33.53012598 9.4094935
OS 33.53937158 9.42428646
OS 33.54769262 9.44000398
OS 33.55416454 9.45664606
OS 33.55878734 9.47051446
OS 33.56063646 9.47698638
OS 33.56156102 9.48253374
OS 33.56248558 9.48715654
OS 33.56341014 9.49085478
OS 33.5643347 9.4927039
OS 33.5643347 9.49362846
OS 33.6429223 9.4834583
OS 33.64107318 9.46866534
OS 33.6382995 9.45479694
OS 33.62997846 9.42890926
OS 33.6198083 9.40671982
OS 33.61426094 9.39747422
OS 33.60871358 9.38822862
OS 33.60316622 9.37990758
OS 33.59761886 9.37343566
OS 33.59299606 9.36696374
OS 33.58837326 9.36234094
OS 33.58559958 9.3586427
OS 33.5828259 9.35586902
OS 33.58097678 9.3540199
OS 33.58005222 9.35309534
OS 33.5689575 9.3447743
OS 33.55786278 9.33645326
OS 33.54676806 9.32998134
OS 33.53474878 9.32443398
OS 33.51163478 9.31518838
OS 33.48944534 9.30964102
OS 33.47927518 9.3077919
OS 33.47002958 9.30594278
OS 33.46170854 9.30501822
OS 33.45431206 9.30409366
OS 33.4487647 9.3031691
OS 33.44044366 9.3031691
OS 33.42287702 9.30409366
OS 33.4071595 9.30594278
OS 33.39144198 9.30871646
OS 33.37664902 9.3124147
OS 33.36278062 9.3170375
OS 33.35076134 9.3216603
OS 33.33874206 9.32720766
OS 33.3285719 9.33275502
OS 33.31840174 9.33737782
OS 33.3100807 9.34292518
OS 33.30268422 9.34754798
OS 33.29713686 9.35217078
OS 33.29251406 9.35586902
OS 33.28881582 9.3586427
OS 33.2869667 9.36049182
OS 33.28604214 9.36141638
OS 33.27494742 9.3725111
OS 33.26570182 9.38453038
OS 33.25738078 9.39654966
OS 33.2499843 9.40856894
OS 33.24443694 9.41966366
OS 33.23888958 9.43168294
OS 33.2314931 9.45387238
OS 33.22964398 9.46404254
OS 33.22779486 9.47328814
OS 33.22594574 9.48160918
OS 33.22502118 9.48900566
OS 33.22409662 9.49455302
OS 33.22409662 9.49917582
OS 33.22409662 9.5019495
OS 33.22409662 9.50287406
OS 33.22502118 9.5250635
OS 33.22871942 9.54540382
OS 33.23426678 9.56297046
OS 33.23981414 9.57776342
OS 33.2453615 9.5897827
OS 33.25090886 9.5990283
OS 33.2546071 9.60457566
OS 33.25553166 9.60642478
OS 33.2684755 9.62029318
OS 33.2823439 9.63231246
OS 33.29713686 9.64155806
OS 33.31192982 9.64895454
OS 33.32487366 9.6545019
OS 33.33504382 9.65820014
OS 33.33874206 9.6591247
OS 33.34151574 9.66004926
OS 33.34336486 9.66097382
OS 33.34428942 9.66097382
OS 33.3285719 9.66929486
OS 33.31562806 9.6776159
OS 33.30453334 9.6868615
OS 33.29528774 9.69518254
OS 33.28789126 9.70257902
OS 33.2823439 9.70905094
OS 33.27957022 9.71274918
OS 33.27864566 9.7145983
OS 33.27124918 9.72754214
OS 33.26570182 9.74048598
OS 33.26107902 9.75342982
OS 33.25830534 9.7654491
OS 33.25645622 9.77561926
OS 33.25553166 9.78301574
OS 33.25553166 9.7885631
OS 33.25553166 9.79041222
OS 33.25645622 9.80612974
OS 33.2592299 9.82184726
OS 33.26292814 9.83571566
OS 33.26755094 9.84773494
OS 33.27217374 9.8579051
OS 33.27587198 9.86622614
OS 33.27864566 9.87084894
OS 33.27957022 9.87269806
OS 33.28881582 9.88656646
OS 33.29991054 9.89858574
OS 33.31100526 9.9087559
OS 33.32209998 9.9180015
OS 33.33134558 9.92447342
OS 33.33966662 9.93002078
OS 33.34521398 9.93279446
OS 33.34613854 9.93371902
OS 33.3470631 9.93371902
OS 33.36370518 9.9411155
OS 33.38034726 9.94666286
OS 33.39698934 9.95128566
OS 33.4117823 9.95405934
OS 33.42380158 9.95590846
OE
OB 33.96929198 9.88286822 H
OS 33.94432886 9.88194366
OS 33.92306398 9.87824542
OS 33.90457278 9.87362262
OS 33.89070438 9.86807526
OS 33.8786851 9.8625279
OS 33.87128862 9.8579051
OS 33.86666582 9.85420686
OS 33.8648167 9.8532823
OS 33.85372198 9.84126302
OS 33.84540094 9.82924374
OS 33.83985358 9.8162999
OS 33.83523078 9.80520518
OS 33.83338166 9.79411046
OS 33.8324571 9.78578942
OS 33.83153254 9.78024206
OS 33.83153254 9.7793175
OS 33.83153254 9.77839294
OS 33.8324571 9.76729822
OS 33.83430622 9.7562035
OS 33.8370799 9.7469579
OS 33.83985358 9.73863686
OS 33.84355182 9.73124038
OS 33.8463255 9.72569302
OS 33.84817462 9.72199478
OS 33.84909918 9.72107022
OS 33.8555711 9.71182462
OS 33.86389214 9.70350358
OS 33.87221318 9.69703166
OS 33.88053422 9.6914843
OS 33.8879307 9.68778606
OS 33.89347806 9.68501238
OS 33.8971763 9.68316326
OS 33.89902542 9.6822387
OS 33.91196926 9.67854046
OS 33.92676222 9.67576678
OS 33.94155518 9.67391766
OS 33.95634814 9.6729931
OS 33.96929198 9.67206854
OS 33.9803867 9.67114398
OS 34.17084606 9.67114398
OS 34.17084606 9.88286822
OS 33.96929198 9.88286822
OE
SE
S P 0
OB 35.58552192 3.1640526 I
OS 35.58552192 3.60044492
OS 35.67058144 3.60044492
OS 35.67058144 3.1594298
OS 35.67058144 3.14001404
OS 35.67243056 3.12337196
OS 35.67335512 3.10950356
OS 35.67520424 3.09840884
OS 35.67705336 3.0900878
OS 35.67797792 3.08361588
OS 35.67982704 3.07991764
OS 35.67982704 3.07899308
OS 35.68352528 3.06974748
OS 35.68814808 3.062351
OS 35.69369544 3.05587908
OS 35.69831824 3.04940716
OS 35.7038656 3.04570892
OS 35.70756384 3.04201068
OS 35.71033752 3.04016156
OS 35.71126208 3.039237
OS 35.72050768 3.0346142
OS 35.72975328 3.03091596
OS 35.73899888 3.02906684
OS 35.74731992 3.02721772
OS 35.75564096 3.02629316
OS 35.76118832 3.0253686
OS 35.76673568 3.0253686
OS 35.78152864 3.02629316
OS 35.79539704 3.0299914
OS 35.80649176 3.03368964
OS 35.81666192 3.039237
OS 35.8240584 3.0438598
OS 35.82960576 3.0484826
OS 35.833304 3.05125628
OS 35.83422856 3.05218084
OS 35.83885136 3.0577282
OS 35.8425496 3.06420012
OS 35.84809696 3.07899308
OS 35.85364432 3.09563516
OS 35.856418 3.11227724
OS 35.85919168 3.12799476
OS 35.85919168 3.13446668
OS 35.86011624 3.14001404
OS 35.8610408 3.1455614
OS 35.8610408 3.14925964
OS 35.8610408 3.15110876
OS 35.8610408 3.15203332
OS 35.93777928 3.1409386
OS 35.93777928 3.12337196
OS 35.93685472 3.10765444
OS 35.93408104 3.09193692
OS 35.93223192 3.07806852
OS 35.92853368 3.06512468
OS 35.92483544 3.05402996
OS 35.9211372 3.04293524
OS 35.91743896 3.03368964
OS 35.91281616 3.0253686
OS 35.90911792 3.01797212
OS 35.90541968 3.0115002
OS 35.90172144 3.0068774
OS 35.89894776 3.00317916
OS 35.89709864 2.99948092
OS 35.89617408 2.99855636
OS 35.89524952 2.9976318
OS 35.88600392 2.98931076
OS 35.87675832 2.98191428
OS 35.86658816 2.97544236
OS 35.85549344 2.969895
OS 35.83422856 2.96157396
OS 35.81388824 2.9560266
OS 35.79447248 2.95232836
OS 35.787076 2.9514038
OS 35.77967952 2.95047924
OS 35.77413216 2.94955468
OS 35.76581112 2.94955468
OS 35.7454708 2.95047924
OS 35.7269796 2.95325292
OS 35.71033752 2.95695116
OS 35.69554456 2.96157396
OS 35.68352528 2.9652722
OS 35.67520424 2.96897044
OS 35.66965688 2.97174412
OS 35.66780776 2.97266868
OS 35.6530148 2.98191428
OS 35.64007096 2.993009
OS 35.6299008 3.00410372
OS 35.6206552 3.01427388
OS 35.61418328 3.02444404
OS 35.60956048 3.03184052
OS 35.6067868 3.03738788
OS 35.60586224 3.03831244
OS 35.60586224 3.039237
OS 35.59939032 3.0577282
OS 35.59384296 3.07714396
OS 35.59014472 3.09840884
OS 35.5882956 3.11874916
OS 35.58644648 3.1363158
OS 35.58644648 3.14371228
OS 35.58552192 3.15110876
OS 35.58552192 3.15665612
OS 35.58552192 3.16035436
OS 35.58552192 3.16312804
OS 35.58552192 3.1640526
OE
OB 35.1491296 3.18624204 I
OS 35.1491296 3.60044492
OS 35.21292424 3.60044492
OS 35.50600976 3.18624204
OS 35.50600976 3.11412636
OS 35.2277172 3.11412636
OS 35.2277172 2.9606494
OS 35.1491296 2.9606494
OS 35.1491296 3.11412636
OS 35.06222096 3.11412636
OS 35.06222096 3.18624204
OS 35.1491296 3.18624204
OE
OB 35.2277172 3.47285564 H
OS 35.2277172 3.18624204
OS 35.42927128 3.18624204
OS 35.2277172 3.47285564
OE
SE
S P 0
OB 40.23977982 10.27006836 I
OS 40.24625174 10.27099292
OS 40.25549734 10.27099292
OS 40.28600782 10.2691438
OS 40.31559374 10.264521
OS 40.34148142 10.25897364
OS 40.3535007 10.2552754
OS 40.36459542 10.25157716
OS 40.37476558 10.24787892
OS 40.38401118 10.24418068
OS 40.39140766 10.241407
OS 40.39880414 10.23863332
OS 40.40342694 10.23585964
OS 40.40712518 10.23401052
OS 40.40989886 10.23308596
OS 40.41082342 10.2321614
OS 40.43578654 10.21644388
OS 40.45705142 10.19795268
OS 40.47554262 10.17946148
OS 40.49126014 10.16097028
OS 40.50327942 10.1443282
OS 40.50790222 10.13693172
OS 40.51160046 10.1304598
OS 40.5152987 10.125837
OS 40.51714782 10.12213876
OS 40.51807238 10.11936508
OS 40.51899694 10.11844052
OS 40.53194078 10.08977916
OS 40.54118638 10.06019324
OS 40.5476583 10.03060732
OS 40.5522811 10.00379508
OS 40.55413022 9.9917758
OS 40.55505478 9.97975652
OS 40.55597934 9.97051092
OS 40.55597934 9.96126532
OS 40.5569039 9.9547934
OS 40.5569039 9.94924604
OS 40.5569039 9.9455478
OS 40.5569039 9.94462324
OS 40.55505478 9.91133908
OS 40.55135654 9.87897948
OS 40.54673374 9.85031812
OS 40.5430355 9.83644972
OS 40.54026182 9.82443044
OS 40.53748814 9.81333572
OS 40.5337899 9.80316556
OS 40.53101622 9.79391996
OS 40.5291671 9.78652348
OS 40.52639342 9.78097612
OS 40.52546886 9.77635332
OS 40.52361974 9.77357964
OS 40.52361974 9.77265508
OS 40.50975134 9.74491828
OS 40.49403382 9.71995516
OS 40.47739174 9.69869028
OS 40.4690707 9.69036924
OS 40.46167422 9.6820482
OS 40.45427774 9.67465172
OS 40.44688126 9.6681798
OS 40.44040934 9.66263244
OS 40.43486198 9.6589342
OS 40.43116374 9.65523596
OS 40.4274655 9.65246228
OS 40.42561638 9.65153772
OS 40.42469182 9.65061316
OS 40.41174798 9.64321668
OS 40.39880414 9.63674476
OS 40.37106734 9.6265746
OS 40.34333054 9.61917812
OS 40.3165183 9.61455532
OS 40.30357446 9.6127062
OS 40.29247974 9.61085708
OS 40.28230958 9.60993252
OS 40.27398854 9.60993252
OS 40.26659206 9.60900796
OS 40.2564219 9.60900796
OS 40.2379307 9.60993252
OS 40.22036406 9.61178164
OS 40.20372198 9.61363076
OS 40.18800446 9.617329
OS 40.1732115 9.6219518
OS 40.1593431 9.6265746
OS 40.14639926 9.6311974
OS 40.13437998 9.63674476
OS 40.12420982 9.64136756
OS 40.11403966 9.64599036
OS 40.10664318 9.65061316
OS 40.0992467 9.65523596
OS 40.0946239 9.6589342
OS 40.0900011 9.66078332
OS 40.08815198 9.66263244
OS 40.08722742 9.663557
OS 40.07428358 9.67465172
OS 40.06318886 9.68574644
OS 40.0530187 9.69869028
OS 40.04284854 9.71163412
OS 40.02620646 9.7375218
OS 40.01326262 9.76340948
OS 40.00771526 9.77542876
OS 40.00309246 9.78652348
OS 39.99939422 9.79669364
OS 39.99662054 9.80501468
OS 39.99384686 9.81241116
OS 39.99199774 9.81795852
OS 39.99107318 9.82165676
OS 39.99107318 9.82258132
OS 40.0761327 9.8438462
OS 40.07983094 9.82905324
OS 40.08445374 9.81518484
OS 40.08907654 9.802241
OS 40.09369934 9.79022172
OS 40.0992467 9.779127
OS 40.10479406 9.7698814
OS 40.11126598 9.7606358
OS 40.11681334 9.75231476
OS 40.12143614 9.74491828
OS 40.1269835 9.73937092
OS 40.1316063 9.73382356
OS 40.13530454 9.72920076
OS 40.13900278 9.72642708
OS 40.14177646 9.7236534
OS 40.14270102 9.72272884
OS 40.14362558 9.72180428
OS 40.15287118 9.7144078
OS 40.16304134 9.70886044
OS 40.18338166 9.69869028
OS 40.20279742 9.6912938
OS 40.22221318 9.686671
OS 40.23885526 9.68297276
OS 40.24532718 9.6820482
OS 40.2517991 9.6820482
OS 40.25734646 9.68112364
OS 40.26381838 9.68112364
OS 40.28508326 9.6820482
OS 40.30542358 9.68574644
OS 40.32391478 9.69036924
OS 40.34055686 9.6959166
OS 40.3535007 9.70146396
OS 40.35904806 9.70423764
OS 40.36367086 9.70608676
OS 40.3673691 9.70793588
OS 40.37014278 9.709785
OS 40.3719919 9.71070956
OS 40.37291646 9.71070956
OS 40.3904831 9.7236534
OS 40.40527606 9.7375218
OS 40.4182199 9.75323932
OS 40.42839006 9.76803228
OS 40.4367111 9.78097612
OS 40.44225846 9.79207084
OS 40.44410758 9.79669364
OS 40.4459567 9.79946732
OS 40.44688126 9.80131644
OS 40.44688126 9.802241
OS 40.45427774 9.82627956
OS 40.4598251 9.85031812
OS 40.4644479 9.87435668
OS 40.46722158 9.89654612
OS 40.46814614 9.90671628
OS 40.4690707 9.91596188
OS 40.4690707 9.92428292
OS 40.46999526 9.93075484
OS 40.46999526 9.9363022
OS 40.46999526 9.940925
OS 40.46999526 9.94369868
OS 40.46999526 9.94462324
OS 40.4690707 9.9686618
OS 40.46722158 9.99085124
OS 40.46352334 10.01119156
OS 40.4598251 10.02968276
OS 40.45705142 10.04540028
OS 40.4552023 10.0518722
OS 40.45335318 10.05741956
OS 40.45242862 10.06204236
OS 40.45150406 10.06481604
OS 40.4505795 10.06666516
OS 40.4505795 10.06758972
OS 40.4413339 10.0888546
OS 40.43116374 10.10827036
OS 40.42006902 10.12398788
OS 40.40804974 10.13785628
OS 40.39787958 10.148951
OS 40.38955854 10.15634748
OS 40.38308662 10.16097028
OS 40.38216206 10.1628194
OS 40.3812375 10.1628194
OS 40.36182174 10.17483868
OS 40.34055686 10.18408428
OS 40.32021654 10.1905562
OS 40.30080078 10.19425444
OS 40.28323414 10.19702812
OS 40.27583766 10.19795268
OS 40.26936574 10.19795268
OS 40.26474294 10.19887724
OS 40.25734646 10.19887724
OS 40.23423246 10.19795268
OS 40.21296758 10.19425444
OS 40.19540094 10.18870708
OS 40.17968342 10.18315972
OS 40.16766414 10.1766878
OS 40.15841854 10.172065
OS 40.15287118 10.16836676
OS 40.15102206 10.16651764
OS 40.1362291 10.15264924
OS 40.1223607 10.13693172
OS 40.11126598 10.12028964
OS 40.10202038 10.10364756
OS 40.0946239 10.0888546
OS 40.09185022 10.08145812
OS 40.0900011 10.07591076
OS 40.08815198 10.07128796
OS 40.08630286 10.06758972
OS 40.0853783 10.0657406
OS 40.0853783 10.06481604
OS 40.0021679 10.0842318
OS 40.00771526 10.10087388
OS 40.01326262 10.11566684
OS 40.0206591 10.12953524
OS 40.02713102 10.14340364
OS 40.0345275 10.15542292
OS 40.04284854 10.16651764
OS 40.05024502 10.17761236
OS 40.0576415 10.18685796
OS 40.06503798 10.19425444
OS 40.0715099 10.20165092
OS 40.07798182 10.20812284
OS 40.08260462 10.21274564
OS 40.08722742 10.21736844
OS 40.09092566 10.22014212
OS 40.09277478 10.22106668
OS 40.09369934 10.22199124
OS 40.10664318 10.23031228
OS 40.11958702 10.23863332
OS 40.13253086 10.24510524
OS 40.14639926 10.2506526
OS 40.17413606 10.25897364
OS 40.19909918 10.264521
OS 40.21111846 10.26729468
OS 40.22128862 10.26821924
OS 40.23145878 10.2691438
OS 40.23977982 10.27006836
OE
OB 39.6230983 9.62010268 I
OS 39.6230983 10.26267188
OS 39.6739491 10.26267188
OS 39.6831947 10.24695436
OS 39.69336486 10.2321614
OS 39.70538414 10.21736844
OS 39.71647886 10.2044246
OS 39.72757358 10.19332988
OS 39.73589462 10.18408428
OS 39.73959286 10.1813106
OS 39.74236654 10.17853692
OS 39.7432911 10.17761236
OS 39.74421566 10.1766878
OS 39.76363142 10.16097028
OS 39.78304718 10.14617732
OS 39.80153838 10.13323348
OS 39.82002958 10.12306332
OS 39.8357471 10.11381772
OS 39.84221902 10.11011948
OS 39.84776638 10.1073458
OS 39.85238918 10.10457212
OS 39.85608742 10.10364756
OS 39.85793654 10.10179844
OS 39.8588611 10.10179844
OS 39.8588611 10.02598452
OS 39.8449927 10.03153188
OS 39.8311243 10.0380038
OS 39.8172559 10.04447572
OS 39.80431206 10.05094764
OS 39.79321734 10.056495
OS 39.78397174 10.0611178
OS 39.77842438 10.06481604
OS 39.77749982 10.0657406
OS 39.77657526 10.0657406
OS 39.75993318 10.07591076
OS 39.74514022 10.08608092
OS 39.73219638 10.09532652
OS 39.72202622 10.10364756
OS 39.71278062 10.11011948
OS 39.70723326 10.11566684
OS 39.70261046 10.11936508
OS 39.7016859 10.12028964
OS 39.7016859 9.62010268
OS 39.6230983 9.62010268
OE
SE
S P 0
OB 40.83347688 2.15758522 I
OS 40.84734528 2.15850978
OS 41.10992032 2.15850978
OS 41.10992032 1.51871426
OS 41.0248608 1.51871426
OS 41.0248608 1.77851562
OS 40.86121368 1.77851562
OS 40.83717512 1.77944018
OS 40.81406112 1.7812893
OS 40.7937208 1.78406298
OS 40.7752296 1.78776122
OS 40.75766296 1.79145946
OS 40.74287 1.79608226
OS 40.7290016 1.80162962
OS 40.71698232 1.80717698
OS 40.70681216 1.81179978
OS 40.69756656 1.81734714
OS 40.69017008 1.82196994
OS 40.68462272 1.82659274
OS 40.67999992 1.82936642
OS 40.67722624 1.8321401
OS 40.67537712 1.83398922
OS 40.67445256 1.83491378
OS 40.66520696 1.8460085
OS 40.65688592 1.85710322
OS 40.650414 1.86819794
OS 40.64394208 1.88021722
OS 40.63839472 1.8922365
OS 40.63469648 1.90333122
OS 40.62822456 1.9245961
OS 40.62637544 1.93476626
OS 40.62452632 1.94401186
OS 40.62360176 1.9523329
OS 40.6226772 1.95880482
OS 40.62175264 1.96527674
OS 40.62175264 1.96897498
OS 40.62175264 1.97174866
OS 40.62175264 1.97267322
OS 40.6226772 1.99023986
OS 40.62452632 2.00688194
OS 40.62822456 2.0216749
OS 40.63099824 2.03461874
OS 40.63469648 2.04571346
OS 40.63839472 2.0540345
OS 40.64024384 2.0586573
OS 40.6411684 2.06050642
OS 40.64856488 2.07437482
OS 40.65781048 2.0863941
OS 40.66613152 2.09748882
OS 40.67445256 2.10580986
OS 40.68184904 2.11228178
OS 40.6873964 2.11782914
OS 40.69109464 2.12060282
OS 40.69294376 2.12152738
OS 40.70496304 2.12892386
OS 40.71883144 2.13539578
OS 40.73177528 2.14094314
OS 40.74379456 2.14556594
OS 40.75488928 2.14833962
OS 40.76321032 2.15018874
OS 40.76968224 2.15203786
OS 40.77153136 2.15203786
OS 40.78539976 2.15388698
OS 40.80111728 2.1557361
OS 40.81775936 2.15666066
OS 40.83347688 2.15758522
OE
OB 40.25007952 1.51871426 I
OS 40.25007952 2.16128346
OS 40.30093032 2.16128346
OS 40.31017592 2.14556594
OS 40.32034608 2.13077298
OS 40.33236536 2.11598002
OS 40.34346008 2.10303618
OS 40.3545548 2.09194146
OS 40.36287584 2.08269586
OS 40.36657408 2.07992218
OS 40.36934776 2.0771485
OS 40.37027232 2.07622394
OS 40.37119688 2.07529938
OS 40.39061264 2.05958186
OS 40.4100284 2.0447889
OS 40.4285196 2.03184506
OS 40.4470108 2.0216749
OS 40.46272832 2.0124293
OS 40.46920024 2.00873106
OS 40.4747476 2.00595738
OS 40.4793704 2.0031837
OS 40.48306864 2.00225914
OS 40.48491776 2.00041002
OS 40.48584232 2.00041002
OS 40.48584232 1.9245961
OS 40.47197392 1.93014346
OS 40.45810552 1.93661538
OS 40.44423712 1.9430873
OS 40.43129328 1.94955922
OS 40.42019856 1.95510658
OS 40.41095296 1.95972938
OS 40.4054056 1.96342762
OS 40.40448104 1.96435218
OS 40.40355648 1.96435218
OS 40.3869144 1.97452234
OS 40.37212144 1.9846925
OS 40.3591776 1.9939381
OS 40.34900744 2.00225914
OS 40.33976184 2.00873106
OS 40.33421448 2.01427842
OS 40.32959168 2.01797666
OS 40.32866712 2.01890122
OS 40.32866712 1.51871426
OS 40.25007952 1.51871426
OE
OB 40.84179792 2.08269586 H
OS 40.82515584 2.0817713
OS 40.81128744 2.08084674
OS 40.80019272 2.07992218
OS 40.79279624 2.07807306
OS 40.78724888 2.0771485
OS 40.78355064 2.07622394
OS 40.78262608 2.07622394
OS 40.7706068 2.07160114
OS 40.76043664 2.06605378
OS 40.75119104 2.06050642
OS 40.74287 2.0540345
OS 40.73732264 2.04756258
OS 40.73269984 2.04293978
OS 40.72992616 2.03924154
OS 40.7290016 2.03831698
OS 40.72252968 2.02722226
OS 40.71698232 2.01612754
OS 40.71328408 2.00410826
OS 40.71143496 1.9939381
OS 40.70958584 1.9846925
OS 40.70866128 1.97637146
OS 40.70866128 1.97174866
OS 40.70866128 1.9708241
OS 40.70866128 1.96989954
OS 40.7105104 1.95048378
OS 40.71420864 1.9338417
OS 40.719756 1.91904874
OS 40.72622792 1.90702946
OS 40.73269984 1.89778386
OS 40.7382472 1.89038738
OS 40.74194544 1.88668914
OS 40.74379456 1.88484002
OS 40.75026648 1.87929266
OS 40.75858752 1.87466986
OS 40.77615416 1.86727338
OS 40.79556992 1.86172602
OS 40.81498568 1.85802778
OS 40.83255232 1.85617866
OS 40.8399488 1.8552541
OS 40.84642072 1.8552541
OS 40.85289264 1.85432954
OS 41.0248608 1.85432954
OS 41.0248608 2.08269586
OS 40.84179792 2.08269586
OE
SE
S P 0
OB 40.89218644 22.64533444 I
OS 40.90605484 22.646259
OS 41.16862988 22.646259
OS 41.16862988 22.00646348
OS 41.08357036 22.00646348
OS 41.08357036 22.26626484
OS 40.91992324 22.26626484
OS 40.89588468 22.2671894
OS 40.87277068 22.26903852
OS 40.85243036 22.2718122
OS 40.83393916 22.27551044
OS 40.81637252 22.27920868
OS 40.80157956 22.28383148
OS 40.78771116 22.28937884
OS 40.77569188 22.2949262
OS 40.76552172 22.299549
OS 40.75627612 22.30509636
OS 40.74887964 22.30971916
OS 40.74333228 22.31434196
OS 40.73870948 22.31711564
OS 40.7359358 22.31988932
OS 40.73408668 22.32173844
OS 40.73316212 22.322663
OS 40.72391652 22.33375772
OS 40.71559548 22.34485244
OS 40.70912356 22.35594716
OS 40.70265164 22.36796644
OS 40.69710428 22.37998572
OS 40.69340604 22.39108044
OS 40.68693412 22.41234532
OS 40.685085 22.42251548
OS 40.68323588 22.43176108
OS 40.68231132 22.44008212
OS 40.68138676 22.44655404
OS 40.6804622 22.45302596
OS 40.6804622 22.4567242
OS 40.6804622 22.45949788
OS 40.6804622 22.46042244
OS 40.68138676 22.47798908
OS 40.68323588 22.49463116
OS 40.68693412 22.50942412
OS 40.6897078 22.52236796
OS 40.69340604 22.53346268
OS 40.69710428 22.54178372
OS 40.6989534 22.54640652
OS 40.69987796 22.54825564
OS 40.70727444 22.56212404
OS 40.71652004 22.57414332
OS 40.72484108 22.58523804
OS 40.73316212 22.59355908
OS 40.7405586 22.600031
OS 40.74610596 22.60557836
OS 40.7498042 22.60835204
OS 40.75165332 22.6092766
OS 40.7636726 22.61667308
OS 40.777541 22.623145
OS 40.79048484 22.62869236
OS 40.80250412 22.63331516
OS 40.81359884 22.63608884
OS 40.82191988 22.63793796
OS 40.8283918 22.63978708
OS 40.83024092 22.63978708
OS 40.84410932 22.6416362
OS 40.85982684 22.64348532
OS 40.87646892 22.64440988
OS 40.89218644 22.64533444
OE
OB 40.37720652 22.64810812 I
OS 40.38367844 22.64903268
OS 40.39292404 22.64903268
OS 40.40956612 22.64810812
OS 40.42528364 22.64718356
OS 40.4400766 22.64440988
OS 40.453945 22.6416362
OS 40.46688884 22.63793796
OS 40.47890812 22.63423972
OS 40.49000284 22.62961692
OS 40.500173 22.62499412
OS 40.5094186 22.62037132
OS 40.51681508 22.61574852
OS 40.523287 22.61205028
OS 40.52883436 22.60835204
OS 40.53345716 22.60557836
OS 40.53623084 22.60280468
OS 40.53807996 22.60188012
OS 40.53900452 22.60095556
OS 40.54825012 22.59170996
OS 40.55657116 22.5815398
OS 40.5648922 22.57044508
OS 40.57136412 22.55935036
OS 40.58245884 22.53716092
OS 40.58985532 22.51497148
OS 40.592629 22.50480132
OS 40.59540268 22.49463116
OS 40.5972518 22.48631012
OS 40.59910092 22.47891364
OS 40.60002548 22.47244172
OS 40.60002548 22.46781892
OS 40.60095004 22.46504524
OS 40.60095004 22.46412068
OS 40.52051332 22.45579964
OS 40.5186642 22.47706452
OS 40.51496596 22.49555572
OS 40.5094186 22.5121978
OS 40.50294668 22.52514164
OS 40.49739932 22.53623636
OS 40.49185196 22.54363284
OS 40.48815372 22.54825564
OS 40.4863046 22.55010476
OS 40.4724362 22.56119948
OS 40.45764324 22.56952052
OS 40.44192572 22.57599244
OS 40.42805732 22.57969068
OS 40.41511348 22.58246436
OS 40.40401876 22.58338892
OS 40.40032052 22.58431348
OS 40.39477316 22.58431348
OS 40.3753574 22.58338892
OS 40.35779076 22.57969068
OS 40.3429978 22.57414332
OS 40.33005396 22.56859596
OS 40.3198838 22.56212404
OS 40.31341188 22.55750124
OS 40.30878908 22.553803
OS 40.30693996 22.55195388
OS 40.29584524 22.53901004
OS 40.2875242 22.5260662
OS 40.28105228 22.51312236
OS 40.27735404 22.50017852
OS 40.27458036 22.49000836
OS 40.2736558 22.48076276
OS 40.27273124 22.4752154
OS 40.27273124 22.47429084
OS 40.27273124 22.47336628
OS 40.27458036 22.4567242
OS 40.2782786 22.43915756
OS 40.28475052 22.42344004
OS 40.29122244 22.40864708
OS 40.29861892 22.3966278
OS 40.30509084 22.38645764
OS 40.30693996 22.3827594
OS 40.30878908 22.37998572
OS 40.3106382 22.37906116
OS 40.3106382 22.3781366
OS 40.31803468 22.36796644
OS 40.32728028 22.35779628
OS 40.33745044 22.34670156
OS 40.34854516 22.33560684
OS 40.37165916 22.3134174
OS 40.39477316 22.29122796
OS 40.40679244 22.2810578
OS 40.4169626 22.2718122
OS 40.42713276 22.26349116
OS 40.4354538 22.25609468
OS 40.44192572 22.25054732
OS 40.44747308 22.24592452
OS 40.45117132 22.24315084
OS 40.45209588 22.24222628
OS 40.47520988 22.22281052
OS 40.49647476 22.20431932
OS 40.5140414 22.18767724
OS 40.5279098 22.17380884
OS 40.53992908 22.16178956
OS 40.54825012 22.15346852
OS 40.55287292 22.14792116
OS 40.55472204 22.1469966
OS 40.55472204 22.14607204
OS 40.56766588 22.13035452
OS 40.57783604 22.11556156
OS 40.58708164 22.1007686
OS 40.59447812 22.08782476
OS 40.60002548 22.07673004
OS 40.60372372 22.068409
OS 40.60557284 22.06286164
OS 40.6064974 22.06193708
OS 40.6064974 22.06101252
OS 40.61019564 22.05084236
OS 40.61204476 22.04159676
OS 40.61389388 22.03235116
OS 40.61481844 22.02403012
OS 40.615743 22.01663364
OS 40.615743 22.01108628
OS 40.615743 22.00738804
OS 40.615743 22.00646348
OS 40.19136996 22.00646348
OS 40.19136996 22.0822774
OS 40.50664492 22.0822774
OS 40.4955502 22.09799492
OS 40.49000284 22.10446684
OS 40.48538004 22.11093876
OS 40.48075724 22.11648612
OS 40.477059 22.12018436
OS 40.47428532 22.12295804
OS 40.47336076 22.1238826
OS 40.46873796 22.1285054
OS 40.4631906 22.1331282
OS 40.45024676 22.14514748
OS 40.4354538 22.15901588
OS 40.41973628 22.17288428
OS 40.40494332 22.18490356
OS 40.3984714 22.19045092
OS 40.39292404 22.19599828
OS 40.38830124 22.19969652
OS 40.384603 22.2024702
OS 40.38275388 22.20431932
OS 40.38182932 22.20524388
OS 40.36703636 22.21818772
OS 40.3522434 22.230207
OS 40.33929956 22.24222628
OS 40.32728028 22.25239644
OS 40.31618556 22.2625666
OS 40.30693996 22.2718122
OS 40.29769436 22.28013324
OS 40.29029788 22.28752972
OS 40.2829014 22.2949262
OS 40.27735404 22.30047356
OS 40.27273124 22.30509636
OS 40.26810844 22.30971916
OS 40.26348564 22.31526652
OS 40.26163652 22.31711564
OS 40.24869268 22.33283316
OS 40.23759796 22.34670156
OS 40.22835236 22.36056996
OS 40.22095588 22.37166468
OS 40.21540852 22.38183484
OS 40.21171028 22.38923132
OS 40.20986116 22.39385412
OS 40.2089366 22.39570324
OS 40.20338924 22.40957164
OS 40.199691 22.42344004
OS 40.19599276 22.43638388
OS 40.19414364 22.4474786
OS 40.19321908 22.45764876
OS 40.19229452 22.46504524
OS 40.19229452 22.46966804
OS 40.19229452 22.47151716
OS 40.19321908 22.48538556
OS 40.1950682 22.4983294
OS 40.19691732 22.51127324
OS 40.20061556 22.52236796
OS 40.20986116 22.5445574
OS 40.21910676 22.56212404
OS 40.22465412 22.57044508
OS 40.22927692 22.576917
OS 40.23389972 22.58338892
OS 40.23852252 22.58801172
OS 40.24222076 22.59170996
OS 40.24406988 22.5954082
OS 40.245919 22.59633276
OS 40.24684356 22.59725732
OS 40.25701372 22.60650292
OS 40.26810844 22.61482396
OS 40.28012772 22.62129588
OS 40.292147 22.62684324
OS 40.31618556 22.63608884
OS 40.34022412 22.64256076
OS 40.35039428 22.64440988
OS 40.36056444 22.646259
OS 40.36981004 22.64718356
OS 40.37720652 22.64810812
OE
OB 40.90050748 22.57044508 H
OS 40.8838654 22.56952052
OS 40.869997 22.56859596
OS 40.85890228 22.5676714
OS 40.8515058 22.56582228
OS 40.84595844 22.56489772
OS 40.8422602 22.56397316
OS 40.84133564 22.56397316
OS 40.82931636 22.55935036
OS 40.8191462 22.553803
OS 40.8099006 22.54825564
OS 40.80157956 22.54178372
OS 40.7960322 22.5353118
OS 40.7914094 22.530689
OS 40.78863572 22.52699076
OS 40.78771116 22.5260662
OS 40.78123924 22.51497148
OS 40.77569188 22.50387676
OS 40.77199364 22.49185748
OS 40.77014452 22.48168732
OS 40.7682954 22.47244172
OS 40.76737084 22.46412068
OS 40.76737084 22.45949788
OS 40.76737084 22.45857332
OS 40.76737084 22.45764876
OS 40.76921996 22.438233
OS 40.7729182 22.42159092
OS 40.77846556 22.40679796
OS 40.78493748 22.39477868
OS 40.7914094 22.38553308
OS 40.79695676 22.3781366
OS 40.800655 22.37443836
OS 40.80250412 22.37258924
OS 40.80897604 22.36704188
OS 40.81729708 22.36241908
OS 40.83486372 22.3550226
OS 40.85427948 22.34947524
OS 40.87369524 22.345777
OS 40.89126188 22.34392788
OS 40.89865836 22.34300332
OS 40.90513028 22.34300332
OS 40.9116022 22.34207876
OS 41.08357036 22.34207876
OS 41.08357036 22.57044508
OS 40.90050748 22.57044508
OE
SE
S P 0
OB 40.8954224 43.08813328 I
OS 40.9092908 43.08905784
OS 41.17186584 43.08905784
OS 41.17186584 42.44926232
OS 41.08680632 42.44926232
OS 41.08680632 42.70906368
OS 40.9231592 42.70906368
OS 40.89912064 42.70998824
OS 40.87600664 42.71183736
OS 40.85566632 42.71461104
OS 40.83717512 42.71830928
OS 40.81960848 42.72200752
OS 40.80481552 42.72663032
OS 40.79094712 42.73217768
OS 40.77892784 42.73772504
OS 40.76875768 42.74234784
OS 40.75951208 42.7478952
OS 40.7521156 42.752518
OS 40.74656824 42.7571408
OS 40.74194544 42.75991448
OS 40.73917176 42.76268816
OS 40.73732264 42.76453728
OS 40.73639808 42.76546184
OS 40.72715248 42.77655656
OS 40.71883144 42.78765128
OS 40.71235952 42.798746
OS 40.7058876 42.81076528
OS 40.70034024 42.82278456
OS 40.696642 42.83387928
OS 40.69017008 42.85514416
OS 40.68832096 42.86531432
OS 40.68647184 42.87455992
OS 40.68554728 42.88288096
OS 40.68462272 42.88935288
OS 40.68369816 42.8958248
OS 40.68369816 42.89952304
OS 40.68369816 42.90229672
OS 40.68369816 42.90322128
OS 40.68462272 42.92078792
OS 40.68647184 42.93743
OS 40.69017008 42.95222296
OS 40.69294376 42.9651668
OS 40.696642 42.97626152
OS 40.70034024 42.98458256
OS 40.70218936 42.98920536
OS 40.70311392 42.99105448
OS 40.7105104 43.00492288
OS 40.719756 43.01694216
OS 40.72807704 43.02803688
OS 40.73639808 43.03635792
OS 40.74379456 43.04282984
OS 40.74934192 43.0483772
OS 40.75304016 43.05115088
OS 40.75488928 43.05207544
OS 40.76690856 43.05947192
OS 40.78077696 43.06594384
OS 40.7937208 43.0714912
OS 40.80574008 43.076114
OS 40.8168348 43.07888768
OS 40.82515584 43.0807368
OS 40.83162776 43.08258592
OS 40.83347688 43.08258592
OS 40.84734528 43.08443504
OS 40.8630628 43.08628416
OS 40.87970488 43.08720872
OS 40.8954224 43.08813328
OE
OB 40.38783896 43.09090696 I
OS 40.39800912 43.09183152
OS 40.42112312 43.09183152
OS 40.43406696 43.0899824
OS 40.45903008 43.0853596
OS 40.48029496 43.07796312
OS 40.49878616 43.07056664
OS 40.5071072 43.06594384
OS 40.51357912 43.0622456
OS 40.52005104 43.05854736
OS 40.52467384 43.05484912
OS 40.52837208 43.05207544
OS 40.53114576 43.05022632
OS 40.53299488 43.04930176
OS 40.53391944 43.0483772
OS 40.55148608 43.03081056
OS 40.56535448 43.0113948
OS 40.5764492 42.99105448
OS 40.5856948 42.97071416
OS 40.59124216 42.95314752
OS 40.59401584 42.94575104
OS 40.59586496 42.93927912
OS 40.59678952 42.93373176
OS 40.59771408 42.93003352
OS 40.59863864 42.92725984
OS 40.59863864 42.92633528
OS 40.52005104 42.91246688
OS 40.5163528 42.9328072
OS 40.51080544 42.95037384
OS 40.50433352 42.9651668
OS 40.4978616 42.97718608
OS 40.49138968 42.98643168
OS 40.48584232 42.9929036
OS 40.48214408 42.9975264
OS 40.48121952 42.99845096
OS 40.46920024 43.00769656
OS 40.4562564 43.01509304
OS 40.44423712 43.01971584
OS 40.43221784 43.02341408
OS 40.42112312 43.0252632
OS 40.41280208 43.02711232
OS 40.4054056 43.02711232
OS 40.38876352 43.02618776
OS 40.37397056 43.02248952
OS 40.36102672 43.01786672
OS 40.349932 43.01324392
OS 40.34161096 43.00769656
OS 40.33513904 43.00307376
OS 40.33051624 42.99937552
OS 40.32959168 42.99845096
OS 40.31942152 42.98735624
OS 40.31202504 42.97533696
OS 40.30740224 42.96331768
OS 40.303704 42.95222296
OS 40.30185488 42.9420528
OS 40.30000576 42.93465632
OS 40.30000576 42.92910896
OS 40.30000576 42.9281844
OS 40.30000576 42.92725984
OS 40.30000576 42.91708968
OS 40.30185488 42.90784408
OS 40.30647768 42.89212656
OS 40.3129496 42.87825816
OS 40.32034608 42.86623888
OS 40.32774256 42.85791784
OS 40.33421448 42.85144592
OS 40.33883728 42.84774768
OS 40.33976184 42.84682312
OS 40.3406864 42.84682312
OS 40.35640392 42.83850208
OS 40.37119688 42.83203016
OS 40.3869144 42.82740736
OS 40.4007828 42.82463368
OS 40.41280208 42.82278456
OS 40.42297224 42.82093544
OS 40.43499152 42.82093544
OS 40.43868976 42.82186
OS 40.44331256 42.82186
OS 40.45255816 42.752518
OS 40.44053888 42.75529168
OS 40.42944416 42.7571408
OS 40.42019856 42.75898992
OS 40.41187752 42.75991448
OS 40.4054056 42.76083904
OS 40.39708456 42.76083904
OS 40.3776688 42.75898992
OS 40.36010216 42.75529168
OS 40.34438464 42.74974432
OS 40.3314408 42.7432724
OS 40.32127064 42.73680048
OS 40.31387416 42.73125312
OS 40.30925136 42.72755488
OS 40.30740224 42.72570576
OS 40.29538296 42.71183736
OS 40.28613736 42.6970444
OS 40.27966544 42.68225144
OS 40.2759672 42.66745848
OS 40.27319352 42.6554392
OS 40.27226896 42.64526904
OS 40.2713444 42.6415708
OS 40.2713444 42.63879712
OS 40.2713444 42.636948
OS 40.2713444 42.63602344
OS 40.27319352 42.61568312
OS 40.27781632 42.59719192
OS 40.28336368 42.5814744
OS 40.29076016 42.567606
OS 40.29815664 42.55651128
OS 40.303704 42.54819024
OS 40.3083268 42.54264288
OS 40.31017592 42.54079376
OS 40.32496888 42.52784992
OS 40.3406864 42.51860432
OS 40.35640392 42.5121324
OS 40.37119688 42.5075096
OS 40.38414072 42.50473592
OS 40.39431088 42.50381136
OS 40.39800912 42.5028868
OS 40.40355648 42.5028868
OS 40.42019856 42.50381136
OS 40.43591608 42.5075096
OS 40.44978448 42.5121324
OS 40.4608792 42.51767976
OS 40.4701248 42.52230256
OS 40.47752128 42.52692536
OS 40.48121952 42.5306236
OS 40.48306864 42.53154816
OS 40.49416336 42.544492
OS 40.50340896 42.55928496
OS 40.51173 42.57500248
OS 40.51820192 42.59164456
OS 40.52282472 42.60551296
OS 40.52467384 42.61198488
OS 40.5255984 42.61753224
OS 40.52652296 42.62215504
OS 40.52744752 42.62585328
OS 40.52837208 42.6277024
OS 40.52837208 42.62862696
OS 40.60695968 42.6184568
OS 40.60511056 42.60366384
OS 40.60233688 42.58979544
OS 40.59401584 42.56390776
OS 40.58384568 42.54171832
OS 40.57829832 42.53247272
OS 40.57275096 42.52322712
OS 40.5672036 42.51490608
OS 40.56165624 42.50843416
OS 40.55703344 42.50196224
OS 40.55241064 42.49733944
OS 40.54963696 42.4936412
OS 40.54686328 42.49086752
OS 40.54501416 42.4890184
OS 40.5440896 42.48809384
OS 40.53299488 42.4797728
OS 40.52190016 42.47145176
OS 40.51080544 42.46497984
OS 40.49878616 42.45943248
OS 40.47567216 42.45018688
OS 40.45348272 42.44463952
OS 40.44331256 42.4427904
OS 40.43406696 42.44094128
OS 40.42574592 42.44001672
OS 40.41834944 42.43909216
OS 40.41280208 42.4381676
OS 40.40448104 42.4381676
OS 40.3869144 42.43909216
OS 40.37119688 42.44094128
OS 40.35547936 42.44371496
OS 40.3406864 42.4474132
OS 40.326818 42.452036
OS 40.31479872 42.4566588
OS 40.30277944 42.46220616
OS 40.29260928 42.46775352
OS 40.28243912 42.47237632
OS 40.27411808 42.47792368
OS 40.2667216 42.48254648
OS 40.26117424 42.48716928
OS 40.25655144 42.49086752
OS 40.2528532 42.4936412
OS 40.25100408 42.49549032
OS 40.25007952 42.49641488
OS 40.2389848 42.5075096
OS 40.2297392 42.51952888
OS 40.22141816 42.53154816
OS 40.21402168 42.54356744
OS 40.20847432 42.55466216
OS 40.20292696 42.56668144
OS 40.19553048 42.58887088
OS 40.19368136 42.59904104
OS 40.19183224 42.60828664
OS 40.18998312 42.61660768
OS 40.18905856 42.62400416
OS 40.188134 42.62955152
OS 40.188134 42.63417432
OS 40.188134 42.636948
OS 40.188134 42.63787256
OS 40.18905856 42.660062
OS 40.1927568 42.68040232
OS 40.19830416 42.69796896
OS 40.20385152 42.71276192
OS 40.20939888 42.7247812
OS 40.21494624 42.7340268
OS 40.21864448 42.73957416
OS 40.21956904 42.74142328
OS 40.23251288 42.75529168
OS 40.24638128 42.76731096
OS 40.26117424 42.77655656
OS 40.2759672 42.78395304
OS 40.28891104 42.7895004
OS 40.2990812 42.79319864
OS 40.30277944 42.7941232
OS 40.30555312 42.79504776
OS 40.30740224 42.79597232
OS 40.3083268 42.79597232
OS 40.29260928 42.80429336
OS 40.27966544 42.8126144
OS 40.26857072 42.82186
OS 40.25932512 42.83018104
OS 40.25192864 42.83757752
OS 40.24638128 42.84404944
OS 40.2436076 42.84774768
OS 40.24268304 42.8495968
OS 40.23528656 42.86254064
OS 40.2297392 42.87548448
OS 40.2251164 42.88842832
OS 40.22234272 42.9004476
OS 40.2204936 42.91061776
OS 40.21956904 42.91801424
OS 40.21956904 42.9235616
OS 40.21956904 42.92541072
OS 40.2204936 42.94112824
OS 40.22326728 42.95684576
OS 40.22696552 42.97071416
OS 40.23158832 42.98273344
OS 40.23621112 42.9929036
OS 40.23990936 43.00122464
OS 40.24268304 43.00584744
OS 40.2436076 43.00769656
OS 40.2528532 43.02156496
OS 40.26394792 43.03358424
OS 40.27504264 43.0437544
OS 40.28613736 43.053
OS 40.29538296 43.05947192
OS 40.303704 43.06501928
OS 40.30925136 43.06779296
OS 40.31017592 43.06871752
OS 40.31110048 43.06871752
OS 40.32774256 43.076114
OS 40.34438464 43.08166136
OS 40.36102672 43.08628416
OS 40.37581968 43.08905784
OS 40.38783896 43.09090696
OE
OB 40.90374344 43.01324392 H
OS 40.88710136 43.01231936
OS 40.87323296 43.0113948
OS 40.86213824 43.01047024
OS 40.85474176 43.00862112
OS 40.8491944 43.00769656
OS 40.84549616 43.006772
OS 40.8445716 43.006772
OS 40.83255232 43.0021492
OS 40.82238216 42.99660184
OS 40.81313656 42.99105448
OS 40.80481552 42.98458256
OS 40.79926816 42.97811064
OS 40.79464536 42.97348784
OS 40.79187168 42.9697896
OS 40.79094712 42.96886504
OS 40.7844752 42.95777032
OS 40.77892784 42.9466756
OS 40.7752296 42.93465632
OS 40.77338048 42.92448616
OS 40.77153136 42.91524056
OS 40.7706068 42.90691952
OS 40.7706068 42.90229672
OS 40.7706068 42.90137216
OS 40.7706068 42.9004476
OS 40.77245592 42.88103184
OS 40.77615416 42.86438976
OS 40.78170152 42.8495968
OS 40.78817344 42.83757752
OS 40.79464536 42.82833192
OS 40.80019272 42.82093544
OS 40.80389096 42.8172372
OS 40.80574008 42.81538808
OS 40.812212 42.80984072
OS 40.82053304 42.80521792
OS 40.83809968 42.79782144
OS 40.85751544 42.79227408
OS 40.8769312 42.78857584
OS 40.89449784 42.78672672
OS 40.90189432 42.78580216
OS 40.90836624 42.78580216
OS 40.91483816 42.7848776
OS 41.08680632 42.7848776
OS 41.08680632 43.01324392
OS 40.90374344 43.01324392
OE
SE
S P 0
OB 41.56870528 16.28258618 I
OS 41.57610176 16.28351074
OS 41.87288552 16.28351074
OS 41.87288552 15.64371522
OS 41.787826 15.64371522
OS 41.787826 15.92755514
OS 41.67872792 15.92755514
OS 41.66855776 15.92663058
OS 41.66116128 15.92663058
OS 41.65468936 15.92570602
OS 41.65006656 15.92478146
OS 41.64636832 15.92478146
OS 41.6445192 15.9238569
OS 41.64359464 15.9238569
OS 41.62880168 15.9192341
OS 41.62232976 15.91646042
OS 41.6167824 15.91368674
OS 41.61123504 15.91091306
OS 41.6075368 15.90906394
OS 41.60568768 15.90813938
OS 41.60476312 15.90721482
OS 41.59736664 15.90166746
OS 41.58997016 15.89519554
OS 41.57610176 15.88132714
OS 41.56962984 15.87485522
OS 41.56500704 15.86930786
OS 41.56223336 15.86560962
OS 41.5613088 15.86468506
OS 41.5520632 15.85174122
OS 41.54189304 15.83787282
OS 41.53172288 15.82307986
OS 41.52155272 15.80921146
OS 41.51323168 15.79626762
OS 41.50675976 15.78609746
OS 41.50398608 15.78239922
OS 41.50213696 15.77962554
OS 41.50028784 15.77777642
OS 41.50028784 15.77685186
OS 41.41615288 15.64371522
OS 41.31075304 15.64371522
OS 41.42077568 15.8175325
OS 41.43371952 15.8360237
OS 41.4457388 15.85266578
OS 41.45775808 15.86653418
OS 41.46792824 15.87947802
OS 41.47717384 15.88872362
OS 41.48457032 15.8961201
OS 41.48919312 15.9007429
OS 41.49104224 15.90259202
OS 41.49843872 15.90813938
OS 41.50675976 15.9146113
OS 41.52340184 15.92478146
OS 41.53079832 15.9284797
OS 41.53634568 15.93217794
OS 41.54004392 15.93402706
OS 41.54189304 15.93495162
OS 41.52525096 15.9377253
OS 41.50953344 15.94049898
OS 41.49566504 15.94512178
OS 41.48179664 15.94882002
OS 41.46977736 15.95344282
OS 41.45868264 15.95899018
OS 41.44851248 15.96361298
OS 41.43926688 15.96823578
OS 41.4318704 15.97378314
OS 41.42447392 15.97840594
OS 41.41892656 15.98210418
OS 41.41430376 15.98580242
OS 41.41060552 15.9885761
OS 41.40783184 15.99134978
OS 41.40690728 15.99227434
OS 41.40598272 15.9931989
OS 41.39858624 16.0024445
OS 41.39118976 16.0116901
OS 41.38009504 16.03110586
OS 41.37269856 16.05052162
OS 41.3671512 16.06901282
OS 41.36345296 16.08473034
OS 41.3625284 16.09120226
OS 41.3625284 16.09767418
OS 41.36160384 16.10229698
OS 41.36160384 16.10599522
OS 41.36160384 16.10784434
OS 41.36160384 16.1087689
OS 41.3625284 16.12818466
OS 41.36530208 16.1457513
OS 41.36992488 16.16239338
OS 41.37454768 16.17626178
OS 41.38009504 16.18828106
OS 41.38379328 16.19752666
OS 41.38749152 16.20307402
OS 41.38841608 16.20399858
OS 41.38841608 16.20492314
OS 41.3995108 16.2197161
OS 41.41060552 16.23265994
OS 41.4226248 16.24375466
OS 41.43371952 16.2520757
OS 41.44388968 16.25854762
OS 41.45221072 16.26224586
OS 41.45775808 16.26501954
OS 41.45868264 16.2659441
OS 41.4596072 16.2659441
OS 41.46792824 16.26871778
OS 41.4780984 16.27149146
OS 41.49843872 16.27611426
OS 41.52062816 16.27888794
OS 41.54096848 16.28166162
OS 41.56038424 16.28258618
OS 41.56870528 16.28258618
OE
OB 40.9649676 15.64371522 I
OS 40.9649676 16.28628442
OS 41.0158184 16.28628442
OS 41.025064 16.2705669
OS 41.03523416 16.25577394
OS 41.04725344 16.24098098
OS 41.05834816 16.22803714
OS 41.06944288 16.21694242
OS 41.07776392 16.20769682
OS 41.08146216 16.20492314
OS 41.08423584 16.20214946
OS 41.0851604 16.2012249
OS 41.08608496 16.20030034
OS 41.10550072 16.18458282
OS 41.12491648 16.16978986
OS 41.14340768 16.15684602
OS 41.16189888 16.14667586
OS 41.1776164 16.13743026
OS 41.18408832 16.13373202
OS 41.18963568 16.13095834
OS 41.19425848 16.12818466
OS 41.19795672 16.1272601
OS 41.19980584 16.12541098
OS 41.2007304 16.12541098
OS 41.2007304 16.04959706
OS 41.186862 16.05514442
OS 41.1729936 16.06161634
OS 41.1591252 16.06808826
OS 41.14618136 16.07456018
OS 41.13508664 16.08010754
OS 41.12584104 16.08473034
OS 41.12029368 16.08842858
OS 41.11936912 16.08935314
OS 41.11844456 16.08935314
OS 41.10180248 16.0995233
OS 41.08700952 16.10969346
OS 41.07406568 16.11893906
OS 41.06389552 16.1272601
OS 41.05464992 16.13373202
OS 41.04910256 16.13927938
OS 41.04447976 16.14297762
OS 41.0435552 16.14390218
OS 41.0435552 15.64371522
OS 40.9649676 15.64371522
OE
OB 41.58627192 16.21231962 H
OS 41.5613088 16.21139506
OS 41.54004392 16.20769682
OS 41.52155272 16.20307402
OS 41.50768432 16.19752666
OS 41.49566504 16.1919793
OS 41.48826856 16.1873565
OS 41.48364576 16.18365826
OS 41.48179664 16.1827337
OS 41.47070192 16.17071442
OS 41.46238088 16.15869514
OS 41.45683352 16.1457513
OS 41.45221072 16.13465658
OS 41.4503616 16.12356186
OS 41.44943704 16.11524082
OS 41.44851248 16.10969346
OS 41.44851248 16.1087689
OS 41.44851248 16.10784434
OS 41.44943704 16.09674962
OS 41.45128616 16.0856549
OS 41.45405984 16.0764093
OS 41.45683352 16.06808826
OS 41.46053176 16.06069178
OS 41.46330544 16.05514442
OS 41.46515456 16.05144618
OS 41.46607912 16.05052162
OS 41.47255104 16.04127602
OS 41.48087208 16.03295498
OS 41.48919312 16.02648306
OS 41.49751416 16.0209357
OS 41.50491064 16.01723746
OS 41.510458 16.01446378
OS 41.51415624 16.01261466
OS 41.51600536 16.0116901
OS 41.5289492 16.00799186
OS 41.54374216 16.00521818
OS 41.55853512 16.00336906
OS 41.57332808 16.0024445
OS 41.58627192 16.00151994
OS 41.59736664 16.00059538
OS 41.787826 16.00059538
OS 41.787826 16.21231962
OS 41.58627192 16.21231962
OE
SE
S P 0
OB 41.74848902 8.43006696 I
OS 41.75496094 8.43099152
OS 41.76420654 8.43099152
OS 41.79471702 8.4291424
OS 41.82430294 8.4245196
OS 41.85019062 8.41897224
OS 41.8622099 8.415274
OS 41.87330462 8.41157576
OS 41.88347478 8.40787752
OS 41.89272038 8.40417928
OS 41.90011686 8.4014056
OS 41.90751334 8.39863192
OS 41.91213614 8.39585824
OS 41.91583438 8.39400912
OS 41.91860806 8.39308456
OS 41.91953262 8.39216
OS 41.94449574 8.37644248
OS 41.96576062 8.35795128
OS 41.98425182 8.33946008
OS 41.99996934 8.32096888
OS 42.01198862 8.3043268
OS 42.01661142 8.29693032
OS 42.02030966 8.2904584
OS 42.0240079 8.2858356
OS 42.02585702 8.28213736
OS 42.02678158 8.27936368
OS 42.02770614 8.27843912
OS 42.04064998 8.24977776
OS 42.04989558 8.22019184
OS 42.0563675 8.19060592
OS 42.0609903 8.16379368
OS 42.06283942 8.1517744
OS 42.06376398 8.13975512
OS 42.06468854 8.13050952
OS 42.06468854 8.12126392
OS 42.0656131 8.114792
OS 42.0656131 8.10924464
OS 42.0656131 8.1055464
OS 42.0656131 8.10462184
OS 42.06376398 8.07133768
OS 42.06006574 8.03897808
OS 42.05544294 8.01031672
OS 42.0517447 7.99644832
OS 42.04897102 7.98442904
OS 42.04619734 7.97333432
OS 42.0424991 7.96316416
OS 42.03972542 7.95391856
OS 42.0378763 7.94652208
OS 42.03510262 7.94097472
OS 42.03417806 7.93635192
OS 42.03232894 7.93357824
OS 42.03232894 7.93265368
OS 42.01846054 7.90491688
OS 42.00274302 7.87995376
OS 41.98610094 7.85868888
OS 41.9777799 7.85036784
OS 41.97038342 7.8420468
OS 41.96298694 7.83465032
OS 41.95559046 7.8281784
OS 41.94911854 7.82263104
OS 41.94357118 7.8189328
OS 41.93987294 7.81523456
OS 41.9361747 7.81246088
OS 41.93432558 7.81153632
OS 41.93340102 7.81061176
OS 41.92045718 7.80321528
OS 41.90751334 7.79674336
OS 41.87977654 7.7865732
OS 41.85203974 7.77917672
OS 41.8252275 7.77455392
OS 41.81228366 7.7727048
OS 41.80118894 7.77085568
OS 41.79101878 7.76993112
OS 41.78269774 7.76993112
OS 41.77530126 7.76900656
OS 41.7651311 7.76900656
OS 41.7466399 7.76993112
OS 41.72907326 7.77178024
OS 41.71243118 7.77362936
OS 41.69671366 7.7773276
OS 41.6819207 7.7819504
OS 41.6680523 7.7865732
OS 41.65510846 7.791196
OS 41.64308918 7.79674336
OS 41.63291902 7.80136616
OS 41.62274886 7.80598896
OS 41.61535238 7.81061176
OS 41.6079559 7.81523456
OS 41.6033331 7.8189328
OS 41.5987103 7.82078192
OS 41.59686118 7.82263104
OS 41.59593662 7.8235556
OS 41.58299278 7.83465032
OS 41.57189806 7.84574504
OS 41.5617279 7.85868888
OS 41.55155774 7.87163272
OS 41.53491566 7.8975204
OS 41.52197182 7.92340808
OS 41.51642446 7.93542736
OS 41.51180166 7.94652208
OS 41.50810342 7.95669224
OS 41.50532974 7.96501328
OS 41.50255606 7.97240976
OS 41.50070694 7.97795712
OS 41.49978238 7.98165536
OS 41.49978238 7.98257992
OS 41.5848419 8.0038448
OS 41.58854014 7.98905184
OS 41.59316294 7.97518344
OS 41.59778574 7.9622396
OS 41.60240854 7.95022032
OS 41.6079559 7.9391256
OS 41.61350326 7.92988
OS 41.61997518 7.9206344
OS 41.62552254 7.91231336
OS 41.63014534 7.90491688
OS 41.6356927 7.89936952
OS 41.6403155 7.89382216
OS 41.64401374 7.88919936
OS 41.64771198 7.88642568
OS 41.65048566 7.883652
OS 41.65141022 7.88272744
OS 41.65233478 7.88180288
OS 41.66158038 7.8744064
OS 41.67175054 7.86885904
OS 41.69209086 7.85868888
OS 41.71150662 7.8512924
OS 41.73092238 7.8466696
OS 41.74756446 7.84297136
OS 41.75403638 7.8420468
OS 41.7605083 7.8420468
OS 41.76605566 7.84112224
OS 41.77252758 7.84112224
OS 41.79379246 7.8420468
OS 41.81413278 7.84574504
OS 41.83262398 7.85036784
OS 41.84926606 7.8559152
OS 41.8622099 7.86146256
OS 41.86775726 7.86423624
OS 41.87238006 7.86608536
OS 41.8760783 7.86793448
OS 41.87885198 7.8697836
OS 41.8807011 7.87070816
OS 41.88162566 7.87070816
OS 41.8991923 7.883652
OS 41.91398526 7.8975204
OS 41.9269291 7.91323792
OS 41.93709926 7.92803088
OS 41.9454203 7.94097472
OS 41.95096766 7.95206944
OS 41.95281678 7.95669224
OS 41.9546659 7.95946592
OS 41.95559046 7.96131504
OS 41.95559046 7.9622396
OS 41.96298694 7.98627816
OS 41.9685343 8.01031672
OS 41.9731571 8.03435528
OS 41.97593078 8.05654472
OS 41.97685534 8.06671488
OS 41.9777799 8.07596048
OS 41.9777799 8.08428152
OS 41.97870446 8.09075344
OS 41.97870446 8.0963008
OS 41.97870446 8.1009236
OS 41.97870446 8.10369728
OS 41.97870446 8.10462184
OS 41.9777799 8.1286604
OS 41.97593078 8.15084984
OS 41.97223254 8.17119016
OS 41.9685343 8.18968136
OS 41.96576062 8.20539888
OS 41.9639115 8.2118708
OS 41.96206238 8.21741816
OS 41.96113782 8.22204096
OS 41.96021326 8.22481464
OS 41.9592887 8.22666376
OS 41.9592887 8.22758832
OS 41.9500431 8.2488532
OS 41.93987294 8.26826896
OS 41.92877822 8.28398648
OS 41.91675894 8.29785488
OS 41.90658878 8.3089496
OS 41.89826774 8.31634608
OS 41.89179582 8.32096888
OS 41.89087126 8.322818
OS 41.8899467 8.322818
OS 41.87053094 8.33483728
OS 41.84926606 8.34408288
OS 41.82892574 8.3505548
OS 41.80950998 8.35425304
OS 41.79194334 8.35702672
OS 41.78454686 8.35795128
OS 41.77807494 8.35795128
OS 41.77345214 8.35887584
OS 41.76605566 8.35887584
OS 41.74294166 8.35795128
OS 41.72167678 8.35425304
OS 41.70411014 8.34870568
OS 41.68839262 8.34315832
OS 41.67637334 8.3366864
OS 41.66712774 8.3320636
OS 41.66158038 8.32836536
OS 41.65973126 8.32651624
OS 41.6449383 8.31264784
OS 41.6310699 8.29693032
OS 41.61997518 8.28028824
OS 41.61072958 8.26364616
OS 41.6033331 8.2488532
OS 41.60055942 8.24145672
OS 41.5987103 8.23590936
OS 41.59686118 8.23128656
OS 41.59501206 8.22758832
OS 41.5940875 8.2257392
OS 41.5940875 8.22481464
OS 41.5108771 8.2442304
OS 41.51642446 8.26087248
OS 41.52197182 8.27566544
OS 41.5293683 8.28953384
OS 41.53584022 8.30340224
OS 41.5432367 8.31542152
OS 41.55155774 8.32651624
OS 41.55895422 8.33761096
OS 41.5663507 8.34685656
OS 41.57374718 8.35425304
OS 41.5802191 8.36164952
OS 41.58669102 8.36812144
OS 41.59131382 8.37274424
OS 41.59593662 8.37736704
OS 41.59963486 8.38014072
OS 41.60148398 8.38106528
OS 41.60240854 8.38198984
OS 41.61535238 8.39031088
OS 41.62829622 8.39863192
OS 41.64124006 8.40510384
OS 41.65510846 8.4106512
OS 41.68284526 8.41897224
OS 41.70780838 8.4245196
OS 41.71982766 8.42729328
OS 41.72999782 8.42821784
OS 41.74016798 8.4291424
OS 41.74848902 8.43006696
OE
OB 41.20022494 8.42174592 I
OS 41.20669686 8.42267048
OS 41.21594246 8.42267048
OS 41.23258454 8.42174592
OS 41.24830206 8.42082136
OS 41.26309502 8.41804768
OS 41.27696342 8.415274
OS 41.28990726 8.41157576
OS 41.30192654 8.40787752
OS 41.31302126 8.40325472
OS 41.32319142 8.39863192
OS 41.33243702 8.39400912
OS 41.3398335 8.38938632
OS 41.34630542 8.38568808
OS 41.35185278 8.38198984
OS 41.35647558 8.37921616
OS 41.35924926 8.37644248
OS 41.36109838 8.37551792
OS 41.36202294 8.37459336
OS 41.37126854 8.36534776
OS 41.37958958 8.3551776
OS 41.38791062 8.34408288
OS 41.39438254 8.33298816
OS 41.40547726 8.31079872
OS 41.41287374 8.28860928
OS 41.41564742 8.27843912
OS 41.4184211 8.26826896
OS 41.42027022 8.25994792
OS 41.42211934 8.25255144
OS 41.4230439 8.24607952
OS 41.4230439 8.24145672
OS 41.42396846 8.23868304
OS 41.42396846 8.23775848
OS 41.34353174 8.22943744
OS 41.34168262 8.25070232
OS 41.33798438 8.26919352
OS 41.33243702 8.2858356
OS 41.3259651 8.29877944
OS 41.32041774 8.30987416
OS 41.31487038 8.31727064
OS 41.31117214 8.32189344
OS 41.30932302 8.32374256
OS 41.29545462 8.33483728
OS 41.28066166 8.34315832
OS 41.26494414 8.34963024
OS 41.25107574 8.35332848
OS 41.2381319 8.35610216
OS 41.22703718 8.35702672
OS 41.22333894 8.35795128
OS 41.21779158 8.35795128
OS 41.19837582 8.35702672
OS 41.18080918 8.35332848
OS 41.16601622 8.34778112
OS 41.15307238 8.34223376
OS 41.14290222 8.33576184
OS 41.1364303 8.33113904
OS 41.1318075 8.3274408
OS 41.12995838 8.32559168
OS 41.11886366 8.31264784
OS 41.11054262 8.299704
OS 41.1040707 8.28676016
OS 41.10037246 8.27381632
OS 41.09759878 8.26364616
OS 41.09667422 8.25440056
OS 41.09574966 8.2488532
OS 41.09574966 8.24792864
OS 41.09574966 8.24700408
OS 41.09759878 8.230362
OS 41.10129702 8.21279536
OS 41.10776894 8.19707784
OS 41.11424086 8.18228488
OS 41.12163734 8.1702656
OS 41.12810926 8.16009544
OS 41.12995838 8.1563972
OS 41.1318075 8.15362352
OS 41.13365662 8.15269896
OS 41.13365662 8.1517744
OS 41.1410531 8.14160424
OS 41.1502987 8.13143408
OS 41.16046886 8.12033936
OS 41.17156358 8.10924464
OS 41.19467758 8.0870552
OS 41.21779158 8.06486576
OS 41.22981086 8.0546956
OS 41.23998102 8.04545
OS 41.25015118 8.03712896
OS 41.25847222 8.02973248
OS 41.26494414 8.02418512
OS 41.2704915 8.01956232
OS 41.27418974 8.01678864
OS 41.2751143 8.01586408
OS 41.2982283 7.99644832
OS 41.31949318 7.97795712
OS 41.33705982 7.96131504
OS 41.35092822 7.94744664
OS 41.3629475 7.93542736
OS 41.37126854 7.92710632
OS 41.37589134 7.92155896
OS 41.37774046 7.9206344
OS 41.37774046 7.91970984
OS 41.3906843 7.90399232
OS 41.40085446 7.88919936
OS 41.41010006 7.8744064
OS 41.41749654 7.86146256
OS 41.4230439 7.85036784
OS 41.42674214 7.8420468
OS 41.42859126 7.83649944
OS 41.42951582 7.83557488
OS 41.42951582 7.83465032
OS 41.43321406 7.82448016
OS 41.43506318 7.81523456
OS 41.4369123 7.80598896
OS 41.43783686 7.79766792
OS 41.43876142 7.79027144
OS 41.43876142 7.78472408
OS 41.43876142 7.78102584
OS 41.43876142 7.78010128
OS 41.01438838 7.78010128
OS 41.01438838 7.8559152
OS 41.32966334 7.8559152
OS 41.31856862 7.87163272
OS 41.31302126 7.87810464
OS 41.30839846 7.88457656
OS 41.30377566 7.89012392
OS 41.30007742 7.89382216
OS 41.29730374 7.89659584
OS 41.29637918 7.8975204
OS 41.29175638 7.9021432
OS 41.28620902 7.906766
OS 41.27326518 7.91878528
OS 41.25847222 7.93265368
OS 41.2427547 7.94652208
OS 41.22796174 7.95854136
OS 41.22148982 7.96408872
OS 41.21594246 7.96963608
OS 41.21131966 7.97333432
OS 41.20762142 7.976108
OS 41.2057723 7.97795712
OS 41.20484774 7.97888168
OS 41.19005478 7.99182552
OS 41.17526182 8.0038448
OS 41.16231798 8.01586408
OS 41.1502987 8.02603424
OS 41.13920398 8.0362044
OS 41.12995838 8.04545
OS 41.12071278 8.05377104
OS 41.1133163 8.06116752
OS 41.10591982 8.068564
OS 41.10037246 8.07411136
OS 41.09574966 8.07873416
OS 41.09112686 8.08335696
OS 41.08650406 8.08890432
OS 41.08465494 8.09075344
OS 41.0717111 8.10647096
OS 41.06061638 8.12033936
OS 41.05137078 8.13420776
OS 41.0439743 8.14530248
OS 41.03842694 8.15547264
OS 41.0347287 8.16286912
OS 41.03287958 8.16749192
OS 41.03195502 8.16934104
OS 41.02640766 8.18320944
OS 41.02270942 8.19707784
OS 41.01901118 8.21002168
OS 41.01716206 8.2211164
OS 41.0162375 8.23128656
OS 41.01531294 8.23868304
OS 41.01531294 8.24330584
OS 41.01531294 8.24515496
OS 41.0162375 8.25902336
OS 41.01808662 8.2719672
OS 41.01993574 8.28491104
OS 41.02363398 8.29600576
OS 41.03287958 8.3181952
OS 41.04212518 8.33576184
OS 41.04767254 8.34408288
OS 41.05229534 8.3505548
OS 41.05691814 8.35702672
OS 41.06154094 8.36164952
OS 41.06523918 8.36534776
OS 41.0670883 8.369046
OS 41.06893742 8.36997056
OS 41.06986198 8.37089512
OS 41.08003214 8.38014072
OS 41.09112686 8.38846176
OS 41.10314614 8.39493368
OS 41.11516542 8.40048104
OS 41.13920398 8.40972664
OS 41.16324254 8.41619856
OS 41.1734127 8.41804768
OS 41.18358286 8.4198968
OS 41.19282846 8.42082136
OS 41.20022494 8.42174592
OE
SE
S P 0
OB 48.49040086 -36.61402634 I
OS 48.17420134 -36.61402634
OS 48.17420134 -37.45999874
OS 48.04661206 -37.45999874
OS 48.04661206 -36.61402634
OS 47.73041254 -36.61402634
OS 47.73041254 -36.50030546
OS 48.49040086 -36.50030546
OS 48.49040086 -36.61402634
OE
OB 47.69990206 -37.45999874 I
OS 47.5556707 -37.45999874
OS 47.44333666 -37.16876234
OS 47.04115306 -37.16876234
OS 46.93714006 -37.45999874
OS 46.80261658 -37.45999874
OS 47.16874234 -36.50030546
OS 47.30742634 -36.50030546
OS 47.69990206 -37.45999874
OE
OB 49.31834434 -36.61402634 I
OS 48.75112678 -36.61402634
OS 48.75112678 -36.90664958
OS 49.2822865 -36.90664958
OS 49.2822865 -37.02037046
OS 48.75112678 -37.02037046
OS 48.75112678 -37.34627786
OS 49.34053378 -37.34627786
OS 49.34053378 -37.45999874
OS 48.6235375 -37.45999874
OS 48.6235375 -36.50030546
OS 49.31834434 -36.50030546
OS 49.31834434 -36.61402634
OE
OB 46.33386466 -36.5016923 I
OS 46.36160146 -36.50307914
OS 46.38933826 -36.50585282
OS 46.41707506 -36.51001334
OS 46.44065134 -36.51417386
OS 46.44203818 -36.51417386
OS 46.44481186 -36.5155607
OS 46.44897238 -36.5155607
OS 46.45451974 -36.51833438
OS 46.46977498 -36.5224949
OS 46.48919074 -36.5294291
OS 46.51138018 -36.53913698
OS 46.53495646 -36.55161854
OS 46.55853274 -36.56548694
OS 46.58072218 -36.58351586
OS 46.58210902 -36.5849027
OS 46.58349586 -36.58628954
OS 46.58765638 -36.59045006
OS 46.59320374 -36.59461058
OS 46.60707214 -36.60847898
OS 46.62371422 -36.62789474
OS 46.64174314 -36.65147102
OS 46.6611589 -36.67920782
OS 46.67918782 -36.71110514
OS 46.69444306 -36.74716298
OS 46.69444306 -36.74854982
OS 46.6958299 -36.7513235
OS 46.69860358 -36.75687086
OS 46.69999042 -36.7651919
OS 46.70415094 -36.77489978
OS 46.70692462 -36.7859945
OS 46.7096983 -36.79847606
OS 46.71385882 -36.8137313
OS 46.71801934 -36.82898654
OS 46.72079302 -36.84701546
OS 46.72772722 -36.88584698
OS 46.73188774 -36.92883902
OS 46.73327458 -36.97599158
OS 46.73327458 -36.97737842
OS 46.73327458 -36.9801521
OS 46.73327458 -36.9870863
OS 46.73327458 -36.9940205
OS 46.73188774 -37.00372838
OS 46.73188774 -37.0148231
OS 46.7305009 -37.04117306
OS 46.72634038 -37.07168354
OS 46.72217986 -37.10358086
OS 46.71524566 -37.13686502
OS 46.70692462 -37.17014918
OS 46.70692462 -37.17153602
OS 46.70553778 -37.1743097
OS 46.70415094 -37.17847022
OS 46.7027641 -37.18401758
OS 46.69721674 -37.19927282
OS 46.6888957 -37.21868858
OS 46.68057466 -37.24087802
OS 46.66947994 -37.26306746
OS 46.65561154 -37.28664374
OS 46.64174314 -37.30883318
OS 46.6403563 -37.31160686
OS 46.63480894 -37.31854106
OS 46.6264879 -37.32824894
OS 46.61539318 -37.3407305
OS 46.60291162 -37.3545989
OS 46.58765638 -37.3684673
OS 46.57240114 -37.38372254
OS 46.55437222 -37.3962041
OS 46.55159854 -37.39759094
OS 46.54605118 -37.40175146
OS 46.5363433 -37.40729882
OS 46.5224749 -37.41423302
OS 46.50583282 -37.42255406
OS 46.48641706 -37.42948826
OS 46.46422762 -37.4378093
OS 46.4392645 -37.4447435
OS 46.43649082 -37.4447435
OS 46.4323303 -37.44613034
OS 46.42816978 -37.44751718
OS 46.41430138 -37.44890402
OS 46.39488562 -37.4516777
OS 46.37269618 -37.45445138
OS 46.34634622 -37.45722506
OS 46.31722258 -37.4586119
OS 46.28532526 -37.45999874
OS 45.9400021 -37.45999874
OS 45.9400021 -36.50030546
OS 46.30890154 -36.50030546
OS 46.33386466 -36.5016923
OE
OB 46.28948578 -36.61402634 H
OS 46.06759138 -36.61402634
OS 46.06759138 -37.34627786
OS 46.29503314 -37.34627786
OS 46.30474102 -37.34489102
OS 46.32554362 -37.34350418
OS 46.3491199 -37.34211734
OS 46.37408302 -37.33934366
OS 46.39904614 -37.33518314
OS 46.41984874 -37.32963578
OS 46.42262242 -37.32824894
OS 46.42955662 -37.3268621
OS 46.4392645 -37.32270158
OS 46.45174606 -37.31715422
OS 46.46561446 -37.30883318
OS 46.47948286 -37.30051214
OS 46.49335126 -37.29080426
OS 46.50721966 -37.27970954
OS 46.5086065 -37.27693586
OS 46.51415386 -37.2713885
OS 46.5224749 -37.26168062
OS 46.53218278 -37.24781222
OS 46.5432775 -37.2297833
OS 46.55575906 -37.2089807
OS 46.56685378 -37.18540442
OS 46.57656166 -37.15905446
OS 46.57656166 -37.15766762
OS 46.5779485 -37.15489394
OS 46.57933534 -37.15073342
OS 46.58072218 -37.14518606
OS 46.58210902 -37.13825186
OS 46.5848827 -37.12854398
OS 46.58765638 -37.1188361
OS 46.59043006 -37.10774138
OS 46.59459058 -37.08000458
OS 46.5987511 -37.04810726
OS 46.60152478 -37.01204942
OS 46.60291162 -36.9732179
OS 46.60291162 -36.97183106
OS 46.60291162 -36.9662837
OS 46.60291162 -36.9593495
OS 46.60152478 -36.94825478
OS 46.60152478 -36.93577322
OS 46.60013794 -36.92190482
OS 46.5987511 -36.90526274
OS 46.59736426 -36.88862066
OS 46.59043006 -36.85117598
OS 46.58210902 -36.81234446
OS 46.56962746 -36.77628662
OS 46.56130642 -36.7582577
OS 46.55298538 -36.74300246
OS 46.55298538 -36.74161562
OS 46.5502117 -36.73884194
OS 46.54743802 -36.73468142
OS 46.54466434 -36.72913406
OS 46.53356962 -36.71526566
OS 46.51970122 -36.69862358
OS 46.5016723 -36.68059466
OS 46.4808697 -36.66256574
OS 46.45729342 -36.6473105
OS 46.4323303 -36.63482894
OS 46.42955662 -36.6334421
OS 46.42262242 -36.63205526
OS 46.41014086 -36.62789474
OS 46.39211194 -36.62373422
OS 46.3699225 -36.62096054
OS 46.3421857 -36.61680002
OS 46.32554362 -36.61541318
OS 46.3075147 -36.61541318
OS 46.28948578 -36.61402634
OE
OB 47.23531066 -36.60015794 H
OS 47.23531066 -36.60154478
OS 47.23392382 -36.60431846
OS 47.23392382 -36.60986582
OS 47.23115014 -36.61541318
OS 47.2297633 -36.62512106
OS 47.22698962 -36.63482894
OS 47.22144226 -36.65840522
OS 47.21450806 -36.68614202
OS 47.20480018 -36.7166525
OS 47.1950923 -36.74993666
OS 47.18261074 -36.78460766
OS 47.07859774 -37.06474934
OS 47.4031183 -37.06474934
OS 47.30326582 -36.80124974
OS 47.30326582 -36.7998629
OS 47.30187898 -36.79570238
OS 47.2991053 -36.78876818
OS 47.29633162 -36.78044714
OS 47.2921711 -36.77073926
OS 47.28801058 -36.7582577
OS 47.28385006 -36.7443893
OS 47.2783027 -36.7305209
OS 47.26720798 -36.69862358
OS 47.25611326 -36.66533942
OS 47.24501854 -36.63205526
OS 47.23531066 -36.60015794
OE
SE
S P 0
OB 53.64989524 -38.94890356 I
OS 53.57130764 -38.94890356
OS 53.57130764 -38.4487166
OS 53.57038308 -38.44964116
OS 53.56576028 -38.4533394
OS 53.56021292 -38.45888676
OS 53.55096732 -38.46535868
OS 53.54079716 -38.47367972
OS 53.52785332 -38.48292532
OS 53.51306036 -38.49309548
OS 53.49641828 -38.50326564
OS 53.49549372 -38.50326564
OS 53.49456916 -38.5041902
OS 53.4890218 -38.50788844
OS 53.4797762 -38.51251124
OS 53.46868148 -38.5180586
OS 53.45573764 -38.52453052
OS 53.44186924 -38.53100244
OS 53.42800084 -38.53747436
OS 53.41413244 -38.54302172
OS 53.41413244 -38.4672078
OS 53.415057 -38.4672078
OS 53.41690612 -38.46535868
OS 53.42060436 -38.46443412
OS 53.42522716 -38.46166044
OS 53.43077452 -38.45888676
OS 53.43724644 -38.45518852
OS 53.45296396 -38.44594292
OS 53.47145516 -38.43577276
OS 53.48994636 -38.42282892
OS 53.50936212 -38.40803596
OS 53.52877788 -38.39231844
OS 53.52970244 -38.39139388
OS 53.530627 -38.39046932
OS 53.53340068 -38.38769564
OS 53.53709892 -38.38492196
OS 53.54541996 -38.37567636
OS 53.55651468 -38.36458164
OS 53.5676094 -38.3516378
OS 53.57962868 -38.33684484
OS 53.58979884 -38.32205188
OS 53.59904444 -38.30633436
OS 53.64989524 -38.30633436
OS 53.64989524 -38.94890356
OE
OB 54.07334372 -38.30725892 I
OS 54.0807402 -38.30818348
OS 54.08906124 -38.30910804
OS 54.09830684 -38.3100326
OS 54.10755244 -38.31280628
OS 54.12974188 -38.31835364
OS 54.15193132 -38.32667468
OS 54.16302604 -38.33222204
OS 54.17412076 -38.33869396
OS 54.18429092 -38.347015
OS 54.19446108 -38.35533604
OS 54.19538564 -38.3562606
OS 54.1963102 -38.35718516
OS 54.19908388 -38.35995884
OS 54.20278212 -38.36365708
OS 54.20648036 -38.36920444
OS 54.21110316 -38.3747518
OS 54.22034876 -38.3886202
OS 54.22959436 -38.40618684
OS 54.2379154 -38.42652716
OS 54.24438732 -38.44964116
OS 54.24531188 -38.46166044
OS 54.24623644 -38.47460428
OS 54.24623644 -38.47552884
OS 54.24623644 -38.4764534
OS 54.24623644 -38.48200076
OS 54.24531188 -38.4903218
OS 54.24346276 -38.50049196
OS 54.24068908 -38.5134358
OS 54.23606628 -38.52637964
OS 54.23051892 -38.53932348
OS 54.22219788 -38.55226732
OS 54.22127332 -38.55411644
OS 54.21757508 -38.55781468
OS 54.21202772 -38.56336204
OS 54.20463124 -38.57075852
OS 54.19446108 -38.57907956
OS 54.1824418 -38.5874006
OS 54.1685734 -38.59572164
OS 54.15193132 -38.60311812
OS 54.15285588 -38.60311812
OS 54.154705 -38.60404268
OS 54.15747868 -38.60496724
OS 54.16117692 -38.60681636
OS 54.17227164 -38.61143916
OS 54.18521548 -38.61791108
OS 54.19908388 -38.62715668
OS 54.21387684 -38.63732684
OS 54.22774524 -38.65027068
OS 54.24068908 -38.66506364
OS 54.24068908 -38.6659882
OS 54.24161364 -38.66691276
OS 54.24531188 -38.67246012
OS 54.25085924 -38.68170572
OS 54.2564066 -38.693725
OS 54.26195396 -38.70851796
OS 54.26750132 -38.7260846
OS 54.27119956 -38.74550036
OS 54.27212412 -38.76676524
OS 54.27212412 -38.7676898
OS 54.27212412 -38.77046348
OS 54.27212412 -38.77508628
OS 54.27119956 -38.78063364
OS 54.270275 -38.78710556
OS 54.26935044 -38.7954266
OS 54.26750132 -38.8046722
OS 54.26472764 -38.81484236
OS 54.25825572 -38.83610724
OS 54.25363292 -38.84812652
OS 54.247161 -38.85922124
OS 54.24068908 -38.87124052
OS 54.2332926 -38.88233524
OS 54.224047 -38.89342996
OS 54.21387684 -38.90452468
OS 54.21295228 -38.90544924
OS 54.21110316 -38.90729836
OS 54.20832948 -38.91007204
OS 54.20370668 -38.91284572
OS 54.19723476 -38.91746852
OS 54.19076284 -38.92209132
OS 54.1824418 -38.92671412
OS 54.1731962 -38.93226148
OS 54.16302604 -38.93780884
OS 54.15100676 -38.94243164
OS 54.13806292 -38.94705444
OS 54.12511908 -38.95167724
OS 54.11032612 -38.95445092
OS 54.0946086 -38.9572246
OS 54.07889108 -38.95907372
OS 54.06132444 -38.95999828
OS 54.05207884 -38.95999828
OS 54.04560692 -38.95907372
OS 54.03728588 -38.95814916
OS 54.02804028 -38.9572246
OS 54.01787012 -38.95537548
OS 54.0067754 -38.9526018
OS 53.98181228 -38.94612988
OS 53.96886844 -38.94150708
OS 53.95684916 -38.93688428
OS 53.94390532 -38.93041236
OS 53.93096148 -38.92301588
OS 53.9189422 -38.91469484
OS 53.90784748 -38.90452468
OS 53.90692292 -38.90360012
OS 53.9050738 -38.901751
OS 53.90230012 -38.89897732
OS 53.89860188 -38.89435452
OS 53.89490364 -38.88880716
OS 53.88935628 -38.88233524
OS 53.88473348 -38.87493876
OS 53.87918612 -38.86569316
OS 53.87363876 -38.85644756
OS 53.86901596 -38.84535284
OS 53.85977036 -38.82223884
OS 53.85607212 -38.80837044
OS 53.85329844 -38.79450204
OS 53.85144932 -38.77970908
OS 53.85052476 -38.76491612
OS 53.85052476 -38.76399156
OS 53.85052476 -38.76214244
OS 53.85052476 -38.7584442
OS 53.85144932 -38.75474596
OS 53.85144932 -38.7491986
OS 53.85237388 -38.74272668
OS 53.854223 -38.72793372
OS 53.85792124 -38.71129164
OS 53.8634686 -38.69464956
OS 53.87178964 -38.67708292
OS 53.8819598 -38.66044084
OS 53.8819598 -38.65951628
OS 53.88380892 -38.65859172
OS 53.88750716 -38.65396892
OS 53.89490364 -38.64657244
OS 53.9050738 -38.63732684
OS 53.91801764 -38.62808124
OS 53.93373516 -38.61791108
OS 53.9513018 -38.60959004
OS 53.97256668 -38.60311812
OS 53.97164212 -38.60311812
OS 53.97071756 -38.60219356
OS 53.96794388 -38.601269
OS 53.96424564 -38.59941988
OS 53.9559246 -38.59572164
OS 53.94482988 -38.59017428
OS 53.9328106 -38.5827778
OS 53.92079132 -38.5735322
OS 53.9096966 -38.56336204
OS 53.89952644 -38.55226732
OS 53.89860188 -38.5504182
OS 53.8958282 -38.54671996
OS 53.89212996 -38.53932348
OS 53.88843172 -38.53007788
OS 53.88380892 -38.5180586
OS 53.88011068 -38.5041902
OS 53.877337 -38.48847268
OS 53.87641244 -38.4718306
OS 53.87641244 -38.47090604
OS 53.87641244 -38.46905692
OS 53.87641244 -38.46535868
OS 53.877337 -38.45981132
OS 53.87826156 -38.45426396
OS 53.87918612 -38.44686748
OS 53.88288436 -38.43114996
OS 53.88843172 -38.41265876
OS 53.89767732 -38.393243
OS 53.90322468 -38.38307284
OS 53.9096966 -38.37290268
OS 53.91801764 -38.36365708
OS 53.92633868 -38.35441148
OS 53.92726324 -38.35348692
OS 53.92911236 -38.35256236
OS 53.93188604 -38.34978868
OS 53.93558428 -38.347015
OS 53.94020708 -38.34331676
OS 53.946679 -38.33961852
OS 53.95407548 -38.33499572
OS 53.96147196 -38.33037292
OS 53.97071756 -38.32575012
OS 53.98088772 -38.32112732
OS 53.99198244 -38.31742908
OS 54.00400172 -38.31373084
OS 54.0298894 -38.30818348
OS 54.04468236 -38.30725892
OS 54.05947532 -38.30633436
OS 54.06779636 -38.30633436
OS 54.07334372 -38.30725892
OE
OB 53.23846604 -38.94890356 I
OS 53.14878372 -38.94890356
OS 53.14878372 -38.85922124
OS 53.23846604 -38.85922124
OS 53.23846604 -38.94890356
OE
OB 53.00177868 -38.39231844 I
OS 52.74567556 -38.39231844
OS 52.71146684 -38.56521116
OS 52.7123914 -38.5642866
OS 52.71424052 -38.56336204
OS 52.7170142 -38.56151292
OS 52.721637 -38.55873924
OS 52.72718436 -38.55596556
OS 52.73365628 -38.55226732
OS 52.74844924 -38.54487084
OS 52.76694044 -38.53747436
OS 52.78728076 -38.53100244
OS 52.8094702 -38.52637964
OS 52.82056492 -38.52453052
OS 52.84090524 -38.52453052
OS 52.8464526 -38.52545508
OS 52.85384908 -38.52637964
OS 52.86217012 -38.5273042
OS 52.87141572 -38.52915332
OS 52.88158588 -38.531927
OS 52.90377532 -38.53839892
OS 52.9157946 -38.54302172
OS 52.92781388 -38.54949364
OS 52.93983316 -38.55596556
OS 52.95185244 -38.56336204
OS 52.96294716 -38.57260764
OS 52.97404188 -38.5827778
OS 52.97496644 -38.58370236
OS 52.97681556 -38.58555148
OS 52.97958924 -38.58832516
OS 52.98328748 -38.59294796
OS 52.98791028 -38.59941988
OS 52.99253308 -38.6058918
OS 52.99808044 -38.61421284
OS 53.0036278 -38.62345844
OS 53.0082506 -38.6336286
OS 53.01379796 -38.64472332
OS 53.01842076 -38.65766716
OS 53.02304356 -38.670611
OS 53.0267418 -38.6844794
OS 53.02951548 -38.70019692
OS 53.0313646 -38.71591444
OS 53.03228916 -38.73255652
OS 53.03228916 -38.73348108
OS 53.03228916 -38.73625476
OS 53.03228916 -38.74087756
OS 53.0313646 -38.74734948
OS 53.03044004 -38.75474596
OS 53.02951548 -38.763067
OS 53.02766636 -38.77323716
OS 53.02581724 -38.78340732
OS 53.02026988 -38.80744588
OS 53.01102428 -38.832409
OS 53.00547692 -38.84535284
OS 52.99808044 -38.85737212
OS 52.99068396 -38.87031596
OS 52.98143836 -38.88233524
OS 52.9805138 -38.8832598
OS 52.97866468 -38.88603348
OS 52.97496644 -38.88973172
OS 52.97034364 -38.89435452
OS 52.96387172 -38.89990188
OS 52.95647524 -38.90729836
OS 52.94722964 -38.91377028
OS 52.93705948 -38.92116676
OS 52.92596476 -38.92856324
OS 52.91302092 -38.93503516
OS 52.89915252 -38.94150708
OS 52.88435956 -38.947979
OS 52.86864204 -38.9526018
OS 52.8510754 -38.95630004
OS 52.8325842 -38.95907372
OS 52.81316844 -38.95999828
OS 52.8048474 -38.95999828
OS 52.79837548 -38.95907372
OS 52.790979 -38.95814916
OS 52.78265796 -38.9572246
OS 52.7724878 -38.95630004
OS 52.76231764 -38.95352636
OS 52.73920364 -38.947979
OS 52.71608964 -38.93965796
OS 52.70407036 -38.9341106
OS 52.69205108 -38.92763868
OS 52.68095636 -38.9202422
OS 52.66986164 -38.91192116
OS 52.66893708 -38.9109966
OS 52.66708796 -38.91007204
OS 52.66523884 -38.9063738
OS 52.6615406 -38.90267556
OS 52.6569178 -38.89805276
OS 52.652295 -38.8925054
OS 52.64674764 -38.88510892
OS 52.64212484 -38.87678788
OS 52.63657748 -38.86846684
OS 52.63103012 -38.85829668
OS 52.62085996 -38.83610724
OS 52.61253892 -38.81021956
OS 52.60976524 -38.79635116
OS 52.60791612 -38.7815582
OS 52.69020196 -38.77508628
OS 52.69020196 -38.77601084
OS 52.69020196 -38.77785996
OS 52.69112652 -38.78063364
OS 52.69205108 -38.78525644
OS 52.69482476 -38.7954266
OS 52.698523 -38.809295
OS 52.70407036 -38.8231634
OS 52.71146684 -38.83888092
OS 52.72071244 -38.85274932
OS 52.73180716 -38.86569316
OS 52.73365628 -38.86661772
OS 52.73735452 -38.87031596
OS 52.744751 -38.87493876
OS 52.75492116 -38.88048612
OS 52.76601588 -38.88603348
OS 52.77988428 -38.89065628
OS 52.7956018 -38.89435452
OS 52.81316844 -38.89527908
OS 52.8187158 -38.89527908
OS 52.82241404 -38.89435452
OS 52.83350876 -38.89342996
OS 52.8464526 -38.88973172
OS 52.86217012 -38.88510892
OS 52.87788764 -38.87771244
OS 52.89452972 -38.86661772
OS 52.9019262 -38.8601458
OS 52.90932268 -38.85274932
OS 52.91024724 -38.85182476
OS 52.9111718 -38.8509002
OS 52.91302092 -38.84812652
OS 52.9157946 -38.84535284
OS 52.92226652 -38.83518268
OS 52.929663 -38.82223884
OS 52.93613492 -38.80652132
OS 52.94260684 -38.78710556
OS 52.94722964 -38.76399156
OS 52.94907876 -38.75197228
OS 52.94907876 -38.73902844
OS 52.94907876 -38.73810388
OS 52.94907876 -38.73625476
OS 52.94907876 -38.73255652
OS 52.9481542 -38.72793372
OS 52.9481542 -38.72238636
OS 52.94722964 -38.71591444
OS 52.94445596 -38.70112148
OS 52.93983316 -38.68355484
OS 52.93336124 -38.6659882
OS 52.92411564 -38.64934612
OS 52.9111718 -38.6336286
OS 52.9111718 -38.63270404
OS 52.90932268 -38.63177948
OS 52.90469988 -38.62715668
OS 52.89637884 -38.62068476
OS 52.88528412 -38.61328828
OS 52.87049116 -38.60681636
OS 52.85384908 -38.60034444
OS 52.83443332 -38.59572164
OS 52.8233386 -38.59387252
OS 52.80577196 -38.59387252
OS 52.79837548 -38.59479708
OS 52.78912988 -38.59572164
OS 52.77803516 -38.59849532
OS 52.76694044 -38.601269
OS 52.75492116 -38.6058918
OS 52.74290188 -38.61143916
OS 52.74197732 -38.61236372
OS 52.73827908 -38.61421284
OS 52.73273172 -38.61883564
OS 52.72533524 -38.62345844
OS 52.71793876 -38.62993036
OS 52.71054228 -38.6382514
OS 52.70222124 -38.64657244
OS 52.69574932 -38.6567426
OS 52.62178452 -38.64657244
OS 52.68373004 -38.31742908
OS 53.00177868 -38.31742908
OS 53.00177868 -38.39231844
OE
OB 53.23846604 -38.57445676 I
OS 53.14878372 -38.57445676
OS 53.14878372 -38.48477444
OS 53.23846604 -38.48477444
OS 53.23846604 -38.57445676
OE
OB 54.48199924 -38.57445676 I
OS 54.39231692 -38.57445676
OS 54.39231692 -38.48477444
OS 54.48199924 -38.48477444
OS 54.48199924 -38.57445676
OE
OB 56.14990548 -38.3100326 I
OS 56.165623 -38.31095716
OS 56.18226508 -38.31188172
OS 56.1979826 -38.31373084
OS 56.211851 -38.31557996
OS 56.21370012 -38.31557996
OS 56.22017204 -38.31742908
OS 56.22849308 -38.3192782
OS 56.2395878 -38.32205188
OS 56.25160708 -38.32667468
OS 56.26455092 -38.33222204
OS 56.27841932 -38.33869396
OS 56.2904386 -38.34609044
OS 56.29228772 -38.347015
OS 56.29598596 -38.34978868
OS 56.30153332 -38.35533604
OS 56.3089298 -38.36180796
OS 56.31725084 -38.370129
OS 56.32557188 -38.38122372
OS 56.33481748 -38.393243
OS 56.34221396 -38.4071114
OS 56.34313852 -38.40896052
OS 56.34498764 -38.41358332
OS 56.34868588 -38.42190436
OS 56.35238412 -38.43299908
OS 56.3551578 -38.44594292
OS 56.35885604 -38.46073588
OS 56.36070516 -38.47737796
OS 56.36162972 -38.4949446
OS 56.36162972 -38.49586916
OS 56.36162972 -38.49864284
OS 56.36162972 -38.50234108
OS 56.36070516 -38.508813
OS 56.3597806 -38.51528492
OS 56.35885604 -38.52360596
OS 56.35700692 -38.53285156
OS 56.3551578 -38.54302172
OS 56.34868588 -38.5642866
OS 56.34498764 -38.57538132
OS 56.33944028 -38.5874006
OS 56.33296836 -38.59941988
OS 56.32649644 -38.6105146
OS 56.3181754 -38.62160932
OS 56.3089298 -38.63270404
OS 56.30800524 -38.6336286
OS 56.30615612 -38.63547772
OS 56.30338244 -38.6382514
OS 56.29875964 -38.64102508
OS 56.29321228 -38.64564788
OS 56.2858158 -38.65027068
OS 56.2765702 -38.65581804
OS 56.26640004 -38.66044084
OS 56.25438076 -38.6659882
OS 56.24051236 -38.67153556
OS 56.2257194 -38.67615836
OS 56.20815276 -38.6798566
OS 56.18966156 -38.68355484
OS 56.16932124 -38.68632852
OS 56.14620724 -38.68817764
OS 56.12216868 -38.6891022
OS 55.95852156 -38.6891022
OS 55.95852156 -38.94890356
OS 55.87346204 -38.94890356
OS 55.87346204 -38.30910804
OS 56.13603708 -38.30910804
OS 56.14990548 -38.3100326
OE
OB 57.07723916 -38.94890356 I
OS 56.99587788 -38.94890356
OS 56.99587788 -38.41358332
OS 56.80911676 -38.94890356
OS 56.73330284 -38.94890356
OS 56.54839084 -38.40433772
OS 56.54839084 -38.94890356
OS 56.46702956 -38.94890356
OS 56.46702956 -38.30910804
OS 56.59369428 -38.30910804
OS 56.74532212 -38.763067
OS 56.74532212 -38.76399156
OS 56.74624668 -38.76584068
OS 56.74717124 -38.76861436
OS 56.74902036 -38.77323716
OS 56.7527186 -38.78433188
OS 56.7573414 -38.79820028
OS 56.7619642 -38.8139178
OS 56.76751156 -38.82963532
OS 56.77213436 -38.84442828
OS 56.7758326 -38.85737212
OS 56.77675716 -38.855523
OS 56.77768172 -38.8509002
OS 56.7804554 -38.84257916
OS 56.78415364 -38.83148444
OS 56.78877644 -38.81669148
OS 56.79524836 -38.79912484
OS 56.80172028 -38.77878452
OS 56.81004132 -38.75474596
OS 56.96351828 -38.30910804
OS 57.07723916 -38.30910804
OS 57.07723916 -38.94890356
OE
OB 55.39084172 -38.94890356 I
OS 55.31225412 -38.94890356
OS 55.31225412 -38.4487166
OS 55.31132956 -38.44964116
OS 55.30670676 -38.4533394
OS 55.3011594 -38.45888676
OS 55.2919138 -38.46535868
OS 55.28174364 -38.47367972
OS 55.2687998 -38.48292532
OS 55.25400684 -38.49309548
OS 55.23736476 -38.50326564
OS 55.2364402 -38.50326564
OS 55.23551564 -38.5041902
OS 55.22996828 -38.50788844
OS 55.22072268 -38.51251124
OS 55.20962796 -38.5180586
OS 55.19668412 -38.52453052
OS 55.18281572 -38.53100244
OS 55.16894732 -38.53747436
OS 55.15507892 -38.54302172
OS 55.15507892 -38.4672078
OS 55.15600348 -38.4672078
OS 55.1578526 -38.46535868
OS 55.16155084 -38.46443412
OS 55.16617364 -38.46166044
OS 55.171721 -38.45888676
OS 55.17819292 -38.45518852
OS 55.19391044 -38.44594292
OS 55.21240164 -38.43577276
OS 55.23089284 -38.42282892
OS 55.2503086 -38.40803596
OS 55.26972436 -38.39231844
OS 55.27064892 -38.39139388
OS 55.27157348 -38.39046932
OS 55.27434716 -38.38769564
OS 55.2780454 -38.38492196
OS 55.28636644 -38.37567636
OS 55.29746116 -38.36458164
OS 55.30855588 -38.3516378
OS 55.32057516 -38.33684484
OS 55.33074532 -38.32205188
OS 55.33999092 -38.30633436
OS 55.39084172 -38.30633436
OS 55.39084172 -38.94890356
OE
OB 54.48199924 -38.94890356 I
OS 54.39231692 -38.94890356
OS 54.39231692 -38.85922124
OS 54.48199924 -38.85922124
OS 54.48199924 -38.94890356
OE
OB 54.825011 -38.30725892 I
OS 54.83703028 -38.30910804
OS 54.85089868 -38.31188172
OS 54.86569164 -38.31557996
OS 54.88140916 -38.32020276
OS 54.89620212 -38.32759924
OS 54.89712668 -38.32759924
OS 54.89805124 -38.3285238
OS 54.90267404 -38.33129748
OS 54.91007052 -38.33592028
OS 54.91931612 -38.3423922
OS 54.92948628 -38.3516378
OS 54.940581 -38.36180796
OS 54.95075116 -38.37382724
OS 54.96092132 -38.38769564
OS 54.96184588 -38.38954476
OS 54.96554412 -38.39416756
OS 54.96924236 -38.4024886
OS 54.97571428 -38.41450788
OS 54.98126164 -38.42837628
OS 54.98865812 -38.4440938
OS 54.99513004 -38.462585
OS 55.0006774 -38.48292532
OS 55.0006774 -38.48384988
OS 55.00160196 -38.485699
OS 55.00252652 -38.48847268
OS 55.00345108 -38.49309548
OS 55.00437564 -38.49864284
OS 55.0053002 -38.50511476
OS 55.00714932 -38.5134358
OS 55.00807388 -38.5226814
OS 55.009923 -38.53285156
OS 55.01084756 -38.54394628
OS 55.01177212 -38.55689012
OS 55.01362124 -38.56983396
OS 55.0145458 -38.58462692
OS 55.0145458 -38.59941988
OS 55.01547036 -38.61606196
OS 55.01547036 -38.6336286
OS 55.01547036 -38.63455316
OS 55.01547036 -38.6382514
OS 55.01547036 -38.64472332
OS 55.01547036 -38.6521198
OS 55.0145458 -38.66228996
OS 55.0145458 -38.67338468
OS 55.01362124 -38.68540396
OS 55.01269668 -38.6983478
OS 55.009923 -38.72793372
OS 55.0053002 -38.7584442
OS 54.99975284 -38.78803012
OS 54.9960546 -38.80189852
OS 54.9914318 -38.81576692
OS 54.9914318 -38.81669148
OS 54.99050724 -38.8185406
OS 54.98865812 -38.82223884
OS 54.986809 -38.82686164
OS 54.98495988 -38.83333356
OS 54.98126164 -38.83980548
OS 54.97386516 -38.855523
OS 54.96461956 -38.87216508
OS 54.95260028 -38.89065628
OS 54.93873188 -38.90729836
OS 54.9220898 -38.92301588
OS 54.92116524 -38.92301588
OS 54.92024068 -38.924865
OS 54.917467 -38.92671412
OS 54.91376876 -38.92856324
OS 54.90914596 -38.93133692
OS 54.90452316 -38.93503516
OS 54.89065476 -38.94150708
OS 54.87401268 -38.947979
OS 54.85459692 -38.95445092
OS 54.83148292 -38.95814916
OS 54.8065198 -38.95999828
OS 54.7972742 -38.95999828
OS 54.79080228 -38.95907372
OS 54.7834058 -38.95814916
OS 54.7741602 -38.95630004
OS 54.76399004 -38.95445092
OS 54.75289532 -38.95167724
OS 54.7418006 -38.947979
OS 54.72978132 -38.94428076
OS 54.71776204 -38.9387334
OS 54.70574276 -38.93226148
OS 54.69372348 -38.924865
OS 54.6817042 -38.9156194
OS 54.67060948 -38.90544924
OS 54.66043932 -38.89435452
OS 54.65951476 -38.89342996
OS 54.65766564 -38.89065628
OS 54.65489196 -38.88603348
OS 54.65026916 -38.878637
OS 54.64564636 -38.87031596
OS 54.64102356 -38.85922124
OS 54.63455164 -38.8462774
OS 54.62900428 -38.83148444
OS 54.62345692 -38.81484236
OS 54.61790956 -38.7954266
OS 54.6123622 -38.77416172
OS 54.6077394 -38.75012316
OS 54.6031166 -38.72423548
OS 54.60034292 -38.69649868
OS 54.5984938 -38.6659882
OS 54.59756924 -38.6336286
OS 54.59756924 -38.63270404
OS 54.59756924 -38.6290058
OS 54.59756924 -38.62253388
OS 54.59756924 -38.6151374
OS 54.5984938 -38.60496724
OS 54.5984938 -38.59387252
OS 54.59941836 -38.58185324
OS 54.60034292 -38.56798484
OS 54.6031166 -38.53932348
OS 54.6077394 -38.508813
OS 54.61328676 -38.47830252
OS 54.616985 -38.46443412
OS 54.62068324 -38.45056572
OS 54.62068324 -38.44964116
OS 54.6216078 -38.44779204
OS 54.62345692 -38.4440938
OS 54.62530604 -38.439471
OS 54.62715516 -38.43299908
OS 54.6308534 -38.42652716
OS 54.63824988 -38.41080964
OS 54.64749548 -38.39416756
OS 54.65951476 -38.37660092
OS 54.67338316 -38.35903428
OS 54.69002524 -38.34424132
OS 54.6909498 -38.34424132
OS 54.69187436 -38.3423922
OS 54.69464804 -38.34054308
OS 54.69834628 -38.33869396
OS 54.70296908 -38.33499572
OS 54.70851644 -38.33222204
OS 54.72238484 -38.32482556
OS 54.73902692 -38.31835364
OS 54.75844268 -38.31188172
OS 54.78155668 -38.30818348
OS 54.8065198 -38.30633436
OS 54.81484084 -38.30633436
OS 54.825011 -38.30725892
OE
OB 49.95350436 -38.72331092 I
OS 50.040413 -38.72331092
OS 50.040413 -38.7954266
OS 49.95350436 -38.7954266
OS 49.95350436 -38.94890356
OS 49.87491676 -38.94890356
OS 49.87491676 -38.7954266
OS 49.5966242 -38.7954266
OS 49.5966242 -38.72331092
OS 49.88970972 -38.30910804
OS 49.95350436 -38.30910804
OS 49.95350436 -38.72331092
OE
OB 50.1467374 -38.95999828 I
OS 50.08386732 -38.95999828
OS 50.26970388 -38.29801332
OS 50.33257396 -38.29801332
OS 50.1467374 -38.95999828
OE
OB 50.59699812 -38.30725892 I
OS 50.6043946 -38.30818348
OS 50.6136402 -38.30910804
OS 50.62381036 -38.31095716
OS 50.63398052 -38.31280628
OS 50.65801908 -38.3192782
OS 50.68205764 -38.3285238
OS 50.69407692 -38.33407116
OS 50.7060962 -38.34054308
OS 50.71719092 -38.34886412
OS 50.72736108 -38.35810972
OS 50.72828564 -38.35903428
OS 50.73013476 -38.35995884
OS 50.73198388 -38.36365708
OS 50.73568212 -38.36735532
OS 50.74030492 -38.37197812
OS 50.74492772 -38.37845004
OS 50.74955052 -38.38492196
OS 50.75509788 -38.393243
OS 50.76434348 -38.41080964
OS 50.77358908 -38.43299908
OS 50.77728732 -38.4440938
OS 50.77913644 -38.45703764
OS 50.78098556 -38.46998148
OS 50.78191012 -38.48384988
OS 50.78191012 -38.485699
OS 50.78191012 -38.4903218
OS 50.78098556 -38.49771828
OS 50.780061 -38.50788844
OS 50.77821188 -38.51898316
OS 50.77451364 -38.531927
OS 50.7708154 -38.5457954
OS 50.76526804 -38.5596638
OS 50.76434348 -38.56151292
OS 50.76249436 -38.56613572
OS 50.75879612 -38.5735322
OS 50.75324876 -38.58370236
OS 50.74585228 -38.59479708
OS 50.73660668 -38.60866548
OS 50.72551196 -38.62253388
OS 50.71256812 -38.6382514
OS 50.710719 -38.64010052
OS 50.7060962 -38.64564788
OS 50.7014734 -38.65027068
OS 50.6968506 -38.65489348
OS 50.69130324 -38.66044084
OS 50.68390676 -38.66783732
OS 50.67651028 -38.6752338
OS 50.66726468 -38.68355484
OS 50.65801908 -38.69280044
OS 50.64692436 -38.7029706
OS 50.63490508 -38.71314076
OS 50.62196124 -38.72516004
OS 50.60716828 -38.73717932
OS 50.59237532 -38.75012316
OS 50.59145076 -38.75104772
OS 50.58960164 -38.75289684
OS 50.5859034 -38.75567052
OS 50.5812806 -38.75936876
OS 50.57573324 -38.76491612
OS 50.56926132 -38.77046348
OS 50.55446836 -38.78248276
OS 50.53875084 -38.79635116
OS 50.52395788 -38.81021956
OS 50.51101404 -38.82223884
OS 50.50546668 -38.82686164
OS 50.50084388 -38.83148444
OS 50.49991932 -38.832409
OS 50.49714564 -38.83518268
OS 50.4934474 -38.83888092
OS 50.4888246 -38.84442828
OS 50.4842018 -38.8509002
OS 50.47865444 -38.85737212
OS 50.46755972 -38.87308964
OS 50.78283468 -38.87308964
OS 50.78283468 -38.94890356
OS 50.35846164 -38.94890356
OS 50.35846164 -38.947979
OS 50.35846164 -38.94428076
OS 50.35846164 -38.9387334
OS 50.3593862 -38.93133692
OS 50.36031076 -38.92301588
OS 50.36215988 -38.91377028
OS 50.364009 -38.90452468
OS 50.36770724 -38.89435452
OS 50.36770724 -38.89342996
OS 50.3686318 -38.8925054
OS 50.37048092 -38.88695804
OS 50.37417916 -38.878637
OS 50.37972652 -38.86754228
OS 50.387123 -38.85459844
OS 50.3963686 -38.83980548
OS 50.40653876 -38.82501252
OS 50.4194826 -38.809295
OS 50.4194826 -38.80837044
OS 50.42133172 -38.80744588
OS 50.42595452 -38.80189852
OS 50.43427556 -38.79357748
OS 50.44629484 -38.7815582
OS 50.46016324 -38.7676898
OS 50.47772988 -38.75104772
OS 50.49899476 -38.73255652
OS 50.52210876 -38.71314076
OS 50.52303332 -38.7122162
OS 50.52673156 -38.70944252
OS 50.53227892 -38.70481972
OS 50.53875084 -38.69927236
OS 50.54707188 -38.69187588
OS 50.55724204 -38.68355484
OS 50.5674122 -38.67430924
OS 50.57943148 -38.66413908
OS 50.60254548 -38.64194964
OS 50.62565948 -38.6197602
OS 50.6367542 -38.60866548
OS 50.64692436 -38.59757076
OS 50.65616996 -38.5874006
OS 50.66356644 -38.57723044
OS 50.66356644 -38.57630588
OS 50.66541556 -38.57538132
OS 50.66726468 -38.57260764
OS 50.6691138 -38.5689094
OS 50.67558572 -38.55873924
OS 50.6829822 -38.54671996
OS 50.68945412 -38.531927
OS 50.69592604 -38.51620948
OS 50.69962428 -38.49864284
OS 50.7014734 -38.48200076
OS 50.7014734 -38.4810762
OS 50.7014734 -38.48015164
OS 50.70054884 -38.47460428
OS 50.69962428 -38.46535868
OS 50.6968506 -38.45518852
OS 50.69315236 -38.44224468
OS 50.68668044 -38.42930084
OS 50.6783594 -38.416357
OS 50.66726468 -38.40341316
OS 50.66541556 -38.40156404
OS 50.66079276 -38.3978658
OS 50.65432084 -38.393243
OS 50.64415068 -38.38677108
OS 50.63120684 -38.38122372
OS 50.61641388 -38.37567636
OS 50.59884724 -38.37197812
OS 50.57943148 -38.37105356
OS 50.57388412 -38.37105356
OS 50.57018588 -38.37197812
OS 50.55909116 -38.37290268
OS 50.54614732 -38.37567636
OS 50.53227892 -38.3793746
OS 50.5165614 -38.38584652
OS 50.50176844 -38.39416756
OS 50.48790004 -38.40526228
OS 50.48605092 -38.4071114
OS 50.48235268 -38.4117342
OS 50.47680532 -38.41913068
OS 50.47125796 -38.4302254
OS 50.46478604 -38.44316924
OS 50.45923868 -38.45981132
OS 50.45554044 -38.47830252
OS 50.45369132 -38.4995674
OS 50.3732546 -38.49124636
OS 50.3732546 -38.4903218
OS 50.37417916 -38.48754812
OS 50.37417916 -38.48292532
OS 50.37510372 -38.4764534
OS 50.37695284 -38.46905692
OS 50.37880196 -38.46073588
OS 50.38157564 -38.45056572
OS 50.38434932 -38.44039556
OS 50.3917458 -38.41820612
OS 50.40284052 -38.39601668
OS 50.40931244 -38.38492196
OS 50.41763348 -38.37382724
OS 50.42595452 -38.36365708
OS 50.43520012 -38.35441148
OS 50.43612468 -38.35348692
OS 50.4379738 -38.35256236
OS 50.44074748 -38.34978868
OS 50.44537028 -38.347015
OS 50.45091764 -38.34331676
OS 50.45738956 -38.33961852
OS 50.46478604 -38.33499572
OS 50.47403164 -38.33037292
OS 50.4842018 -38.32575012
OS 50.49529652 -38.32112732
OS 50.5073158 -38.31742908
OS 50.52025964 -38.31373084
OS 50.53412804 -38.31095716
OS 50.548921 -38.30818348
OS 50.56463852 -38.30725892
OS 50.5812806 -38.30633436
OS 50.5905262 -38.30633436
OS 50.59699812 -38.30725892
OE
OB 48.67576244 -38.94890356 I
OS 48.59717484 -38.94890356
OS 48.59717484 -38.4487166
OS 48.59625028 -38.44964116
OS 48.59162748 -38.4533394
OS 48.58608012 -38.45888676
OS 48.57683452 -38.46535868
OS 48.56666436 -38.47367972
OS 48.55372052 -38.48292532
OS 48.53892756 -38.49309548
OS 48.52228548 -38.50326564
OS 48.52136092 -38.50326564
OS 48.52043636 -38.5041902
OS 48.514889 -38.50788844
OS 48.5056434 -38.51251124
OS 48.49454868 -38.5180586
OS 48.48160484 -38.52453052
OS 48.46773644 -38.53100244
OS 48.45386804 -38.53747436
OS 48.43999964 -38.54302172
OS 48.43999964 -38.4672078
OS 48.4409242 -38.4672078
OS 48.44277332 -38.46535868
OS 48.44647156 -38.46443412
OS 48.45109436 -38.46166044
OS 48.45664172 -38.45888676
OS 48.46311364 -38.45518852
OS 48.47883116 -38.44594292
OS 48.49732236 -38.43577276
OS 48.51581356 -38.42282892
OS 48.53522932 -38.40803596
OS 48.55464508 -38.39231844
OS 48.55556964 -38.39139388
OS 48.5564942 -38.39046932
OS 48.55926788 -38.38769564
OS 48.56296612 -38.38492196
OS 48.57128716 -38.37567636
OS 48.58238188 -38.36458164
OS 48.5934766 -38.3516378
OS 48.60549588 -38.33684484
OS 48.61566604 -38.32205188
OS 48.62491164 -38.30633436
OS 48.67576244 -38.30633436
OS 48.67576244 -38.94890356
OE
OB 48.9032042 -38.95999828 I
OS 48.84033412 -38.95999828
OS 49.02617068 -38.29801332
OS 49.08904076 -38.29801332
OS 48.9032042 -38.95999828
OE
OB 49.35346492 -38.30725892 I
OS 49.3608614 -38.30818348
OS 49.370107 -38.30910804
OS 49.38027716 -38.31095716
OS 49.39044732 -38.31280628
OS 49.41448588 -38.3192782
OS 49.43852444 -38.3285238
OS 49.45054372 -38.33407116
OS 49.462563 -38.34054308
OS 49.47365772 -38.34886412
OS 49.48382788 -38.35810972
OS 49.48475244 -38.35903428
OS 49.48660156 -38.35995884
OS 49.48845068 -38.36365708
OS 49.49214892 -38.36735532
OS 49.49677172 -38.37197812
OS 49.50139452 -38.37845004
OS 49.50601732 -38.38492196
OS 49.51156468 -38.393243
OS 49.52081028 -38.41080964
OS 49.53005588 -38.43299908
OS 49.53375412 -38.4440938
OS 49.53560324 -38.45703764
OS 49.53745236 -38.46998148
OS 49.53837692 -38.48384988
OS 49.53837692 -38.485699
OS 49.53837692 -38.4903218
OS 49.53745236 -38.49771828
OS 49.5365278 -38.50788844
OS 49.53467868 -38.51898316
OS 49.53098044 -38.531927
OS 49.5272822 -38.5457954
OS 49.52173484 -38.5596638
OS 49.52081028 -38.56151292
OS 49.51896116 -38.56613572
OS 49.51526292 -38.5735322
OS 49.50971556 -38.58370236
OS 49.50231908 -38.59479708
OS 49.49307348 -38.60866548
OS 49.48197876 -38.62253388
OS 49.46903492 -38.6382514
OS 49.4671858 -38.64010052
OS 49.462563 -38.64564788
OS 49.4579402 -38.65027068
OS 49.4533174 -38.65489348
OS 49.44777004 -38.66044084
OS 49.44037356 -38.66783732
OS 49.43297708 -38.6752338
OS 49.42373148 -38.68355484
OS 49.41448588 -38.69280044
OS 49.40339116 -38.7029706
OS 49.39137188 -38.71314076
OS 49.37842804 -38.72516004
OS 49.36363508 -38.73717932
OS 49.34884212 -38.75012316
OS 49.34791756 -38.75104772
OS 49.34606844 -38.75289684
OS 49.3423702 -38.75567052
OS 49.3377474 -38.75936876
OS 49.33220004 -38.76491612
OS 49.32572812 -38.77046348
OS 49.31093516 -38.78248276
OS 49.29521764 -38.79635116
OS 49.28042468 -38.81021956
OS 49.26748084 -38.82223884
OS 49.26193348 -38.82686164
OS 49.25731068 -38.83148444
OS 49.25638612 -38.832409
OS 49.25361244 -38.83518268
OS 49.2499142 -38.83888092
OS 49.2452914 -38.84442828
OS 49.2406686 -38.8509002
OS 49.23512124 -38.85737212
OS 49.22402652 -38.87308964
OS 49.53930148 -38.87308964
OS 49.53930148 -38.94890356
OS 49.11492844 -38.94890356
OS 49.11492844 -38.947979
OS 49.11492844 -38.94428076
OS 49.11492844 -38.9387334
OS 49.115853 -38.93133692
OS 49.11677756 -38.92301588
OS 49.11862668 -38.91377028
OS 49.1204758 -38.90452468
OS 49.12417404 -38.89435452
OS 49.12417404 -38.89342996
OS 49.1250986 -38.8925054
OS 49.12694772 -38.88695804
OS 49.13064596 -38.878637
OS 49.13619332 -38.86754228
OS 49.1435898 -38.85459844
OS 49.1528354 -38.83980548
OS 49.16300556 -38.82501252
OS 49.1759494 -38.809295
OS 49.1759494 -38.80837044
OS 49.17779852 -38.80744588
OS 49.18242132 -38.80189852
OS 49.19074236 -38.79357748
OS 49.20276164 -38.7815582
OS 49.21663004 -38.7676898
OS 49.23419668 -38.75104772
OS 49.25546156 -38.73255652
OS 49.27857556 -38.71314076
OS 49.27950012 -38.7122162
OS 49.28319836 -38.70944252
OS 49.28874572 -38.70481972
OS 49.29521764 -38.69927236
OS 49.30353868 -38.69187588
OS 49.31370884 -38.68355484
OS 49.323879 -38.67430924
OS 49.33589828 -38.66413908
OS 49.35901228 -38.64194964
OS 49.38212628 -38.6197602
OS 49.393221 -38.60866548
OS 49.40339116 -38.59757076
OS 49.41263676 -38.5874006
OS 49.42003324 -38.57723044
OS 49.42003324 -38.57630588
OS 49.42188236 -38.57538132
OS 49.42373148 -38.57260764
OS 49.4255806 -38.5689094
OS 49.43205252 -38.55873924
OS 49.439449 -38.54671996
OS 49.44592092 -38.531927
OS 49.45239284 -38.51620948
OS 49.45609108 -38.49864284
OS 49.4579402 -38.48200076
OS 49.4579402 -38.4810762
OS 49.4579402 -38.48015164
OS 49.45701564 -38.47460428
OS 49.45609108 -38.46535868
OS 49.4533174 -38.45518852
OS 49.44961916 -38.44224468
OS 49.44314724 -38.42930084
OS 49.4348262 -38.416357
OS 49.42373148 -38.40341316
OS 49.42188236 -38.40156404
OS 49.41725956 -38.3978658
OS 49.41078764 -38.393243
OS 49.40061748 -38.38677108
OS 49.38767364 -38.38122372
OS 49.37288068 -38.37567636
OS 49.35531404 -38.37197812
OS 49.33589828 -38.37105356
OS 49.33035092 -38.37105356
OS 49.32665268 -38.37197812
OS 49.31555796 -38.37290268
OS 49.30261412 -38.37567636
OS 49.28874572 -38.3793746
OS 49.2730282 -38.38584652
OS 49.25823524 -38.39416756
OS 49.24436684 -38.40526228
OS 49.24251772 -38.4071114
OS 49.23881948 -38.4117342
OS 49.23327212 -38.41913068
OS 49.22772476 -38.4302254
OS 49.22125284 -38.44316924
OS 49.21570548 -38.45981132
OS 49.21200724 -38.47830252
OS 49.21015812 -38.4995674
OS 49.1297214 -38.49124636
OS 49.1297214 -38.4903218
OS 49.13064596 -38.48754812
OS 49.13064596 -38.48292532
OS 49.13157052 -38.4764534
OS 49.13341964 -38.46905692
OS 49.13526876 -38.46073588
OS 49.13804244 -38.45056572
OS 49.14081612 -38.44039556
OS 49.1482126 -38.41820612
OS 49.15930732 -38.39601668
OS 49.16577924 -38.38492196
OS 49.17410028 -38.37382724
OS 49.18242132 -38.36365708
OS 49.19166692 -38.35441148
OS 49.19259148 -38.35348692
OS 49.1944406 -38.35256236
OS 49.19721428 -38.34978868
OS 49.20183708 -38.347015
OS 49.20738444 -38.34331676
OS 49.21385636 -38.33961852
OS 49.22125284 -38.33499572
OS 49.23049844 -38.33037292
OS 49.2406686 -38.32575012
OS 49.25176332 -38.32112732
OS 49.2637826 -38.31742908
OS 49.27672644 -38.31373084
OS 49.29059484 -38.31095716
OS 49.3053878 -38.30818348
OS 49.32110532 -38.30725892
OS 49.3377474 -38.30633436
OS 49.346993 -38.30633436
OS 49.35346492 -38.30725892
OE
OB 51.0944114 -38.30725892 I
OS 51.10643068 -38.30910804
OS 51.12029908 -38.31188172
OS 51.13509204 -38.31557996
OS 51.15080956 -38.32020276
OS 51.16560252 -38.32759924
OS 51.16652708 -38.32759924
OS 51.16745164 -38.3285238
OS 51.17207444 -38.33129748
OS 51.17947092 -38.33592028
OS 51.18871652 -38.3423922
OS 51.19888668 -38.3516378
OS 51.2099814 -38.36180796
OS 51.22015156 -38.37382724
OS 51.23032172 -38.38769564
OS 51.23124628 -38.38954476
OS 51.23494452 -38.39416756
OS 51.23864276 -38.4024886
OS 51.24511468 -38.41450788
OS 51.25066204 -38.42837628
OS 51.25805852 -38.4440938
OS 51.26453044 -38.462585
OS 51.2700778 -38.48292532
OS 51.2700778 -38.48384988
OS 51.27100236 -38.485699
OS 51.27192692 -38.48847268
OS 51.27285148 -38.49309548
OS 51.27377604 -38.49864284
OS 51.2747006 -38.50511476
OS 51.27654972 -38.5134358
OS 51.27747428 -38.5226814
OS 51.2793234 -38.53285156
OS 51.28024796 -38.54394628
OS 51.28117252 -38.55689012
OS 51.28302164 -38.56983396
OS 51.2839462 -38.58462692
OS 51.2839462 -38.59941988
OS 51.28487076 -38.61606196
OS 51.28487076 -38.6336286
OS 51.28487076 -38.63455316
OS 51.28487076 -38.6382514
OS 51.28487076 -38.64472332
OS 51.28487076 -38.6521198
OS 51.2839462 -38.66228996
OS 51.2839462 -38.67338468
OS 51.28302164 -38.68540396
OS 51.28209708 -38.6983478
OS 51.2793234 -38.72793372
OS 51.2747006 -38.7584442
OS 51.26915324 -38.78803012
OS 51.265455 -38.80189852
OS 51.2608322 -38.81576692
OS 51.2608322 -38.81669148
OS 51.25990764 -38.8185406
OS 51.25805852 -38.82223884
OS 51.2562094 -38.82686164
OS 51.25436028 -38.83333356
OS 51.25066204 -38.83980548
OS 51.24326556 -38.855523
OS 51.23401996 -38.87216508
OS 51.22200068 -38.89065628
OS 51.20813228 -38.90729836
OS 51.1914902 -38.92301588
OS 51.19056564 -38.92301588
OS 51.18964108 -38.924865
OS 51.1868674 -38.92671412
OS 51.18316916 -38.92856324
OS 51.17854636 -38.93133692
OS 51.17392356 -38.93503516
OS 51.16005516 -38.94150708
OS 51.14341308 -38.947979
OS 51.12399732 -38.95445092
OS 51.10088332 -38.95814916
OS 51.0759202 -38.95999828
OS 51.0666746 -38.95999828
OS 51.06020268 -38.95907372
OS 51.0528062 -38.95814916
OS 51.0435606 -38.95630004
OS 51.03339044 -38.95445092
OS 51.02229572 -38.95167724
OS 51.011201 -38.947979
OS 50.99918172 -38.94428076
OS 50.98716244 -38.9387334
OS 50.97514316 -38.93226148
OS 50.96312388 -38.924865
OS 50.9511046 -38.9156194
OS 50.94000988 -38.90544924
OS 50.92983972 -38.89435452
OS 50.92891516 -38.89342996
OS 50.92706604 -38.89065628
OS 50.92429236 -38.88603348
OS 50.91966956 -38.878637
OS 50.91504676 -38.87031596
OS 50.91042396 -38.85922124
OS 50.90395204 -38.8462774
OS 50.89840468 -38.83148444
OS 50.89285732 -38.81484236
OS 50.88730996 -38.7954266
OS 50.8817626 -38.77416172
OS 50.8771398 -38.75012316
OS 50.872517 -38.72423548
OS 50.86974332 -38.69649868
OS 50.8678942 -38.6659882
OS 50.86696964 -38.6336286
OS 50.86696964 -38.63270404
OS 50.86696964 -38.6290058
OS 50.86696964 -38.62253388
OS 50.86696964 -38.6151374
OS 50.8678942 -38.60496724
OS 50.8678942 -38.59387252
OS 50.86881876 -38.58185324
OS 50.86974332 -38.56798484
OS 50.872517 -38.53932348
OS 50.8771398 -38.508813
OS 50.88268716 -38.47830252
OS 50.8863854 -38.46443412
OS 50.89008364 -38.45056572
OS 50.89008364 -38.44964116
OS 50.8910082 -38.44779204
OS 50.89285732 -38.4440938
OS 50.89470644 -38.439471
OS 50.89655556 -38.43299908
OS 50.9002538 -38.42652716
OS 50.90765028 -38.41080964
OS 50.91689588 -38.39416756
OS 50.92891516 -38.37660092
OS 50.94278356 -38.35903428
OS 50.95942564 -38.34424132
OS 50.9603502 -38.34424132
OS 50.96127476 -38.3423922
OS 50.96404844 -38.34054308
OS 50.96774668 -38.33869396
OS 50.97236948 -38.33499572
OS 50.97791684 -38.33222204
OS 50.99178524 -38.32482556
OS 51.00842732 -38.31835364
OS 51.02784308 -38.31188172
OS 51.05095708 -38.30818348
OS 51.0759202 -38.30633436
OS 51.08424124 -38.30633436
OS 51.0944114 -38.30725892
OE
OB 51.59182468 -38.30725892 I
OS 51.59922116 -38.30818348
OS 51.60846676 -38.30910804
OS 51.61863692 -38.31095716
OS 51.62880708 -38.31280628
OS 51.65284564 -38.3192782
OS 51.6768842 -38.3285238
OS 51.68890348 -38.33407116
OS 51.70092276 -38.34054308
OS 51.71201748 -38.34886412
OS 51.72218764 -38.35810972
OS 51.7231122 -38.35903428
OS 51.72496132 -38.35995884
OS 51.72681044 -38.36365708
OS 51.73050868 -38.36735532
OS 51.73513148 -38.37197812
OS 51.73975428 -38.37845004
OS 51.74437708 -38.38492196
OS 51.74992444 -38.393243
OS 51.75917004 -38.41080964
OS 51.76841564 -38.43299908
OS 51.77211388 -38.4440938
OS 51.773963 -38.45703764
OS 51.77581212 -38.46998148
OS 51.77673668 -38.48384988
OS 51.77673668 -38.485699
OS 51.77673668 -38.4903218
OS 51.77581212 -38.49771828
OS 51.77488756 -38.50788844
OS 51.77303844 -38.51898316
OS 51.7693402 -38.531927
OS 51.76564196 -38.5457954
OS 51.7600946 -38.5596638
OS 51.75917004 -38.56151292
OS 51.75732092 -38.56613572
OS 51.75362268 -38.5735322
OS 51.74807532 -38.58370236
OS 51.74067884 -38.59479708
OS 51.73143324 -38.60866548
OS 51.72033852 -38.62253388
OS 51.70739468 -38.6382514
OS 51.70554556 -38.64010052
OS 51.70092276 -38.64564788
OS 51.69629996 -38.65027068
OS 51.69167716 -38.65489348
OS 51.6861298 -38.66044084
OS 51.67873332 -38.66783732
OS 51.67133684 -38.6752338
OS 51.66209124 -38.68355484
OS 51.65284564 -38.69280044
OS 51.64175092 -38.7029706
OS 51.62973164 -38.71314076
OS 51.6167878 -38.72516004
OS 51.60199484 -38.73717932
OS 51.58720188 -38.75012316
OS 51.58627732 -38.75104772
OS 51.5844282 -38.75289684
OS 51.58072996 -38.75567052
OS 51.57610716 -38.75936876
OS 51.5705598 -38.76491612
OS 51.56408788 -38.77046348
OS 51.54929492 -38.78248276
OS 51.5335774 -38.79635116
OS 51.51878444 -38.81021956
OS 51.5058406 -38.82223884
OS 51.50029324 -38.82686164
OS 51.49567044 -38.83148444
OS 51.49474588 -38.832409
OS 51.4919722 -38.83518268
OS 51.48827396 -38.83888092
OS 51.48365116 -38.84442828
OS 51.47902836 -38.8509002
OS 51.473481 -38.85737212
OS 51.46238628 -38.87308964
OS 51.77766124 -38.87308964
OS 51.77766124 -38.94890356
OS 51.3532882 -38.94890356
OS 51.3532882 -38.947979
OS 51.3532882 -38.94428076
OS 51.3532882 -38.9387334
OS 51.35421276 -38.93133692
OS 51.35513732 -38.92301588
OS 51.35698644 -38.91377028
OS 51.35883556 -38.90452468
OS 51.3625338 -38.89435452
OS 51.3625338 -38.89342996
OS 51.36345836 -38.8925054
OS 51.36530748 -38.88695804
OS 51.36900572 -38.878637
OS 51.37455308 -38.86754228
OS 51.38194956 -38.85459844
OS 51.39119516 -38.83980548
OS 51.40136532 -38.82501252
OS 51.41430916 -38.809295
OS 51.41430916 -38.80837044
OS 51.41615828 -38.80744588
OS 51.42078108 -38.80189852
OS 51.42910212 -38.79357748
OS 51.4411214 -38.7815582
OS 51.4549898 -38.7676898
OS 51.47255644 -38.75104772
OS 51.49382132 -38.73255652
OS 51.51693532 -38.71314076
OS 51.51785988 -38.7122162
OS 51.52155812 -38.70944252
OS 51.52710548 -38.70481972
OS 51.5335774 -38.69927236
OS 51.54189844 -38.69187588
OS 51.5520686 -38.68355484
OS 51.56223876 -38.67430924
OS 51.57425804 -38.66413908
OS 51.59737204 -38.64194964
OS 51.62048604 -38.6197602
OS 51.63158076 -38.60866548
OS 51.64175092 -38.59757076
OS 51.65099652 -38.5874006
OS 51.658393 -38.57723044
OS 51.658393 -38.57630588
OS 51.66024212 -38.57538132
OS 51.66209124 -38.57260764
OS 51.66394036 -38.5689094
OS 51.67041228 -38.55873924
OS 51.67780876 -38.54671996
OS 51.68428068 -38.531927
OS 51.6907526 -38.51620948
OS 51.69445084 -38.49864284
OS 51.69629996 -38.48200076
OS 51.69629996 -38.4810762
OS 51.69629996 -38.48015164
OS 51.6953754 -38.47460428
OS 51.69445084 -38.46535868
OS 51.69167716 -38.45518852
OS 51.68797892 -38.44224468
OS 51.681507 -38.42930084
OS 51.67318596 -38.416357
OS 51.66209124 -38.40341316
OS 51.66024212 -38.40156404
OS 51.65561932 -38.3978658
OS 51.6491474 -38.393243
OS 51.63897724 -38.38677108
OS 51.6260334 -38.38122372
OS 51.61124044 -38.37567636
OS 51.5936738 -38.37197812
OS 51.57425804 -38.37105356
OS 51.56871068 -38.37105356
OS 51.56501244 -38.37197812
OS 51.55391772 -38.37290268
OS 51.54097388 -38.37567636
OS 51.52710548 -38.3793746
OS 51.51138796 -38.38584652
OS 51.496595 -38.39416756
OS 51.4827266 -38.40526228
OS 51.48087748 -38.4071114
OS 51.47717924 -38.4117342
OS 51.47163188 -38.41913068
OS 51.46608452 -38.4302254
OS 51.4596126 -38.44316924
OS 51.45406524 -38.45981132
OS 51.450367 -38.47830252
OS 51.44851788 -38.4995674
OS 51.36808116 -38.49124636
OS 51.36808116 -38.4903218
OS 51.36900572 -38.48754812
OS 51.36900572 -38.48292532
OS 51.36993028 -38.4764534
OS 51.3717794 -38.46905692
OS 51.37362852 -38.46073588
OS 51.3764022 -38.45056572
OS 51.37917588 -38.44039556
OS 51.38657236 -38.41820612
OS 51.39766708 -38.39601668
OS 51.404139 -38.38492196
OS 51.41246004 -38.37382724
OS 51.42078108 -38.36365708
OS 51.43002668 -38.35441148
OS 51.43095124 -38.35348692
OS 51.43280036 -38.35256236
OS 51.43557404 -38.34978868
OS 51.44019684 -38.347015
OS 51.4457442 -38.34331676
OS 51.45221612 -38.33961852
OS 51.4596126 -38.33499572
OS 51.4688582 -38.33037292
OS 51.47902836 -38.32575012
OS 51.49012308 -38.32112732
OS 51.50214236 -38.31742908
OS 51.5150862 -38.31373084
OS 51.5289546 -38.31095716
OS 51.54374756 -38.30818348
OS 51.55946508 -38.30725892
OS 51.57610716 -38.30633436
OS 51.58535276 -38.30633436
OS 51.59182468 -38.30725892
OE
OB 52.08184148 -38.30725892 I
OS 52.09386076 -38.30910804
OS 52.10865372 -38.31188172
OS 52.1252958 -38.31650452
OS 52.14193788 -38.32205188
OS 52.15857996 -38.32944836
OS 52.15950452 -38.32944836
OS 52.16042908 -38.33037292
OS 52.16597644 -38.3331466
OS 52.17429748 -38.33869396
OS 52.18354308 -38.34516588
OS 52.1946378 -38.35441148
OS 52.20573252 -38.36458164
OS 52.21682724 -38.37660092
OS 52.22607284 -38.39046932
OS 52.2269974 -38.39231844
OS 52.22977108 -38.39694124
OS 52.23346932 -38.40526228
OS 52.23809212 -38.41543244
OS 52.24271492 -38.42745172
OS 52.24641316 -38.44132012
OS 52.24918684 -38.45703764
OS 52.2501114 -38.47275516
OS 52.2501114 -38.47460428
OS 52.2501114 -38.48015164
OS 52.24918684 -38.48754812
OS 52.24733772 -38.49771828
OS 52.24456404 -38.50973756
OS 52.23994124 -38.5226814
OS 52.23439388 -38.53562524
OS 52.2269974 -38.54856908
OS 52.22607284 -38.5504182
OS 52.22329916 -38.55411644
OS 52.2177518 -38.56058836
OS 52.21035532 -38.56798484
OS 52.20110972 -38.57630588
OS 52.190015 -38.58555148
OS 52.17707116 -38.59387252
OS 52.16135364 -38.60219356
OS 52.1622782 -38.60219356
OS 52.16412732 -38.60311812
OS 52.166901 -38.60404268
OS 52.17059924 -38.60496724
OS 52.1807694 -38.60866548
OS 52.19371324 -38.61421284
OS 52.2085062 -38.62160932
OS 52.22329916 -38.63085492
OS 52.23716756 -38.6428742
OS 52.2501114 -38.6567426
OS 52.25103596 -38.65859172
OS 52.2547342 -38.66413908
OS 52.26028156 -38.67338468
OS 52.26582892 -38.68540396
OS 52.27137628 -38.70019692
OS 52.27692364 -38.71776356
OS 52.28062188 -38.73810388
OS 52.28154644 -38.76029332
OS 52.28154644 -38.76121788
OS 52.28154644 -38.76399156
OS 52.28154644 -38.76861436
OS 52.28062188 -38.77416172
OS 52.27969732 -38.7815582
OS 52.2778482 -38.78987924
OS 52.27599908 -38.79912484
OS 52.27414996 -38.809295
OS 52.26675348 -38.83148444
OS 52.26120612 -38.84350372
OS 52.25565876 -38.85459844
OS 52.24826228 -38.86661772
OS 52.23994124 -38.878637
OS 52.23069564 -38.89065628
OS 52.21960092 -38.901751
OS 52.21867636 -38.90267556
OS 52.21682724 -38.90452468
OS 52.213129 -38.90729836
OS 52.2085062 -38.9109966
OS 52.20295884 -38.9156194
OS 52.19556236 -38.9202422
OS 52.18724132 -38.92578956
OS 52.17707116 -38.93041236
OS 52.166901 -38.93595972
OS 52.15488172 -38.94150708
OS 52.14286244 -38.94612988
OS 52.12899404 -38.95075268
OS 52.11420108 -38.95445092
OS 52.09848356 -38.9572246
OS 52.08276604 -38.95907372
OS 52.0651994 -38.95999828
OS 52.05687836 -38.95999828
OS 52.051331 -38.95907372
OS 52.04393452 -38.95814916
OS 52.03561348 -38.9572246
OS 52.02636788 -38.95537548
OS 52.01619772 -38.95352636
OS 51.99400828 -38.947979
OS 51.97089428 -38.9387334
OS 51.958875 -38.93318604
OS 51.94778028 -38.92671412
OS 51.93668556 -38.91839308
OS 51.92559084 -38.91007204
OS 51.92466628 -38.90914748
OS 51.92281716 -38.90729836
OS 51.92004348 -38.90452468
OS 51.9172698 -38.90082644
OS 51.912647 -38.89620364
OS 51.9080242 -38.88973172
OS 51.90247684 -38.8832598
OS 51.89692948 -38.87493876
OS 51.89138212 -38.86569316
OS 51.88583476 -38.85644756
OS 51.8756646 -38.83425812
OS 51.86734356 -38.80837044
OS 51.86456988 -38.79450204
OS 51.86272076 -38.77970908
OS 51.94130836 -38.76953892
OS 51.94130836 -38.77046348
OS 51.94223292 -38.7723126
OS 51.94315748 -38.77601084
OS 51.94408204 -38.78063364
OS 51.9450066 -38.786181
OS 51.94685572 -38.79265292
OS 51.95147852 -38.80652132
OS 51.95795044 -38.8231634
OS 51.96627148 -38.83888092
OS 51.97551708 -38.85367388
OS 51.9866118 -38.86661772
OS 51.98846092 -38.86754228
OS 51.99215916 -38.87124052
OS 51.99955564 -38.87586332
OS 52.00880124 -38.88048612
OS 52.01989596 -38.88603348
OS 52.03376436 -38.89065628
OS 52.04948188 -38.89435452
OS 52.06612396 -38.89527908
OS 52.07167132 -38.89527908
OS 52.07536956 -38.89435452
OS 52.08553972 -38.89342996
OS 52.09848356 -38.89065628
OS 52.11327652 -38.88603348
OS 52.12899404 -38.87956156
OS 52.14471156 -38.87031596
OS 52.15950452 -38.85737212
OS 52.16135364 -38.855523
OS 52.16597644 -38.84997564
OS 52.1715238 -38.8416546
OS 52.17892028 -38.83055988
OS 52.18631676 -38.81669148
OS 52.19186412 -38.80097396
OS 52.19648692 -38.78248276
OS 52.19833604 -38.76214244
OS 52.19833604 -38.76121788
OS 52.19833604 -38.75936876
OS 52.19833604 -38.75659508
OS 52.19741148 -38.75289684
OS 52.19648692 -38.74272668
OS 52.19371324 -38.7307074
OS 52.190015 -38.71591444
OS 52.18354308 -38.70112148
OS 52.17429748 -38.68632852
OS 52.1622782 -38.67246012
OS 52.16042908 -38.670611
OS 52.15580628 -38.66691276
OS 52.1484098 -38.6613654
OS 52.13823964 -38.65489348
OS 52.1252958 -38.64842156
OS 52.10957828 -38.6428742
OS 52.09201164 -38.63917596
OS 52.07259588 -38.63732684
OS 52.06427484 -38.63732684
OS 52.05780292 -38.6382514
OS 52.04948188 -38.63917596
OS 52.04023628 -38.64102508
OS 52.02914156 -38.6428742
OS 52.01712228 -38.64564788
OS 52.02636788 -38.57630588
OS 52.03099068 -38.57630588
OS 52.03468892 -38.57723044
OS 52.0467082 -38.57723044
OS 52.05687836 -38.57538132
OS 52.06889764 -38.5735322
OS 52.08276604 -38.57075852
OS 52.09848356 -38.56613572
OS 52.11327652 -38.5596638
OS 52.12899404 -38.55134276
OS 52.1299186 -38.55134276
OS 52.13084316 -38.5504182
OS 52.13546596 -38.54671996
OS 52.14193788 -38.54024804
OS 52.14933436 -38.531927
OS 52.15673084 -38.51990772
OS 52.16320276 -38.50603932
OS 52.16782556 -38.4903218
OS 52.16967468 -38.4810762
OS 52.16967468 -38.47090604
OS 52.16967468 -38.46998148
OS 52.16967468 -38.46905692
OS 52.16967468 -38.46350956
OS 52.16782556 -38.45611308
OS 52.16597644 -38.44594292
OS 52.1622782 -38.4348482
OS 52.1576554 -38.42282892
OS 52.15025892 -38.41080964
OS 52.14008876 -38.39971492
OS 52.1391642 -38.39879036
OS 52.1345414 -38.39509212
OS 52.12806948 -38.39046932
OS 52.11974844 -38.38492196
OS 52.10865372 -38.38029916
OS 52.09570988 -38.37567636
OS 52.08091692 -38.37197812
OS 52.06427484 -38.37105356
OS 52.05687836 -38.37105356
OS 52.04855732 -38.37290268
OS 52.0374626 -38.3747518
OS 52.02544332 -38.37845004
OS 52.01342404 -38.38307284
OS 52.0004802 -38.39046932
OS 51.98846092 -38.39971492
OS 51.98753636 -38.40063948
OS 51.98383812 -38.40526228
OS 51.97829076 -38.4117342
OS 51.97181884 -38.4209798
OS 51.96534692 -38.43299908
OS 51.958875 -38.44779204
OS 51.95332764 -38.46535868
OS 51.9496294 -38.485699
OS 51.8710418 -38.4718306
OS 51.8710418 -38.47090604
OS 51.87196636 -38.46813236
OS 51.87289092 -38.46443412
OS 51.87381548 -38.45888676
OS 51.8756646 -38.45241484
OS 51.87843828 -38.44501836
OS 51.88398564 -38.42745172
OS 51.89323124 -38.4071114
OS 51.90432596 -38.38677108
OS 51.91819436 -38.36735532
OS 51.935761 -38.34978868
OS 51.93668556 -38.34886412
OS 51.93853468 -38.34793956
OS 51.94130836 -38.34609044
OS 51.9450066 -38.34331676
OS 51.9496294 -38.33961852
OS 51.95610132 -38.33592028
OS 51.96257324 -38.33222204
OS 51.97089428 -38.32759924
OS 51.98938548 -38.32020276
OS 52.01065036 -38.31280628
OS 52.03561348 -38.30818348
OS 52.04855732 -38.30633436
OS 52.07167132 -38.30633436
OS 52.08184148 -38.30725892
OE
OB 56.14158444 -38.38492196 H
OS 55.95852156 -38.38492196
OS 55.95852156 -38.61328828
OS 56.13048972 -38.61328828
OS 56.13696164 -38.61236372
OS 56.14343356 -38.61236372
OS 56.15083004 -38.61143916
OS 56.16839668 -38.60959004
OS 56.18781244 -38.6058918
OS 56.2072282 -38.60034444
OS 56.22479484 -38.59294796
OS 56.23311588 -38.58832516
OS 56.2395878 -38.5827778
OS 56.24143692 -38.58092868
OS 56.24513516 -38.57723044
OS 56.25068252 -38.56983396
OS 56.25715444 -38.56058836
OS 56.26362636 -38.54856908
OS 56.26917372 -38.53377612
OS 56.27287196 -38.51713404
OS 56.27472108 -38.49771828
OS 56.27472108 -38.49679372
OS 56.27472108 -38.49586916
OS 56.27472108 -38.49124636
OS 56.27379652 -38.48292532
OS 56.2719474 -38.47367972
OS 56.27009828 -38.46350956
OS 56.26640004 -38.45149028
OS 56.26085268 -38.44039556
OS 56.25438076 -38.42930084
OS 56.2534562 -38.42837628
OS 56.25068252 -38.42467804
OS 56.24605972 -38.42005524
OS 56.24051236 -38.41358332
OS 56.23219132 -38.4071114
OS 56.22294572 -38.40156404
OS 56.21277556 -38.39601668
OS 56.20075628 -38.39139388
OS 56.19983172 -38.39139388
OS 56.19613348 -38.39046932
OS 56.19058612 -38.38954476
OS 56.18318964 -38.38769564
OS 56.17209492 -38.38677108
OS 56.15822652 -38.38584652
OS 56.14158444 -38.38492196
OE
OB 49.87491676 -38.43669732 H
OS 49.67336268 -38.72331092
OS 49.87491676 -38.72331092
OS 49.87491676 -38.43669732
OE
OB 54.06132444 -38.37105356 H
OS 54.05392796 -38.37105356
OS 54.04560692 -38.37290268
OS 54.0345122 -38.3747518
OS 54.02249292 -38.37845004
OS 54.00954908 -38.38307284
OS 53.9975298 -38.39046932
OS 53.98551052 -38.40063948
OS 53.98458596 -38.40156404
OS 53.98088772 -38.40526228
OS 53.97626492 -38.4117342
OS 53.97164212 -38.42005524
OS 53.96609476 -38.4302254
OS 53.96147196 -38.44224468
OS 53.95777372 -38.45518852
OS 53.95684916 -38.46998148
OS 53.95684916 -38.47090604
OS 53.95684916 -38.4718306
OS 53.95777372 -38.47737796
OS 53.95869828 -38.485699
OS 53.9605474 -38.49586916
OS 53.96424564 -38.50788844
OS 53.96886844 -38.51990772
OS 53.97626492 -38.53285156
OS 53.98551052 -38.54394628
OS 53.98643508 -38.54487084
OS 53.99105788 -38.54856908
OS 53.9975298 -38.55319188
OS 54.00585084 -38.55781468
OS 54.01694556 -38.56336204
OS 54.0298894 -38.56798484
OS 54.04468236 -38.57168308
OS 54.06132444 -38.57260764
OS 54.06317356 -38.57260764
OS 54.06872092 -38.57168308
OS 54.07704196 -38.57075852
OS 54.08813668 -38.5689094
OS 54.10015596 -38.56521116
OS 54.11217524 -38.56058836
OS 54.12511908 -38.55319188
OS 54.1362138 -38.54394628
OS 54.13713836 -38.54302172
OS 54.1408366 -38.53839892
OS 54.1454594 -38.53285156
OS 54.15100676 -38.52453052
OS 54.15655412 -38.51436036
OS 54.16117692 -38.50234108
OS 54.16487516 -38.48847268
OS 54.16579972 -38.47367972
OS 54.16579972 -38.47275516
OS 54.16579972 -38.4718306
OS 54.16579972 -38.46628324
OS 54.1639506 -38.4579622
OS 54.16210148 -38.44779204
OS 54.15840324 -38.43669732
OS 54.15285588 -38.42467804
OS 54.1454594 -38.41265876
OS 54.13528924 -38.40063948
OS 54.13436468 -38.39971492
OS 54.12974188 -38.39601668
OS 54.12326996 -38.39139388
OS 54.11494892 -38.38584652
OS 54.1038542 -38.38029916
OS 54.09183492 -38.37567636
OS 54.07704196 -38.37197812
OS 54.06132444 -38.37105356
OE
OB 54.05855076 -38.63640228 H
OS 54.0530034 -38.63640228
OS 54.04930516 -38.63732684
OS 54.039135 -38.6382514
OS 54.02619116 -38.64102508
OS 54.0113982 -38.64564788
OS 53.99660524 -38.6521198
OS 53.98088772 -38.6613654
OS 53.96701932 -38.67338468
OS 53.9651702 -38.6752338
OS 53.96147196 -38.6798566
OS 53.9559246 -38.68817764
OS 53.94945268 -38.6983478
OS 53.9420562 -38.7122162
OS 53.93650884 -38.72793372
OS 53.9328106 -38.74550036
OS 53.93096148 -38.76491612
OS 53.93096148 -38.76676524
OS 53.93096148 -38.77046348
OS 53.93188604 -38.7769354
OS 53.9328106 -38.78525644
OS 53.93465972 -38.7954266
OS 53.9374334 -38.80652132
OS 53.94113164 -38.81761604
OS 53.94575444 -38.82963532
OS 53.946679 -38.83055988
OS 53.94852812 -38.83518268
OS 53.95222636 -38.84073004
OS 53.95777372 -38.84720196
OS 53.96424564 -38.855523
OS 53.97256668 -38.86384404
OS 53.98181228 -38.87124052
OS 53.992907 -38.878637
OS 53.99475612 -38.87956156
OS 53.99845436 -38.88141068
OS 54.00492628 -38.88418436
OS 54.01324732 -38.88695804
OS 54.02341748 -38.88973172
OS 54.03543676 -38.8925054
OS 54.0483806 -38.89435452
OS 54.06132444 -38.89527908
OS 54.0668718 -38.89527908
OS 54.07057004 -38.89435452
OS 54.08166476 -38.89342996
OS 54.0946086 -38.89065628
OS 54.10940156 -38.88603348
OS 54.12511908 -38.88048612
OS 54.13991204 -38.87124052
OS 54.154705 -38.85922124
OS 54.15655412 -38.85737212
OS 54.16025236 -38.85274932
OS 54.16672428 -38.84442828
OS 54.1731962 -38.83425812
OS 54.17966812 -38.82131428
OS 54.18614004 -38.80559676
OS 54.18983828 -38.78710556
OS 54.1916874 -38.7676898
OS 54.1916874 -38.76676524
OS 54.1916874 -38.76491612
OS 54.1916874 -38.76214244
OS 54.19076284 -38.7584442
OS 54.18983828 -38.74827404
OS 54.1870646 -38.73440564
OS 54.1824418 -38.72053724
OS 54.17596988 -38.70481972
OS 54.16672428 -38.6891022
OS 54.15378044 -38.67430924
OS 54.15193132 -38.67246012
OS 54.14730852 -38.66876188
OS 54.13898748 -38.66228996
OS 54.12789276 -38.65489348
OS 54.11402436 -38.64842156
OS 54.09738228 -38.64194964
OS 54.07889108 -38.6382514
OS 54.05855076 -38.63640228
OE
OB 54.80559524 -38.37105356 H
OS 54.80004788 -38.37105356
OS 54.79634964 -38.37197812
OS 54.78617948 -38.37382724
OS 54.7741602 -38.37660092
OS 54.7602918 -38.38214828
OS 54.74549884 -38.39046932
OS 54.73810236 -38.39601668
OS 54.73070588 -38.40156404
OS 54.72423396 -38.40896052
OS 54.71776204 -38.41728156
OS 54.71776204 -38.41820612
OS 54.71591292 -38.42005524
OS 54.7140638 -38.42375348
OS 54.71129012 -38.42837628
OS 54.70851644 -38.43577276
OS 54.7048182 -38.4440938
OS 54.70204452 -38.45426396
OS 54.69834628 -38.46628324
OS 54.69464804 -38.48015164
OS 54.6909498 -38.49586916
OS 54.68725156 -38.5134358
OS 54.68447788 -38.53285156
OS 54.6817042 -38.555041
OS 54.67985508 -38.57907956
OS 54.67893052 -38.60496724
OS 54.67800596 -38.6336286
OS 54.67800596 -38.63547772
OS 54.67800596 -38.64010052
OS 54.67800596 -38.64842156
OS 54.67893052 -38.65951628
OS 54.67893052 -38.67153556
OS 54.67985508 -38.68632852
OS 54.68077964 -38.70204604
OS 54.68262876 -38.71868812
OS 54.68725156 -38.75474596
OS 54.69002524 -38.7723126
OS 54.69372348 -38.78895468
OS 54.69742172 -38.8046722
OS 54.70296908 -38.81946516
OS 54.70851644 -38.832409
OS 54.71498836 -38.84350372
OS 54.71498836 -38.84442828
OS 54.71683748 -38.84535284
OS 54.72146028 -38.85182476
OS 54.72978132 -38.8601458
OS 54.73995148 -38.8693914
OS 54.75381988 -38.878637
OS 54.7695374 -38.88695804
OS 54.78710404 -38.89342996
OS 54.79634964 -38.89435452
OS 54.8065198 -38.89527908
OS 54.81206716 -38.89527908
OS 54.8157654 -38.89435452
OS 54.825011 -38.8925054
OS 54.83795484 -38.88880716
OS 54.85182324 -38.88233524
OS 54.86754076 -38.87308964
OS 54.87493724 -38.86754228
OS 54.88233372 -38.8601458
OS 54.8897302 -38.85274932
OS 54.89712668 -38.84350372
OS 54.89712668 -38.84257916
OS 54.8989758 -38.84073004
OS 54.90082492 -38.83795636
OS 54.90267404 -38.83333356
OS 54.90637228 -38.82686164
OS 54.90914596 -38.8185406
OS 54.9128442 -38.809295
OS 54.91654244 -38.79820028
OS 54.91931612 -38.78433188
OS 54.92301436 -38.76953892
OS 54.9267126 -38.75197228
OS 54.92948628 -38.73348108
OS 54.9313354 -38.71129164
OS 54.93318452 -38.68817764
OS 54.93503364 -38.66228996
OS 54.93503364 -38.6336286
OS 54.93503364 -38.63270404
OS 54.93503364 -38.63177948
OS 54.93503364 -38.62715668
OS 54.93503364 -38.61883564
OS 54.93410908 -38.60774092
OS 54.93410908 -38.59572164
OS 54.93318452 -38.58092868
OS 54.93225996 -38.56521116
OS 54.93041084 -38.54764452
OS 54.92578804 -38.51251124
OS 54.92301436 -38.4949446
OS 54.91931612 -38.47830252
OS 54.91561788 -38.462585
OS 54.91007052 -38.44779204
OS 54.90452316 -38.4348482
OS 54.89805124 -38.42375348
OS 54.89805124 -38.42282892
OS 54.89620212 -38.42190436
OS 54.894353 -38.41913068
OS 54.89157932 -38.41543244
OS 54.88325828 -38.4071114
OS 54.87308812 -38.39694124
OS 54.85921972 -38.38769564
OS 54.8435022 -38.3793746
OS 54.83518116 -38.37567636
OS 54.82593556 -38.37290268
OS 54.8157654 -38.37197812
OS 54.80559524 -38.37105356
OE
OB 51.07499564 -38.37105356 H
OS 51.06944828 -38.37105356
OS 51.06575004 -38.37197812
OS 51.05557988 -38.37382724
OS 51.0435606 -38.37660092
OS 51.0296922 -38.38214828
OS 51.01489924 -38.39046932
OS 51.00750276 -38.39601668
OS 51.00010628 -38.40156404
OS 50.99363436 -38.40896052
OS 50.98716244 -38.41728156
OS 50.98716244 -38.41820612
OS 50.98531332 -38.42005524
OS 50.9834642 -38.42375348
OS 50.98069052 -38.42837628
OS 50.97791684 -38.43577276
OS 50.9742186 -38.4440938
OS 50.97144492 -38.45426396
OS 50.96774668 -38.46628324
OS 50.96404844 -38.48015164
OS 50.9603502 -38.49586916
OS 50.95665196 -38.5134358
OS 50.95387828 -38.53285156
OS 50.9511046 -38.555041
OS 50.94925548 -38.57907956
OS 50.94833092 -38.60496724
OS 50.94740636 -38.6336286
OS 50.94740636 -38.63547772
OS 50.94740636 -38.64010052
OS 50.94740636 -38.64842156
OS 50.94833092 -38.65951628
OS 50.94833092 -38.67153556
OS 50.94925548 -38.68632852
OS 50.95018004 -38.70204604
OS 50.95202916 -38.71868812
OS 50.95665196 -38.75474596
OS 50.95942564 -38.7723126
OS 50.96312388 -38.78895468
OS 50.96682212 -38.8046722
OS 50.97236948 -38.81946516
OS 50.97791684 -38.832409
OS 50.98438876 -38.84350372
OS 50.98438876 -38.84442828
OS 50.98623788 -38.84535284
OS 50.99086068 -38.85182476
OS 50.99918172 -38.8601458
OS 51.00935188 -38.8693914
OS 51.02322028 -38.878637
OS 51.0389378 -38.88695804
OS 51.05650444 -38.89342996
OS 51.06575004 -38.89435452
OS 51.0759202 -38.89527908
OS 51.08146756 -38.89527908
OS 51.0851658 -38.89435452
OS 51.0944114 -38.8925054
OS 51.10735524 -38.88880716
OS 51.12122364 -38.88233524
OS 51.13694116 -38.87308964
OS 51.14433764 -38.86754228
OS 51.15173412 -38.8601458
OS 51.1591306 -38.85274932
OS 51.16652708 -38.84350372
OS 51.16652708 -38.84257916
OS 51.1683762 -38.84073004
OS 51.17022532 -38.83795636
OS 51.17207444 -38.83333356
OS 51.17577268 -38.82686164
OS 51.17854636 -38.8185406
OS 51.1822446 -38.809295
OS 51.18594284 -38.79820028
OS 51.18871652 -38.78433188
OS 51.19241476 -38.76953892
OS 51.196113 -38.75197228
OS 51.19888668 -38.73348108
OS 51.2007358 -38.71129164
OS 51.20258492 -38.68817764
OS 51.20443404 -38.66228996
OS 51.20443404 -38.6336286
OS 51.20443404 -38.63270404
OS 51.20443404 -38.63177948
OS 51.20443404 -38.62715668
OS 51.20443404 -38.61883564
OS 51.20350948 -38.60774092
OS 51.20350948 -38.59572164
OS 51.20258492 -38.58092868
OS 51.20166036 -38.56521116
OS 51.19981124 -38.54764452
OS 51.19518844 -38.51251124
OS 51.19241476 -38.4949446
OS 51.18871652 -38.47830252
OS 51.18501828 -38.462585
OS 51.17947092 -38.44779204
OS 51.17392356 -38.4348482
OS 51.16745164 -38.42375348
OS 51.16745164 -38.42282892
OS 51.16560252 -38.42190436
OS 51.1637534 -38.41913068
OS 51.16097972 -38.41543244
OS 51.15265868 -38.4071114
OS 51.14248852 -38.39694124
OS 51.12862012 -38.38769564
OS 51.1129026 -38.3793746
OS 51.10458156 -38.37567636
OS 51.09533596 -38.37290268
OS 51.0851658 -38.37197812
OS 51.07499564 -38.37105356
OE
SE

### steps/pcb/layers/bottom_paste/features
UNITS=MM
#Layer_Color=128
#
#Feature symbol names
#
$0 r99.9998
$1 rect1050.00044x1749.99904
$2 rect1050.00044x900.00074
$3 rect569.99886x619.99876
$4 rect419.99916x439.99912
$5 r6200.0003
$6 rect2300.00048x3300.00102
$7 rect299.9994x1725.00036
$8 rect800.00094x1449.99964
$9 rect599.9988x299.9994
$10 rect1299.99994x1649.99924
$11 rect599.9988x619.99876
$12 rect459.99908x419.99916
$13 rect419.99916x459.99908
$14 rect619.99876x599.9988
$15 rect619.99876x569.99886

#
#Feature attribute names
#
@0 .nomenclature
@1 .string
@2 .string_angle
@3 .geometry
@4 .pad_usage

#
#Feature attribute text strings
#
&0 SMD_RectX1050.0004Y1749.9990
&1 SMD_RectX1050.0004Y900.0007
&2 SMD_RectX569.9989Y619.9988
&3 SMD_RectX419.9992Y439.9991
&4 SMD_RoundX6200.0003Y6200.0003
&5 SMD_RectX2300.0005Y3300.0010
&6 SMD_RectX299.9994Y1725.0004
&7 SMD_RectX800.0009Y1449.9996
&8 SMD_RectX599.9988Y299.9994
&9 SMD_RectX1299.9999Y1649.9992
&10 SMD_RectX599.9988Y619.9988
&11 SMD_RectX459.9991Y419.9992
&12 SMD_RectX419.9992Y459.9991
&13 SMD_RectX619.9988Y599.9988
&14 SMD_RectX619.9988Y569.9989

#
#Layer features
#
L -9.5600012 -24.45999934 40.4400004 -24.45999934 0 P 0
L -9.5600012 -35.9599992 -9.5600012 -24.45999934 0 P 0
L -9.5600012 -35.9599992 28.439999 -35.9599992 0 P 0
L -9.5600012 -39.45999982 -9.5600012 -35.9599992 0 P 0
L -9.5600012 -39.45999982 28.439999 -39.45999982 0 P 0
L -9.5600012 -42.96000044 -9.5600012 -39.45999982 0 P 0
L -9.5600012 -42.96000044 28.439999 -42.96000044 0 P 0
L -10.0600002 -23.96000034 62.93999858 -23.96000034 0 P 0
L -10.0600002 -43.45999944 -10.0600002 -23.96000034 0 P 0
L -10.0600002 -43.45999944 62.93999858 -43.45999944 0 P 0
L 28.439999 -35.96000174 45.44000056 -35.9599992 0 P 0
L 28.439999 -39.45999982 28.439999 -35.9599992 0 P 0
L 28.439999 -39.46000236 45.44000056 -39.45999982 0 P 0
L 28.439999 -42.96000044 28.439999 -39.45999982 0 P 0
L 28.439999 -42.96000298 45.44000056 -42.96000044 0 P 0
L 40.4400004 -24.45999934 62.43999958 -24.45999934 0 P 0
L 40.4400004 -35.9599992 40.4400004 -24.45999934 0 P 0
L 45.44000056 -35.9599992 62.43999958 -35.9599992 0 P 0
L 45.44000056 -39.45999982 62.43999958 -39.45999982 0 P 0
L 45.44000056 -42.96000044 45.44000056 -35.9599992 0 P 0
L 45.44000056 -42.96000044 62.43999958 -42.96000044 0 P 0
L 62.43999958 -35.9599992 62.43999958 -24.45999934 0 P 0
L 62.43999958 -42.96000044 62.43999958 -35.9599992 0 P 0
L 62.93999858 -43.45999944 62.93999858 -23.96000034 0 P 0
P 4.39999882 2.00000108 5 P 0 0 ;3=4,4=0
P 4.39999882 38.599999 5 P 0 0 ;3=4,4=0
P 13.9050014 18.0150008 3 P 0 0 ;3=2,4=0
P 13.9050014 19.16500104 3 P 0 0 ;3=2,4=0
P 14.86499948 18.0150008 3 P 0 0 ;3=2,4=0
P 14.86499948 19.16500104 3 P 0 0 ;3=2,4=0
P 14.86499948 20.21500148 13 P 0 0 ;3=12,4=0
P 14.86499948 20.87500016 13 P 0 0 ;3=12,4=0
P 15.86500002 20.21500148 4 P 0 0 ;3=3,4=0
P 15.86500002 20.89500012 4 P 0 0 ;3=3,4=0
P 15.91499992 7.38999792 10 P 0 0 ;3=9,4=0
P 15.91499992 9.7899982 10 P 0 0 ;3=9,4=0
P 15.91499992 12.39000062 10 P 0 0 ;3=9,4=0
P 16.29499916 22.29000114 12 P 0 0 ;3=11,4=0
P 16.31500166 18.04000202 9 P 0 0 ;3=8,4=0
P 16.31500166 18.49000112 9 P 0 0 ;3=8,4=0
P 16.31500166 18.94000276 9 P 0 0 ;3=8,4=0
P 16.41500146 16.99000158 8 P 0 0 ;3=7,4=0
P 16.65500352 14.7900009 11 P 0 0 ;3=10,4=0
P 16.95499784 20.21500148 15 P 0 0 ;3=14,4=0
P 16.95499784 21.17499956 15 P 0 0 ;3=14,4=0
P 16.95499784 22.29000114 12 P 0 0 ;3=11,4=0
P 17.1650025 16.85250122 7 P 0 0 ;3=6,4=0
P 17.57500168 14.7900009 11 P 0 0 ;3=10,4=0
P 17.7150014 7.38999792 10 P 0 0 ;3=9,4=0
P 17.7150014 9.7899982 10 P 0 0 ;3=9,4=0
P 17.7150014 12.39000062 10 P 0 0 ;3=9,4=0
P 17.915001 16.99000158 8 P 0 0 ;3=7,4=0
P 18.0150008 18.04000202 9 P 0 0 ;3=8,4=0
P 18.0150008 18.49000112 9 P 0 0 ;3=8,4=0
P 18.0150008 18.94000276 9 P 0 0 ;3=8,4=0
P 18.22000166 21.17499956 11 P 0 0 ;3=10,4=0
P 19.13999982 21.17499956 11 P 0 0 ;3=10,4=0
P 20.76500038 16.85250122 6 P 0 0 ;3=5,4=0
P 22.41500216 7.7900022 10 P 0 0 ;3=9,4=0
P 22.41500216 10.29000228 10 P 0 0 ;3=9,4=0
P 22.95500362 12.29000082 11 P 0 0 ;3=10,4=0
P 23.87500178 12.29000082 11 P 0 0 ;3=10,4=0
P 24.21500364 7.7900022 10 P 0 0 ;3=9,4=0
P 24.21500364 10.29000228 10 P 0 0 ;3=9,4=0
P 26.06499994 16.85250122 6 P 0 0 ;3=5,4=0
P 32.24000156 7.63999996 1 P 0 0 ;3=0,4=0
P 35.24000064 7.63999996 1 P 0 0 ;3=0,4=0
P 35.50000012 -1.00000054 5 P 0 0 ;3=4,4=0
P 36.20000126 40.10000108 5 P 0 0 ;3=4,4=0
P 37.8500005 9.94000044 11 P 0 0 ;3=10,4=0
P 38.76999866 9.94000044 11 P 0 0 ;3=10,4=0
P 39.78999916 14.51500018 2 P 0 0 ;3=1,4=0
P 39.78999916 15.96499982 2 P 0 0 ;3=1,4=0
P 40.0900011 7.63999996 14 P 0 0 ;3=13,4=0
P 40.0900011 8.55999812 14 P 0 0 ;3=13,4=0
S P 0
OB -2.41723418 -38.48662356 I
OS -2.41076226 -38.48754812
OS -2.39689386 -38.48939724
OS -2.38025178 -38.49309548
OS -2.36268514 -38.49864284
OS -2.3451185 -38.50696388
OS -2.32755186 -38.51713404
OS -2.3266273 -38.51713404
OS -2.32570274 -38.51898316
OS -2.32015538 -38.5226814
OS -2.31183434 -38.53007788
OS -2.30166418 -38.53932348
OS -2.29056946 -38.55134276
OS -2.27947474 -38.56613572
OS -2.26838002 -38.58370236
OS -2.25913442 -38.60311812
OS -2.25913442 -38.60404268
OS -2.25820986 -38.6058918
OS -2.2572853 -38.60866548
OS -2.25543618 -38.61236372
OS -2.25358706 -38.61791108
OS -2.25173794 -38.624383
OS -2.24711514 -38.63917596
OS -2.24249234 -38.65766716
OS -2.2387941 -38.67800748
OS -2.23602042 -38.70112148
OS -2.23509586 -38.72516004
OS -2.23509586 -38.7260846
OS -2.23509586 -38.72793372
OS -2.23509586 -38.73163196
OS -2.23509586 -38.73717932
OS -2.23602042 -38.74365124
OS -2.23602042 -38.75104772
OS -2.23786954 -38.7676898
OS -2.24156778 -38.78803012
OS -2.24619058 -38.809295
OS -2.2526625 -38.83148444
OS -2.26098354 -38.85367388
OS -2.26098354 -38.85459844
OS -2.2619081 -38.85644756
OS -2.26375722 -38.85922124
OS -2.26560634 -38.86291948
OS -2.27207826 -38.87308964
OS -2.2803993 -38.88603348
OS -2.29056946 -38.89990188
OS -2.3035133 -38.91377028
OS -2.31830626 -38.92763868
OS -2.3358729 -38.94058252
OS -2.33679746 -38.94058252
OS -2.33772202 -38.94150708
OS -2.3404957 -38.9433562
OS -2.34419394 -38.94520532
OS -2.35343954 -38.94982812
OS -2.36638338 -38.95537548
OS -2.3821009 -38.96092284
OS -2.39874298 -38.96554564
OS -2.41815874 -38.96924388
OS -2.4375745 -38.97016844
OS -2.44404642 -38.97016844
OS -2.4514429 -38.96924388
OS -2.4606885 -38.96831932
OS -2.47178322 -38.9664702
OS -2.4838025 -38.96369652
OS -2.49582178 -38.95999828
OS -2.50784106 -38.95445092
OS -2.50876562 -38.95352636
OS -2.51338842 -38.95167724
OS -2.51893578 -38.947979
OS -2.52633226 -38.94243164
OS -2.53372874 -38.93688428
OS -2.54297434 -38.9294878
OS -2.55129538 -38.92116676
OS -2.55869186 -38.91192116
OS -2.55869186 -39.1375138
OS -2.63727946 -39.1375138
OS -2.63727946 -38.49586916
OS -2.56608834 -38.49586916
OS -2.56608834 -38.55689012
OS -2.56516378 -38.555041
OS -2.56146554 -38.55134276
OS -2.55684274 -38.54487084
OS -2.54944626 -38.53747436
OS -2.54112522 -38.52822876
OS -2.53187962 -38.51990772
OS -2.5207849 -38.51158668
OS -2.50969018 -38.5041902
OS -2.50784106 -38.50326564
OS -2.50414282 -38.50141652
OS -2.49674634 -38.49864284
OS -2.48750074 -38.4949446
OS -2.47640602 -38.49124636
OS -2.46346218 -38.48847268
OS -2.44866922 -38.48662356
OS -2.43202714 -38.485699
OS -2.42185698 -38.485699
OS -2.41723418 -38.48662356
OE
OB -1.92351914 -38.48662356 I
OS -1.90965074 -38.48754812
OS -1.89393322 -38.48939724
OS -1.8782157 -38.49217092
OS -1.86249818 -38.49586916
OS -1.84770522 -38.50049196
OS -1.8458561 -38.50141652
OS -1.8412333 -38.50326564
OS -1.83476138 -38.50603932
OS -1.82644034 -38.50973756
OS -1.81719474 -38.51528492
OS -1.80794914 -38.52083228
OS -1.7996281 -38.52822876
OS -1.79223162 -38.53562524
OS -1.79130706 -38.5365498
OS -1.78945794 -38.53932348
OS -1.78668426 -38.54394628
OS -1.78298602 -38.54949364
OS -1.77836322 -38.55781468
OS -1.77466498 -38.56613572
OS -1.77096674 -38.57630588
OS -1.76819306 -38.58832516
OS -1.76819306 -38.58924972
OS -1.7672685 -38.5920234
OS -1.76634394 -38.59757076
OS -1.76541938 -38.60496724
OS -1.76541938 -38.6151374
OS -1.76449482 -38.62715668
OS -1.76357026 -38.6428742
OS -1.76357026 -38.66044084
OS -1.76357026 -38.76584068
OS -1.76357026 -38.76676524
OS -1.76357026 -38.77046348
OS -1.76357026 -38.77601084
OS -1.76357026 -38.78340732
OS -1.76357026 -38.79172836
OS -1.76357026 -38.80189852
OS -1.7626457 -38.82408796
OS -1.7626457 -38.84720196
OS -1.76172114 -38.87031596
OS -1.76079658 -38.88048612
OS -1.76079658 -38.88973172
OS -1.75987202 -38.89805276
OS -1.75894746 -38.90452468
OS -1.75894746 -38.90544924
OS -1.7580229 -38.90914748
OS -1.75709834 -38.91469484
OS -1.75432466 -38.92209132
OS -1.75247554 -38.93041236
OS -1.7487773 -38.93965796
OS -1.7441545 -38.94982812
OS -1.7395317 -38.95999828
OS -1.82181754 -38.95999828
OS -1.8227421 -38.95907372
OS -1.82366666 -38.95537548
OS -1.82551578 -38.95075268
OS -1.82828946 -38.9433562
OS -1.83106314 -38.93503516
OS -1.83291226 -38.924865
OS -1.83476138 -38.91377028
OS -1.8366105 -38.901751
OS -1.83753506 -38.901751
OS -1.83845962 -38.90360012
OS -1.84400698 -38.90822292
OS -1.85232802 -38.91469484
OS -1.86342274 -38.92301588
OS -1.87729114 -38.93133692
OS -1.89115954 -38.94058252
OS -1.9059525 -38.94890356
OS -1.92167002 -38.95537548
OS -1.92351914 -38.95630004
OS -1.9290665 -38.9572246
OS -1.93738754 -38.95999828
OS -1.9475577 -38.96277196
OS -1.96050154 -38.96554564
OS -1.9752945 -38.96739476
OS -1.99193658 -38.96924388
OS -2.00857866 -38.97016844
OS -2.01597514 -38.97016844
OS -2.0215225 -38.96924388
OS -2.02799442 -38.96924388
OS -2.0353909 -38.96831932
OS -2.05203298 -38.96554564
OS -2.07052418 -38.96092284
OS -2.0908645 -38.95445092
OS -2.1093557 -38.94520532
OS -2.12599778 -38.93318604
OS -2.1278469 -38.93133692
OS -2.1324697 -38.92671412
OS -2.13894162 -38.91839308
OS -2.1463381 -38.90729836
OS -2.15373458 -38.89342996
OS -2.1602065 -38.87771244
OS -2.1648293 -38.85829668
OS -2.16575386 -38.84905108
OS -2.16667842 -38.83795636
OS -2.16667842 -38.83610724
OS -2.16667842 -38.832409
OS -2.16575386 -38.82593708
OS -2.1648293 -38.81761604
OS -2.16298018 -38.80744588
OS -2.1602065 -38.79727572
OS -2.15650826 -38.786181
OS -2.15188546 -38.77601084
OS -2.1509609 -38.77508628
OS -2.14911178 -38.77138804
OS -2.14541354 -38.76584068
OS -2.14079074 -38.75936876
OS -2.13524338 -38.75197228
OS -2.1278469 -38.7445758
OS -2.12045042 -38.73717932
OS -2.11120482 -38.7307074
OS -2.11028026 -38.72978284
OS -2.10658202 -38.72793372
OS -2.10195922 -38.72423548
OS -2.09456274 -38.72053724
OS -2.0862417 -38.716839
OS -2.07607154 -38.7122162
OS -2.06590138 -38.70851796
OS -2.0538821 -38.70481972
OS -2.05295754 -38.70481972
OS -2.0492593 -38.70389516
OS -2.04371194 -38.70204604
OS -2.03631546 -38.70112148
OS -2.02706986 -38.69927236
OS -2.01505058 -38.69742324
OS -2.00118218 -38.69464956
OS -1.9845401 -38.69280044
OS -1.98361554 -38.69280044
OS -1.9799173 -38.69187588
OS -1.9752945 -38.69187588
OS -1.96882258 -38.69095132
OS -1.9614261 -38.69002676
OS -1.9521805 -38.68817764
OS -1.94201034 -38.68725308
OS -1.93091562 -38.68540396
OS -1.90872618 -38.68078116
OS -1.88468762 -38.67615836
OS -1.86342274 -38.670611
OS -1.85325258 -38.66783732
OS -1.84400698 -38.66506364
OS -1.84400698 -38.66413908
OS -1.84400698 -38.66228996
OS -1.84308242 -38.6567426
OS -1.84308242 -38.65027068
OS -1.84308242 -38.64657244
OS -1.84308242 -38.64472332
OS -1.84308242 -38.64379876
OS -1.84308242 -38.6428742
OS -1.84308242 -38.63732684
OS -1.84400698 -38.62808124
OS -1.8458561 -38.61791108
OS -1.84862978 -38.60681636
OS -1.85325258 -38.59572164
OS -1.85879994 -38.58555148
OS -1.86619642 -38.57723044
OS -1.86712098 -38.57630588
OS -1.87174378 -38.57260764
OS -1.87914026 -38.5689094
OS -1.88838586 -38.56336204
OS -1.9013297 -38.55873924
OS -1.91612266 -38.55411644
OS -1.93461386 -38.55134276
OS -1.95587874 -38.5504182
OS -1.96512434 -38.5504182
OS -1.97436994 -38.55134276
OS -1.98731378 -38.55319188
OS -2.00025762 -38.555041
OS -2.01412602 -38.55873924
OS -2.02706986 -38.56336204
OS -2.03816458 -38.56983396
OS -2.03908914 -38.57075852
OS -2.04278738 -38.5735322
OS -2.04741018 -38.578155
OS -2.05295754 -38.58555148
OS -2.0585049 -38.59479708
OS -2.06497682 -38.60681636
OS -2.07052418 -38.62160932
OS -2.07607154 -38.6382514
OS -2.15281002 -38.62808124
OS -2.15281002 -38.62715668
OS -2.15188546 -38.62623212
OS -2.15188546 -38.62345844
OS -2.1509609 -38.6197602
OS -2.14818722 -38.61143916
OS -2.14448898 -38.59941988
OS -2.13986618 -38.5874006
OS -2.13431882 -38.57445676
OS -2.12692234 -38.56151292
OS -2.1186013 -38.54949364
OS -2.11767674 -38.54856908
OS -2.1139785 -38.54487084
OS -2.10843114 -38.53932348
OS -2.10103466 -38.531927
OS -2.0908645 -38.52453052
OS -2.07884522 -38.51713404
OS -2.06497682 -38.508813
OS -2.0492593 -38.50234108
OS -2.04833474 -38.50234108
OS -2.04741018 -38.50141652
OS -2.0446365 -38.50049196
OS -2.04093826 -38.4995674
OS -2.03169266 -38.49679372
OS -2.01874882 -38.49402004
OS -2.00395586 -38.49124636
OS -1.98546466 -38.48847268
OS -1.9660489 -38.48662356
OS -1.94385946 -38.485699
OS -1.9336893 -38.485699
OS -1.92351914 -38.48662356
OE
OB -3.38339938 -38.48662356 I
OS -3.37692746 -38.48662356
OS -3.37045554 -38.48754812
OS -3.35473802 -38.4903218
OS -3.33809594 -38.4949446
OS -3.3205293 -38.50234108
OS -3.30296266 -38.51158668
OS -3.2881697 -38.52453052
OS -3.28632058 -38.52637964
OS -3.28262234 -38.531927
OS -3.27615042 -38.54024804
OS -3.27337674 -38.54671996
OS -3.2696785 -38.55319188
OS -3.26598026 -38.56151292
OS -3.26320658 -38.56983396
OS -3.25950834 -38.57907956
OS -3.25673466 -38.59017428
OS -3.25488554 -38.601269
OS -3.25303642 -38.61421284
OS -3.2511873 -38.62715668
OS -3.2511873 -38.64194964
OS -3.2511873 -38.95999828
OS -3.3297749 -38.95999828
OS -3.3297749 -38.66876188
OS -3.3297749 -38.66783732
OS -3.3297749 -38.66691276
OS -3.3297749 -38.6613654
OS -3.3297749 -38.65304436
OS -3.33069946 -38.6428742
OS -3.33162402 -38.63177948
OS -3.33254858 -38.62068476
OS -3.3343977 -38.60959004
OS -3.33717138 -38.601269
OS -3.33717138 -38.60034444
OS -3.3390205 -38.59757076
OS -3.34086962 -38.59387252
OS -3.3436433 -38.58924972
OS -3.34734154 -38.58370236
OS -3.35196434 -38.578155
OS -3.3575117 -38.57260764
OS -3.36490818 -38.56706028
OS -3.36583274 -38.56613572
OS -3.36860642 -38.56521116
OS -3.37230466 -38.56336204
OS -3.37877658 -38.56058836
OS -3.3852485 -38.55781468
OS -3.39356954 -38.55596556
OS -3.40189058 -38.555041
OS -3.41206074 -38.55411644
OS -3.41668354 -38.55411644
OS -3.42038178 -38.555041
OS -3.42962738 -38.55596556
OS -3.4407221 -38.55781468
OS -3.45366594 -38.56243748
OS -3.46753434 -38.56798484
OS -3.48140274 -38.57630588
OS -3.49434658 -38.5874006
OS -3.49527114 -38.58924972
OS -3.49896938 -38.59387252
OS -3.50451674 -38.601269
OS -3.5100641 -38.61236372
OS -3.51653602 -38.62715668
OS -3.52115882 -38.64472332
OS -3.52485706 -38.6659882
OS -3.52670618 -38.69095132
OS -3.52670618 -38.95999828
OS -3.60529378 -38.95999828
OS -3.60529378 -38.65951628
OS -3.60529378 -38.65859172
OS -3.60529378 -38.6567426
OS -3.60529378 -38.65489348
OS -3.60529378 -38.65119524
OS -3.60621834 -38.64102508
OS -3.60806746 -38.62993036
OS -3.60991658 -38.61698652
OS -3.61361482 -38.60404268
OS -3.61823762 -38.5920234
OS -3.62470954 -38.58092868
OS -3.6256341 -38.58000412
OS -3.62840778 -38.57630588
OS -3.63303058 -38.57260764
OS -3.6395025 -38.56706028
OS -3.64782354 -38.56243748
OS -3.65891826 -38.55781468
OS -3.6718621 -38.555041
OS -3.68757962 -38.55411644
OS -3.69312698 -38.55411644
OS -3.6995989 -38.555041
OS -3.70699538 -38.55596556
OS -3.71624098 -38.55873924
OS -3.7273357 -38.56151292
OS -3.73750586 -38.56613572
OS -3.74860058 -38.57168308
OS -3.74952514 -38.57260764
OS -3.75322338 -38.57538132
OS -3.75784618 -38.57907956
OS -3.7643181 -38.58462692
OS -3.77079002 -38.5920234
OS -3.77726194 -38.601269
OS -3.78373386 -38.61143916
OS -3.78928122 -38.62345844
OS -3.79020578 -38.62530756
OS -3.79113034 -38.62993036
OS -3.79297946 -38.63732684
OS -3.79575314 -38.647497
OS -3.79852682 -38.6613654
OS -3.80037594 -38.67800748
OS -3.8013005 -38.69742324
OS -3.80222506 -38.71961268
OS -3.80222506 -38.95999828
OS -3.88081266 -38.95999828
OS -3.88081266 -38.49586916
OS -3.8105461 -38.49586916
OS -3.8105461 -38.56243748
OS -3.80962154 -38.56058836
OS -3.80684786 -38.55689012
OS -3.8013005 -38.5504182
OS -3.79482858 -38.54302172
OS -3.78650754 -38.53377612
OS -3.77633738 -38.52453052
OS -3.76524266 -38.51528492
OS -3.75229882 -38.50696388
OS -3.7504497 -38.50603932
OS -3.7458269 -38.50326564
OS -3.73843042 -38.50049196
OS -3.72826026 -38.49586916
OS -3.71624098 -38.49217092
OS -3.70237258 -38.48939724
OS -3.68665506 -38.48662356
OS -3.67001298 -38.485699
OS -3.66169194 -38.485699
OS -3.65152178 -38.48662356
OS -3.64042706 -38.48847268
OS -3.62655866 -38.49124636
OS -3.61269026 -38.4949446
OS -3.59882186 -38.50049196
OS -3.58587802 -38.50788844
OS -3.5840289 -38.508813
OS -3.58033066 -38.51158668
OS -3.5747833 -38.51620948
OS -3.56738682 -38.52360596
OS -3.55999034 -38.531927
OS -3.5516693 -38.54209716
OS -3.54427282 -38.55411644
OS -3.53872546 -38.56798484
OS -3.5378009 -38.56706028
OS -3.53595178 -38.5642866
OS -3.5331781 -38.56058836
OS -3.5285553 -38.555041
OS -3.52300794 -38.54856908
OS -3.51653602 -38.54209716
OS -3.50913954 -38.53470068
OS -3.49989394 -38.52637964
OS -3.48972378 -38.51898316
OS -3.47955362 -38.51158668
OS -3.46753434 -38.50511476
OS -3.4545905 -38.49864284
OS -3.4407221 -38.49309548
OS -3.42592914 -38.48939724
OS -3.41113618 -38.48662356
OS -3.3944941 -38.485699
OS -3.38802218 -38.485699
OS -3.38339938 -38.48662356
OE
OB -2.6872057 -39.1375138 I
OS -3.20773298 -39.1375138
OS -3.20773298 -39.08111564
OS -2.6872057 -39.08111564
OS -2.6872057 -39.1375138
OE
OB -0.7410069 -38.48662356 I
OS -0.73361042 -38.48754812
OS -0.72436482 -38.48939724
OS -0.71419466 -38.49124636
OS -0.70217538 -38.49402004
OS -0.69108066 -38.49679372
OS -0.67813682 -38.50141652
OS -0.66611754 -38.50603932
OS -0.6531737 -38.51251124
OS -0.64022986 -38.51990772
OS -0.62728602 -38.52822876
OS -0.61526674 -38.53839892
OS -0.60417202 -38.54949364
OS -0.60324746 -38.5504182
OS -0.60139834 -38.55226732
OS -0.59862466 -38.55596556
OS -0.59492642 -38.56151292
OS -0.59030362 -38.56798484
OS -0.58568082 -38.57538132
OS -0.58013346 -38.58462692
OS -0.5745861 -38.59572164
OS -0.56903874 -38.60774092
OS -0.56349138 -38.62068476
OS -0.55886858 -38.63547772
OS -0.55424578 -38.65119524
OS -0.55054754 -38.66876188
OS -0.54777386 -38.68725308
OS -0.54592474 -38.70666884
OS -0.54500018 -38.72793372
OS -0.54500018 -38.72885828
OS -0.54500018 -38.73255652
OS -0.54500018 -38.73902844
OS -0.54592474 -38.74827404
OS -0.89263474 -38.74827404
OS -0.89263474 -38.7491986
OS -0.89263474 -38.75197228
OS -0.89171018 -38.75567052
OS -0.89171018 -38.76121788
OS -0.89078562 -38.7676898
OS -0.8889365 -38.77508628
OS -0.88616282 -38.79172836
OS -0.88061546 -38.81021956
OS -0.87321898 -38.83055988
OS -0.86304882 -38.84905108
OS -0.85010498 -38.86569316
OS -0.84918042 -38.86569316
OS -0.84825586 -38.86754228
OS -0.8427085 -38.87216508
OS -0.83438746 -38.878637
OS -0.82329274 -38.88510892
OS -0.80849978 -38.8925054
OS -0.7918577 -38.89897732
OS -0.7733665 -38.90360012
OS -0.76319634 -38.90452468
OS -0.75210162 -38.90544924
OS -0.74470514 -38.90544924
OS -0.7363841 -38.90452468
OS -0.72621394 -38.90267556
OS -0.71511922 -38.89990188
OS -0.70217538 -38.89620364
OS -0.6901561 -38.89065628
OS -0.67813682 -38.8832598
OS -0.67721226 -38.88233524
OS -0.67258946 -38.878637
OS -0.6670421 -38.87308964
OS -0.66057018 -38.86569316
OS -0.6531737 -38.855523
OS -0.64485266 -38.84257916
OS -0.63653162 -38.8277862
OS -0.62913514 -38.81021956
OS -0.54777386 -38.82038972
OS -0.54777386 -38.82131428
OS -0.54869842 -38.8231634
OS -0.54962298 -38.82686164
OS -0.5514721 -38.832409
OS -0.55424578 -38.83795636
OS -0.55701946 -38.84535284
OS -0.56441594 -38.86107036
OS -0.57366154 -38.878637
OS -0.58660538 -38.8971282
OS -0.60139834 -38.91469484
OS -0.61988954 -38.93133692
OS -0.6208141 -38.93133692
OS -0.62266322 -38.93318604
OS -0.6254369 -38.93503516
OS -0.62913514 -38.93780884
OS -0.6346825 -38.94058252
OS -0.64022986 -38.9433562
OS -0.64762634 -38.94705444
OS -0.65594738 -38.95075268
OS -0.66519298 -38.95445092
OS -0.67443858 -38.95814916
OS -0.69755258 -38.96369652
OS -0.72344026 -38.96831932
OS -0.75210162 -38.97016844
OS -0.76227178 -38.97016844
OS -0.7687437 -38.96924388
OS -0.77706474 -38.96831932
OS -0.7872349 -38.9664702
OS -0.79832962 -38.96462108
OS -0.8103489 -38.96277196
OS -0.83623658 -38.95537548
OS -0.85010498 -38.94982812
OS -0.86304882 -38.94428076
OS -0.87691722 -38.93688428
OS -0.88986106 -38.92856324
OS -0.90188034 -38.91931764
OS -0.91389962 -38.90822292
OS -0.91482418 -38.90729836
OS -0.9166733 -38.90544924
OS -0.91944698 -38.901751
OS -0.92314522 -38.89620364
OS -0.92776802 -38.88973172
OS -0.93239082 -38.88233524
OS -0.93793818 -38.87308964
OS -0.94348554 -38.86291948
OS -0.9490329 -38.8509002
OS -0.95458026 -38.83795636
OS -0.95920306 -38.8231634
OS -0.96382586 -38.80744588
OS -0.9675241 -38.7908038
OS -0.97029778 -38.7723126
OS -0.9721469 -38.75289684
OS -0.97307146 -38.73255652
OS -0.97307146 -38.73163196
OS -0.97307146 -38.72700916
OS -0.97307146 -38.7214618
OS -0.9721469 -38.71314076
OS -0.97122234 -38.7029706
OS -0.97029778 -38.69187588
OS -0.96844866 -38.67893204
OS -0.96567498 -38.6659882
OS -0.9582785 -38.63640228
OS -0.9536557 -38.62160932
OS -0.94810834 -38.6058918
OS -0.94071186 -38.59109884
OS -0.93239082 -38.57723044
OS -0.92314522 -38.56336204
OS -0.91297506 -38.5504182
OS -0.9120505 -38.54949364
OS -0.91020138 -38.54764452
OS -0.90650314 -38.54487084
OS -0.90188034 -38.54024804
OS -0.89633298 -38.53562524
OS -0.8889365 -38.53007788
OS -0.88061546 -38.52360596
OS -0.8704453 -38.5180586
OS -0.86027514 -38.51158668
OS -0.84825586 -38.50603932
OS -0.83531202 -38.50049196
OS -0.82144362 -38.49586916
OS -0.80665066 -38.49124636
OS -0.79093314 -38.48847268
OS -0.77429106 -38.48662356
OS -0.75672442 -38.485699
OS -0.74747882 -38.485699
OS -0.7410069 -38.48662356
OE
OB -0.37857938 -38.42745172 I
OS -0.39984426 -38.54671996
OS -0.44884594 -38.54671996
OS -0.4682617 -38.42745172
OS -0.4682617 -38.32020276
OS -0.37857938 -38.32020276
OS -0.37857938 -38.42745172
OE
OB -1.4714093 -38.48662356 I
OS -1.4575409 -38.48754812
OS -1.44274794 -38.48939724
OS -1.42703042 -38.49309548
OS -1.41038834 -38.49679372
OS -1.39467082 -38.50234108
OS -1.39374626 -38.50234108
OS -1.3928217 -38.50326564
OS -1.3881989 -38.50511476
OS -1.38080242 -38.508813
OS -1.37155682 -38.5134358
OS -1.36138666 -38.51990772
OS -1.3512165 -38.5273042
OS -1.3419709 -38.53562524
OS -1.33364986 -38.54487084
OS -1.3327253 -38.5457954
OS -1.33087618 -38.54949364
OS -1.32717794 -38.55596556
OS -1.32255514 -38.56336204
OS -1.31793234 -38.57445676
OS -1.31330954 -38.58647604
OS -1.3096113 -38.60034444
OS -1.30591306 -38.61606196
OS -1.38265154 -38.62623212
OS -1.38265154 -38.624383
OS -1.3835761 -38.62068476
OS -1.38542522 -38.61421284
OS -1.3881989 -38.6058918
OS -1.3928217 -38.59757076
OS -1.39836906 -38.58832516
OS -1.40484098 -38.57907956
OS -1.41408658 -38.57075852
OS -1.41501114 -38.56983396
OS -1.41870938 -38.56798484
OS -1.42425674 -38.5642866
OS -1.43257778 -38.56058836
OS -1.44182338 -38.55689012
OS -1.45384266 -38.55319188
OS -1.46863562 -38.55134276
OS -1.48435314 -38.5504182
OS -1.49359874 -38.5504182
OS -1.50284434 -38.55134276
OS -1.51486362 -38.55226732
OS -1.5268829 -38.555041
OS -1.53982674 -38.55781468
OS -1.55184602 -38.56243748
OS -1.56201618 -38.5689094
OS -1.56294074 -38.56983396
OS -1.56571442 -38.57168308
OS -1.56941266 -38.57538132
OS -1.5731109 -38.58092868
OS -1.5777337 -38.58647604
OS -1.58143194 -38.59387252
OS -1.58420562 -38.60219356
OS -1.58513018 -38.6105146
OS -1.58513018 -38.61143916
OS -1.58513018 -38.61328828
OS -1.58420562 -38.61606196
OS -1.58420562 -38.6197602
OS -1.58143194 -38.6290058
OS -1.57588458 -38.6382514
OS -1.57496002 -38.63917596
OS -1.57403546 -38.64010052
OS -1.57218634 -38.6428742
OS -1.5684881 -38.64564788
OS -1.56478986 -38.64842156
OS -1.5592425 -38.6521198
OS -1.55277058 -38.65489348
OS -1.5453741 -38.65859172
OS -1.54444954 -38.65859172
OS -1.54260042 -38.65951628
OS -1.53890218 -38.66044084
OS -1.53243026 -38.66321452
OS -1.52318466 -38.6659882
OS -1.51116538 -38.66876188
OS -1.5037689 -38.67153556
OS -1.49544786 -38.67338468
OS -1.48620226 -38.67615836
OS -1.4760321 -38.67893204
OS -1.47510754 -38.67893204
OS -1.47233386 -38.6798566
OS -1.46771106 -38.68078116
OS -1.4621637 -38.68263028
OS -1.45569178 -38.6844794
OS -1.44737074 -38.68632852
OS -1.4298041 -38.69187588
OS -1.41038834 -38.69742324
OS -1.39097258 -38.70389516
OS -1.37340594 -38.71036708
OS -1.36600946 -38.71314076
OS -1.35953754 -38.71591444
OS -1.35768842 -38.716839
OS -1.35399018 -38.71868812
OS -1.34844282 -38.7214618
OS -1.34012178 -38.7260846
OS -1.33180074 -38.73163196
OS -1.3234797 -38.73902844
OS -1.31515866 -38.74734948
OS -1.30776218 -38.75659508
OS -1.30683762 -38.75751964
OS -1.3049885 -38.76121788
OS -1.30129026 -38.76676524
OS -1.29759202 -38.77508628
OS -1.29481834 -38.78525644
OS -1.2911201 -38.79635116
OS -1.28927098 -38.809295
OS -1.28834642 -38.82408796
OS -1.28834642 -38.82593708
OS -1.28834642 -38.83055988
OS -1.28927098 -38.83795636
OS -1.2911201 -38.84812652
OS -1.29389378 -38.85922124
OS -1.29851658 -38.87124052
OS -1.30406394 -38.88510892
OS -1.31146042 -38.89805276
OS -1.31238498 -38.89990188
OS -1.31608322 -38.90360012
OS -1.32070602 -38.91007204
OS -1.3281025 -38.91746852
OS -1.33827266 -38.92578956
OS -1.34936738 -38.93503516
OS -1.36231122 -38.9433562
OS -1.37802874 -38.95167724
OS -1.3789533 -38.95167724
OS -1.37987786 -38.9526018
OS -1.38542522 -38.95445092
OS -1.39467082 -38.9572246
OS -1.4066901 -38.96092284
OS -1.42148306 -38.96462108
OS -1.43812514 -38.96739476
OS -1.45569178 -38.96924388
OS -1.4760321 -38.97016844
OS -1.48435314 -38.97016844
OS -1.49082506 -38.96924388
OS -1.49822154 -38.96924388
OS -1.50746714 -38.96831932
OS -1.51671274 -38.96739476
OS -1.5268829 -38.96554564
OS -1.54907234 -38.96092284
OS -1.57218634 -38.95445092
OS -1.59437578 -38.94520532
OS -1.60454594 -38.93965796
OS -1.61379154 -38.93318604
OS -1.6147161 -38.93226148
OS -1.61564066 -38.93133692
OS -1.62118802 -38.92578956
OS -1.62950906 -38.91746852
OS -1.63875466 -38.90452468
OS -1.64892482 -38.88880716
OS -1.65909498 -38.87031596
OS -1.66741602 -38.84720196
OS -1.67388794 -38.82131428
OS -1.5962249 -38.809295
OS -1.5962249 -38.81021956
OS -1.5962249 -38.81114412
OS -1.59437578 -38.81669148
OS -1.59252666 -38.82593708
OS -1.58882842 -38.83610724
OS -1.58420562 -38.84720196
OS -1.57865826 -38.85922124
OS -1.57033722 -38.87124052
OS -1.56016706 -38.88141068
OS -1.55831794 -38.88233524
OS -1.5546197 -38.88510892
OS -1.54722322 -38.88880716
OS -1.53797762 -38.89342996
OS -1.52595834 -38.89805276
OS -1.51208994 -38.901751
OS -1.49544786 -38.90452468
OS -1.4760321 -38.90544924
OS -1.4667865 -38.90544924
OS -1.4575409 -38.90452468
OS -1.44552162 -38.90267556
OS -1.43257778 -38.89990188
OS -1.41870938 -38.89620364
OS -1.4066901 -38.89158084
OS -1.39559538 -38.88418436
OS -1.39467082 -38.8832598
OS -1.39097258 -38.88048612
OS -1.38727434 -38.87586332
OS -1.38172698 -38.8693914
OS -1.37710418 -38.86199492
OS -1.37248138 -38.85274932
OS -1.3697077 -38.84350372
OS -1.36878314 -38.832409
OS -1.36878314 -38.83148444
OS -1.36878314 -38.8277862
OS -1.3697077 -38.8231634
OS -1.37155682 -38.81669148
OS -1.3743305 -38.81021956
OS -1.3789533 -38.80374764
OS -1.38450066 -38.79635116
OS -1.3928217 -38.7908038
OS -1.39374626 -38.78987924
OS -1.39651994 -38.78895468
OS -1.40114274 -38.786181
OS -1.40853922 -38.78340732
OS -1.41963394 -38.77970908
OS -1.42610586 -38.7769354
OS -1.43350234 -38.77508628
OS -1.44182338 -38.7723126
OS -1.45106898 -38.76953892
OS -1.46123914 -38.76676524
OS -1.47325842 -38.76399156
OS -1.47418298 -38.76399156
OS -1.47695666 -38.763067
OS -1.48157946 -38.76214244
OS -1.48712682 -38.76029332
OS -1.4945233 -38.7584442
OS -1.50284434 -38.75567052
OS -1.52041098 -38.75104772
OS -1.5407513 -38.7445758
OS -1.56016706 -38.73902844
OS -1.57865826 -38.73255652
OS -1.5869793 -38.72885828
OS -1.59345122 -38.7260846
OS -1.59530034 -38.72516004
OS -1.59899858 -38.72331092
OS -1.60454594 -38.71961268
OS -1.61194242 -38.71498988
OS -1.62026346 -38.70851796
OS -1.6285845 -38.70112148
OS -1.63690554 -38.69280044
OS -1.64430202 -38.68263028
OS -1.64522658 -38.68170572
OS -1.6470757 -38.67800748
OS -1.64984938 -38.67153556
OS -1.65262306 -38.66413908
OS -1.65539674 -38.65489348
OS -1.65817042 -38.64379876
OS -1.66001954 -38.63270404
OS -1.6609441 -38.6197602
OS -1.6609441 -38.61791108
OS -1.6609441 -38.61421284
OS -1.66001954 -38.60866548
OS -1.65909498 -38.60034444
OS -1.65724586 -38.5920234
OS -1.65539674 -38.58185324
OS -1.6516985 -38.57260764
OS -1.6470757 -38.56243748
OS -1.64615114 -38.56151292
OS -1.64430202 -38.55781468
OS -1.64152834 -38.55319188
OS -1.63690554 -38.54671996
OS -1.63135818 -38.54024804
OS -1.62488626 -38.531927
OS -1.61748978 -38.52453052
OS -1.60824418 -38.5180586
OS -1.60731962 -38.51713404
OS -1.60454594 -38.51620948
OS -1.6008477 -38.5134358
OS -1.59530034 -38.51066212
OS -1.58790386 -38.50696388
OS -1.57958282 -38.50326564
OS -1.56941266 -38.4995674
OS -1.55831794 -38.49586916
OS -1.55646882 -38.4949446
OS -1.55277058 -38.49402004
OS -1.54629866 -38.49217092
OS -1.53797762 -38.4903218
OS -1.52780746 -38.48847268
OS -1.51671274 -38.48754812
OS -1.5037689 -38.485699
OS -1.48157946 -38.485699
OS -1.4714093 -38.48662356
OE
OB -1.10343442 -38.49586916 I
OS -1.02392226 -38.49586916
OS -1.02392226 -38.55689012
OS -1.10343442 -38.55689012
OS -1.10343442 -38.82963532
OS -1.10343442 -38.83148444
OS -1.10343442 -38.83518268
OS -1.10343442 -38.84073004
OS -1.10250986 -38.84720196
OS -1.1015853 -38.86199492
OS -1.10066074 -38.86846684
OS -1.09973618 -38.87308964
OS -1.09881162 -38.87493876
OS -1.09603794 -38.878637
OS -1.0923397 -38.8832598
OS -1.08586778 -38.8878826
OS -1.08401866 -38.88880716
OS -1.07939586 -38.89065628
OS -1.07107482 -38.8925054
OS -1.05905554 -38.89342996
OS -1.04980994 -38.89342996
OS -1.04518714 -38.8925054
OS -1.03871522 -38.8925054
OS -1.03131874 -38.89158084
OS -1.02392226 -38.89065628
OS -1.0137521 -38.95999828
OS -1.01560122 -38.95999828
OS -1.01929946 -38.96092284
OS -1.02577138 -38.9618474
OS -1.03409242 -38.96277196
OS -1.04333802 -38.96462108
OS -1.05350818 -38.96554564
OS -1.0738485 -38.9664702
OS -1.08124498 -38.9664702
OS -1.08864146 -38.96554564
OS -1.09788706 -38.96462108
OS -1.10898178 -38.96369652
OS -1.1200765 -38.96092284
OS -1.13024666 -38.95814916
OS -1.14041682 -38.95352636
OS -1.14134138 -38.9526018
OS -1.14411506 -38.95075268
OS -1.1478133 -38.947979
OS -1.15336066 -38.9433562
OS -1.15798346 -38.9387334
OS -1.16353082 -38.93226148
OS -1.16907818 -38.92578956
OS -1.17277642 -38.91746852
OS -1.17277642 -38.91654396
OS -1.17462554 -38.91284572
OS -1.1755501 -38.9063738
OS -1.17739922 -38.8971282
OS -1.17924834 -38.88510892
OS -1.1801729 -38.87771244
OS -1.1801729 -38.8693914
OS -1.18109746 -38.85922124
OS -1.18202202 -38.84905108
OS -1.18202202 -38.83795636
OS -1.18202202 -38.82501252
OS -1.18202202 -38.55689012
OS -1.2402693 -38.55689012
OS -1.2402693 -38.49586916
OS -1.18202202 -38.49586916
OS -1.18202202 -38.38122372
OS -1.10343442 -38.33407116
OS -1.10343442 -38.49586916
OE
OB -4.17389818 -38.48662356 I
OS -4.16557714 -38.48754812
OS -4.15633154 -38.48939724
OS -4.14616138 -38.49124636
OS -4.1341421 -38.49309548
OS -4.10917898 -38.50141652
OS -4.09623514 -38.50603932
OS -4.0832913 -38.51251124
OS -4.07034746 -38.51898316
OS -4.05740362 -38.52822876
OS -4.04538434 -38.53747436
OS -4.03336506 -38.54856908
OS -4.0324405 -38.54949364
OS -4.03059138 -38.55134276
OS -4.0278177 -38.555041
OS -4.02411946 -38.5596638
OS -4.01949666 -38.56613572
OS -4.0139493 -38.57445676
OS -4.00840194 -38.58370236
OS -4.00285458 -38.59387252
OS -3.99730722 -38.60496724
OS -3.99175986 -38.61883564
OS -3.9862125 -38.63270404
OS -3.9815897 -38.64842156
OS -3.97789146 -38.66506364
OS -3.97511778 -38.68263028
OS -3.97326866 -38.70112148
OS -3.9723441 -38.7214618
OS -3.9723441 -38.72238636
OS -3.9723441 -38.72516004
OS -3.9723441 -38.72978284
OS -3.9723441 -38.73625476
OS -3.97326866 -38.74365124
OS -3.97419322 -38.75289684
OS -3.97419322 -38.76214244
OS -3.97604234 -38.7723126
OS -3.97881602 -38.7954266
OS -3.98436338 -38.8185406
OS -3.9908353 -38.8416546
OS -4.0000809 -38.86291948
OS -4.0000809 -38.86384404
OS -4.00100546 -38.8647686
OS -4.00285458 -38.86754228
OS -4.0047037 -38.87124052
OS -4.01117562 -38.88048612
OS -4.01949666 -38.89158084
OS -4.03059138 -38.90452468
OS -4.04445978 -38.91746852
OS -4.0601773 -38.93041236
OS -4.0786685 -38.94243164
OS -4.07959306 -38.94243164
OS -4.08051762 -38.9433562
OS -4.0832913 -38.94520532
OS -4.0879141 -38.94705444
OS -4.0925369 -38.94890356
OS -4.09808426 -38.95075268
OS -4.11195266 -38.95630004
OS -4.12767018 -38.96092284
OS -4.14708594 -38.96554564
OS -4.16742626 -38.96924388
OS -4.1896157 -38.97016844
OS -4.1988613 -38.97016844
OS -4.20625778 -38.96924388
OS -4.21457882 -38.96831932
OS -4.22382442 -38.9664702
OS -4.23491914 -38.96462108
OS -4.24601386 -38.96277196
OS -4.27097698 -38.95537548
OS -4.28484538 -38.94982812
OS -4.29778922 -38.94428076
OS -4.31073306 -38.93688428
OS -4.3236769 -38.92856324
OS -4.33569618 -38.91931764
OS -4.34771546 -38.90822292
OS -4.34864002 -38.90729836
OS -4.35048914 -38.90544924
OS -4.35326282 -38.901751
OS -4.35696106 -38.89620364
OS -4.36158386 -38.88973172
OS -4.36620666 -38.88233524
OS -4.37175402 -38.87308964
OS -4.37730138 -38.86199492
OS -4.38284874 -38.84997564
OS -4.3883961 -38.83610724
OS -4.3930189 -38.82131428
OS -4.3976417 -38.80559676
OS -4.40133994 -38.78803012
OS -4.40411362 -38.76953892
OS -4.40596274 -38.7491986
OS -4.4068873 -38.72793372
OS -4.4068873 -38.7260846
OS -4.4068873 -38.72238636
OS -4.40596274 -38.71591444
OS -4.40596274 -38.70666884
OS -4.40503818 -38.69649868
OS -4.40318906 -38.68355484
OS -4.40133994 -38.670611
OS -4.3976417 -38.65581804
OS -4.39394346 -38.64102508
OS -4.38932066 -38.62530756
OS -4.3837733 -38.60866548
OS -4.37637682 -38.59294796
OS -4.36898034 -38.578155
OS -4.35881018 -38.56336204
OS -4.34864002 -38.54949364
OS -4.33569618 -38.53747436
OS -4.33477162 -38.5365498
OS -4.3329225 -38.53562524
OS -4.32922426 -38.53285156
OS -4.32460146 -38.52915332
OS -4.3190541 -38.52545508
OS -4.31165762 -38.52083228
OS -4.30426114 -38.51620948
OS -4.29501554 -38.51158668
OS -4.28484538 -38.50696388
OS -4.27375066 -38.50234108
OS -4.24878754 -38.49402004
OS -4.22012618 -38.48754812
OS -4.20533322 -38.48662356
OS -4.1896157 -38.485699
OS -4.1803701 -38.485699
OS -4.17389818 -38.48662356
OE
OB -5.16872474 -38.48662356 I
OS -5.1604037 -38.48754812
OS -5.1511581 -38.48939724
OS -5.14098794 -38.49124636
OS -5.12896866 -38.49309548
OS -5.10400554 -38.50141652
OS -5.0910617 -38.50603932
OS -5.07811786 -38.51251124
OS -5.06517402 -38.51898316
OS -5.05223018 -38.52822876
OS -5.0402109 -38.53747436
OS -5.02819162 -38.54856908
OS -5.02726706 -38.54949364
OS -5.02541794 -38.55134276
OS -5.02264426 -38.555041
OS -5.01894602 -38.5596638
OS -5.01432322 -38.56613572
OS -5.00877586 -38.57445676
OS -5.0032285 -38.58370236
OS -4.99768114 -38.59387252
OS -4.99213378 -38.60496724
OS -4.98658642 -38.61883564
OS -4.98103906 -38.63270404
OS -4.97641626 -38.64842156
OS -4.97271802 -38.66506364
OS -4.96994434 -38.68263028
OS -4.96809522 -38.70112148
OS -4.96717066 -38.7214618
OS -4.96717066 -38.72238636
OS -4.96717066 -38.72516004
OS -4.96717066 -38.72978284
OS -4.96717066 -38.73625476
OS -4.96809522 -38.74365124
OS -4.96901978 -38.75289684
OS -4.96901978 -38.76214244
OS -4.9708689 -38.7723126
OS -4.97364258 -38.7954266
OS -4.97918994 -38.8185406
OS -4.98566186 -38.8416546
OS -4.99490746 -38.86291948
OS -4.99490746 -38.86384404
OS -4.99583202 -38.8647686
OS -4.99768114 -38.86754228
OS -4.99953026 -38.87124052
OS -5.00600218 -38.88048612
OS -5.01432322 -38.89158084
OS -5.02541794 -38.90452468
OS -5.03928634 -38.91746852
OS -5.05500386 -38.93041236
OS -5.07349506 -38.94243164
OS -5.07441962 -38.94243164
OS -5.07534418 -38.9433562
OS -5.07811786 -38.94520532
OS -5.08274066 -38.94705444
OS -5.08736346 -38.94890356
OS -5.09291082 -38.95075268
OS -5.10677922 -38.95630004
OS -5.12249674 -38.96092284
OS -5.1419125 -38.96554564
OS -5.16225282 -38.96924388
OS -5.18444226 -38.97016844
OS -5.19368786 -38.97016844
OS -5.20108434 -38.96924388
OS -5.20940538 -38.96831932
OS -5.21865098 -38.9664702
OS -5.2297457 -38.96462108
OS -5.24084042 -38.96277196
OS -5.26580354 -38.95537548
OS -5.27967194 -38.94982812
OS -5.29261578 -38.94428076
OS -5.30555962 -38.93688428
OS -5.31850346 -38.92856324
OS -5.33052274 -38.91931764
OS -5.34254202 -38.90822292
OS -5.34346658 -38.90729836
OS -5.3453157 -38.90544924
OS -5.34808938 -38.901751
OS -5.35178762 -38.89620364
OS -5.35641042 -38.88973172
OS -5.36103322 -38.88233524
OS -5.36658058 -38.87308964
OS -5.37212794 -38.86199492
OS -5.3776753 -38.84997564
OS -5.38322266 -38.83610724
OS -5.38784546 -38.82131428
OS -5.39246826 -38.80559676
OS -5.3961665 -38.78803012
OS -5.39894018 -38.76953892
OS -5.4007893 -38.7491986
OS -5.40171386 -38.72793372
OS -5.40171386 -38.7260846
OS -5.40171386 -38.72238636
OS -5.4007893 -38.71591444
OS -5.4007893 -38.70666884
OS -5.39986474 -38.69649868
OS -5.39801562 -38.68355484
OS -5.3961665 -38.670611
OS -5.39246826 -38.65581804
OS -5.38877002 -38.64102508
OS -5.38414722 -38.62530756
OS -5.37859986 -38.60866548
OS -5.37120338 -38.59294796
OS -5.3638069 -38.578155
OS -5.35363674 -38.56336204
OS -5.34346658 -38.54949364
OS -5.33052274 -38.53747436
OS -5.32959818 -38.5365498
OS -5.32774906 -38.53562524
OS -5.32405082 -38.53285156
OS -5.31942802 -38.52915332
OS -5.31388066 -38.52545508
OS -5.30648418 -38.52083228
OS -5.2990877 -38.51620948
OS -5.2898421 -38.51158668
OS -5.27967194 -38.50696388
OS -5.26857722 -38.50234108
OS -5.2436141 -38.49402004
OS -5.21495274 -38.48754812
OS -5.20015978 -38.48662356
OS -5.18444226 -38.485699
OS -5.17519666 -38.485699
OS -5.16872474 -38.48662356
OE
OB -5.97031826 -38.42745172 I
OS -5.99158314 -38.54671996
OS -6.04058482 -38.54671996
OS -6.06000058 -38.42745172
OS -6.06000058 -38.32020276
OS -5.97031826 -38.32020276
OS -5.97031826 -38.42745172
OE
OB -5.79280274 -38.54856908 I
OS -5.79187818 -38.54764452
OS -5.79095362 -38.5457954
OS -5.78817994 -38.54302172
OS -5.78355714 -38.53839892
OS -5.77893434 -38.53377612
OS -5.77338698 -38.52822876
OS -5.7659905 -38.5226814
OS -5.75859402 -38.51713404
OS -5.74010282 -38.50511476
OS -5.71883794 -38.49586916
OS -5.70681866 -38.49124636
OS -5.69387482 -38.48847268
OS -5.68000642 -38.48662356
OS -5.66613802 -38.485699
OS -5.65874154 -38.485699
OS -5.6504205 -38.48662356
OS -5.64025034 -38.48754812
OS -5.62823106 -38.4903218
OS -5.61436266 -38.49309548
OS -5.5995697 -38.49771828
OS -5.5857013 -38.50326564
OS -5.58385218 -38.5041902
OS -5.57922938 -38.50603932
OS -5.5718329 -38.51066212
OS -5.56351186 -38.51620948
OS -5.5533417 -38.5226814
OS -5.54317154 -38.53100244
OS -5.53207682 -38.5411726
OS -5.52283122 -38.55226732
OS -5.52190666 -38.55319188
OS -5.51913298 -38.55781468
OS -5.51451018 -38.5642866
OS -5.50896282 -38.57260764
OS -5.5024909 -38.58370236
OS -5.49601898 -38.5966462
OS -5.48954706 -38.61143916
OS -5.4839997 -38.62715668
OS -5.4839997 -38.62808124
OS -5.48307514 -38.6290058
OS -5.48215058 -38.63177948
OS -5.48122602 -38.63455316
OS -5.4793769 -38.64379876
OS -5.47660322 -38.65581804
OS -5.47382954 -38.66968644
OS -5.47105586 -38.68540396
OS -5.4701313 -38.7029706
OS -5.46920674 -38.7214618
OS -5.46920674 -38.72238636
OS -5.46920674 -38.72700916
OS -5.46920674 -38.73255652
OS -5.4701313 -38.74087756
OS -5.47105586 -38.75104772
OS -5.47198042 -38.76214244
OS -5.47382954 -38.77508628
OS -5.47660322 -38.78895468
OS -5.4839997 -38.8185406
OS -5.4886225 -38.83425812
OS -5.49416986 -38.84905108
OS -5.50064178 -38.8647686
OS -5.50896282 -38.878637
OS -5.51820842 -38.8925054
OS -5.52837858 -38.90544924
OS -5.52930314 -38.9063738
OS -5.53115226 -38.90822292
OS -5.53392594 -38.9109966
OS -5.53854874 -38.9156194
OS -5.54502066 -38.9202422
OS -5.55149258 -38.92578956
OS -5.55888906 -38.93133692
OS -5.56813466 -38.93780884
OS -5.57830482 -38.9433562
OS -5.58847498 -38.94982812
OS -5.6134381 -38.95999828
OS -5.62638194 -38.96462108
OS -5.64025034 -38.96739476
OS -5.6550433 -38.96924388
OS -5.66983626 -38.97016844
OS -5.6735345 -38.97016844
OS -5.6781573 -38.96924388
OS -5.68370466 -38.96924388
OS -5.69017658 -38.96831932
OS -5.69849762 -38.9664702
OS -5.71698882 -38.9618474
OS -5.72715898 -38.95814916
OS -5.73732914 -38.95352636
OS -5.74842386 -38.947979
OS -5.75859402 -38.94150708
OS -5.76968874 -38.93318604
OS -5.7798589 -38.92394044
OS -5.7891045 -38.91377028
OS -5.7983501 -38.901751
OS -5.7983501 -38.95999828
OS -5.87139034 -38.95999828
OS -5.87139034 -38.32020276
OS -5.79280274 -38.32020276
OS -5.79280274 -38.54856908
OE
OB -4.78318322 -38.49586916 I
OS -4.70367106 -38.49586916
OS -4.70367106 -38.55689012
OS -4.78318322 -38.55689012
OS -4.78318322 -38.82963532
OS -4.78318322 -38.83148444
OS -4.78318322 -38.83518268
OS -4.78318322 -38.84073004
OS -4.78225866 -38.84720196
OS -4.7813341 -38.86199492
OS -4.78040954 -38.86846684
OS -4.77948498 -38.87308964
OS -4.77856042 -38.87493876
OS -4.77578674 -38.878637
OS -4.7720885 -38.8832598
OS -4.76561658 -38.8878826
OS -4.76376746 -38.88880716
OS -4.75914466 -38.89065628
OS -4.75082362 -38.8925054
OS -4.73880434 -38.89342996
OS -4.72955874 -38.89342996
OS -4.72493594 -38.8925054
OS -4.71846402 -38.8925054
OS -4.71106754 -38.89158084
OS -4.70367106 -38.89065628
OS -4.6935009 -38.95999828
OS -4.69535002 -38.95999828
OS -4.69904826 -38.96092284
OS -4.70552018 -38.9618474
OS -4.71384122 -38.96277196
OS -4.72308682 -38.96462108
OS -4.73325698 -38.96554564
OS -4.7535973 -38.9664702
OS -4.76099378 -38.9664702
OS -4.76839026 -38.96554564
OS -4.77763586 -38.96462108
OS -4.78873058 -38.96369652
OS -4.7998253 -38.96092284
OS -4.80999546 -38.95814916
OS -4.82016562 -38.95352636
OS -4.82109018 -38.9526018
OS -4.82386386 -38.95075268
OS -4.8275621 -38.947979
OS -4.83310946 -38.9433562
OS -4.83773226 -38.9387334
OS -4.84327962 -38.93226148
OS -4.84882698 -38.92578956
OS -4.85252522 -38.91746852
OS -4.85252522 -38.91654396
OS -4.85437434 -38.91284572
OS -4.8552989 -38.9063738
OS -4.85714802 -38.8971282
OS -4.85899714 -38.88510892
OS -4.8599217 -38.87771244
OS -4.8599217 -38.8693914
OS -4.86084626 -38.85922124
OS -4.86177082 -38.84905108
OS -4.86177082 -38.83795636
OS -4.86177082 -38.82501252
OS -4.86177082 -38.55689012
OS -4.9200181 -38.55689012
OS -4.9200181 -38.49586916
OS -4.86177082 -38.49586916
OS -4.86177082 -38.38122372
OS -4.78318322 -38.33407116
OS -4.78318322 -38.49586916
OE
OB -4.53447658 -38.49586916 I
OS -4.45496442 -38.49586916
OS -4.45496442 -38.55689012
OS -4.53447658 -38.55689012
OS -4.53447658 -38.82963532
OS -4.53447658 -38.83148444
OS -4.53447658 -38.83518268
OS -4.53447658 -38.84073004
OS -4.53355202 -38.84720196
OS -4.53262746 -38.86199492
OS -4.5317029 -38.86846684
OS -4.53077834 -38.87308964
OS -4.52985378 -38.87493876
OS -4.5270801 -38.878637
OS -4.52338186 -38.8832598
OS -4.51690994 -38.8878826
OS -4.51506082 -38.88880716
OS -4.51043802 -38.89065628
OS -4.50211698 -38.8925054
OS -4.4900977 -38.89342996
OS -4.4808521 -38.89342996
OS -4.4762293 -38.8925054
OS -4.46975738 -38.8925054
OS -4.4623609 -38.89158084
OS -4.45496442 -38.89065628
OS -4.44479426 -38.95999828
OS -4.44664338 -38.95999828
OS -4.45034162 -38.96092284
OS -4.45681354 -38.9618474
OS -4.46513458 -38.96277196
OS -4.47438018 -38.96462108
OS -4.48455034 -38.96554564
OS -4.50489066 -38.9664702
OS -4.51228714 -38.9664702
OS -4.51968362 -38.96554564
OS -4.52892922 -38.96462108
OS -4.54002394 -38.96369652
OS -4.55111866 -38.96092284
OS -4.56128882 -38.95814916
OS -4.57145898 -38.95352636
OS -4.57238354 -38.9526018
OS -4.57515722 -38.95075268
OS -4.57885546 -38.947979
OS -4.58440282 -38.9433562
OS -4.58902562 -38.9387334
OS -4.59457298 -38.93226148
OS -4.60012034 -38.92578956
OS -4.60381858 -38.91746852
OS -4.60381858 -38.91654396
OS -4.6056677 -38.91284572
OS -4.60659226 -38.9063738
OS -4.60844138 -38.8971282
OS -4.6102905 -38.88510892
OS -4.61121506 -38.87771244
OS -4.61121506 -38.8693914
OS -4.61213962 -38.85922124
OS -4.61306418 -38.84905108
OS -4.61306418 -38.83795636
OS -4.61306418 -38.82501252
OS -4.61306418 -38.55689012
OS -4.67131146 -38.55689012
OS -4.67131146 -38.49586916
OS -4.61306418 -38.49586916
OS -4.61306418 -38.38122372
OS -4.53447658 -38.33407116
OS -4.53447658 -38.49586916
OE
OB -5.6642889 -38.5504182 H
OS -5.6781573 -38.5504182
OS -5.68185554 -38.55134276
OS -5.6920257 -38.55319188
OS -5.70404498 -38.55596556
OS -5.71791338 -38.56151292
OS -5.73270634 -38.56983396
OS -5.74010282 -38.57445676
OS -5.7474993 -38.58092868
OS -5.75489578 -38.5874006
OS -5.76229226 -38.59572164
OS -5.76229226 -38.5966462
OS -5.76414138 -38.59757076
OS -5.7659905 -38.60034444
OS -5.76783962 -38.60404268
OS -5.7706133 -38.60866548
OS -5.77431154 -38.61421284
OS -5.77708522 -38.62068476
OS -5.78078346 -38.62808124
OS -5.7844817 -38.63732684
OS -5.78725538 -38.64657244
OS -5.79095362 -38.65766716
OS -5.7937273 -38.66876188
OS -5.79557642 -38.68170572
OS -5.79742554 -38.69557412
OS -5.79927466 -38.70944252
OS -5.79927466 -38.72516004
OS -5.79927466 -38.7260846
OS -5.79927466 -38.72885828
OS -5.79927466 -38.73348108
OS -5.79927466 -38.73902844
OS -5.7983501 -38.74550036
OS -5.7983501 -38.7538214
OS -5.79650098 -38.77138804
OS -5.7937273 -38.7908038
OS -5.79002906 -38.81114412
OS -5.7844817 -38.82963532
OS -5.78078346 -38.83795636
OS -5.77708522 -38.84535284
OS -5.77708522 -38.8462774
OS -5.7752361 -38.84812652
OS -5.77338698 -38.8509002
OS -5.7706133 -38.85459844
OS -5.76229226 -38.8647686
OS -5.75027298 -38.87493876
OS -5.73640458 -38.88603348
OS -5.71883794 -38.89620364
OS -5.70959234 -38.89990188
OS -5.69849762 -38.90267556
OS -5.68832746 -38.90452468
OS -5.67630818 -38.90544924
OS -5.67168538 -38.90544924
OS -5.66798714 -38.90452468
OS -5.65781698 -38.90267556
OS -5.6457977 -38.89990188
OS -5.6319293 -38.89435452
OS -5.61713634 -38.88695804
OS -5.60234338 -38.87586332
OS -5.5949469 -38.86846684
OS -5.58755042 -38.86107036
OS -5.58755042 -38.8601458
OS -5.5857013 -38.85922124
OS -5.58385218 -38.85644756
OS -5.58200306 -38.85274932
OS -5.57830482 -38.84812652
OS -5.57553114 -38.84257916
OS -5.5718329 -38.83518268
OS -5.56813466 -38.8277862
OS -5.56536098 -38.8185406
OS -5.56166274 -38.809295
OS -5.5579645 -38.79820028
OS -5.55519082 -38.786181
OS -5.5533417 -38.77323716
OS -5.55149258 -38.75936876
OS -5.54964346 -38.74365124
OS -5.54964346 -38.72793372
OS -5.54964346 -38.72700916
OS -5.54964346 -38.72423548
OS -5.54964346 -38.71961268
OS -5.55056802 -38.71314076
OS -5.55056802 -38.70574428
OS -5.55149258 -38.69649868
OS -5.55426626 -38.67708292
OS -5.5579645 -38.65581804
OS -5.56443642 -38.63270404
OS -5.57368202 -38.61236372
OS -5.57922938 -38.60219356
OS -5.5857013 -38.59387252
OS -5.5857013 -38.59294796
OS -5.58755042 -38.5920234
OS -5.59217322 -38.5874006
OS -5.5995697 -38.58000412
OS -5.60973986 -38.57168308
OS -5.6226837 -38.5642866
OS -5.63747666 -38.55689012
OS -5.6550433 -38.55226732
OS -5.6642889 -38.5504182
OE
OB -0.75579986 -38.5504182 H
OS -0.76134722 -38.5504182
OS -0.76504546 -38.55134276
OS -0.77521562 -38.55226732
OS -0.7872349 -38.555041
OS -0.80202786 -38.5596638
OS -0.81774538 -38.56613572
OS -0.83253834 -38.57538132
OS -0.8473313 -38.5874006
OS -0.84918042 -38.58924972
OS -0.85287866 -38.59387252
OS -0.85935058 -38.60219356
OS -0.8658225 -38.61328828
OS -0.87321898 -38.62623212
OS -0.8796909 -38.6428742
OS -0.88523826 -38.66228996
OS -0.88801194 -38.68355484
OS -0.62821058 -38.68355484
OS -0.62821058 -38.68263028
OS -0.62821058 -38.68078116
OS -0.62913514 -38.67800748
OS -0.62913514 -38.67430924
OS -0.63098426 -38.66321452
OS -0.63375794 -38.65119524
OS -0.63838074 -38.63640228
OS -0.64300354 -38.62253388
OS -0.65040002 -38.60866548
OS -0.65872106 -38.5966462
OS -0.65872106 -38.59572164
OS -0.66057018 -38.59479708
OS -0.66519298 -38.58924972
OS -0.67351402 -38.58185324
OS -0.68460874 -38.5735322
OS -0.69847714 -38.56521116
OS -0.71511922 -38.55781468
OS -0.73453498 -38.55226732
OS -0.74470514 -38.55134276
OS -0.75579986 -38.5504182
OE
OB -4.1896157 -38.5504182 H
OS -4.19516306 -38.5504182
OS -4.19978586 -38.55134276
OS -4.20995602 -38.55226732
OS -4.22382442 -38.55596556
OS -4.23954194 -38.56151292
OS -4.25618402 -38.5689094
OS -4.27190154 -38.58000412
OS -4.28022258 -38.5874006
OS -4.28761906 -38.59479708
OS -4.28761906 -38.59572164
OS -4.28946818 -38.5966462
OS -4.2913173 -38.59941988
OS -4.29409098 -38.60311812
OS -4.29686466 -38.60774092
OS -4.29963834 -38.61328828
OS -4.30333658 -38.62068476
OS -4.30703482 -38.62808124
OS -4.31073306 -38.63732684
OS -4.3144313 -38.64657244
OS -4.31720498 -38.65766716
OS -4.31997866 -38.66968644
OS -4.32275234 -38.68263028
OS -4.32460146 -38.69649868
OS -4.32552602 -38.7122162
OS -4.32645058 -38.72793372
OS -4.32645058 -38.72885828
OS -4.32645058 -38.73163196
OS -4.32645058 -38.73625476
OS -4.32552602 -38.74272668
OS -4.32552602 -38.75012316
OS -4.32460146 -38.7584442
OS -4.32182778 -38.77785996
OS -4.31720498 -38.8000494
OS -4.3098085 -38.82223884
OS -4.3005629 -38.84350372
OS -4.29409098 -38.85274932
OS -4.28761906 -38.86199492
OS -4.2866945 -38.86199492
OS -4.28576994 -38.86384404
OS -4.28022258 -38.86846684
OS -4.27190154 -38.87586332
OS -4.26080682 -38.8832598
OS -4.24693842 -38.89158084
OS -4.23029634 -38.89897732
OS -4.21088058 -38.90360012
OS -4.20071042 -38.90452468
OS -4.1896157 -38.90544924
OS -4.18406834 -38.90544924
OS -4.17944554 -38.90452468
OS -4.16927538 -38.90267556
OS -4.15540698 -38.89990188
OS -4.14061402 -38.89435452
OS -4.12397194 -38.88695804
OS -4.10825442 -38.87586332
OS -4.09993338 -38.86846684
OS -4.0925369 -38.86107036
OS -4.09161234 -38.8601458
OS -4.09068778 -38.85922124
OS -4.08883866 -38.85644756
OS -4.08606498 -38.85274932
OS -4.0832913 -38.84812652
OS -4.07959306 -38.84257916
OS -4.07589482 -38.83518268
OS -4.07219658 -38.8277862
OS -4.06849834 -38.8185406
OS -4.06572466 -38.80837044
OS -4.06202642 -38.79727572
OS -4.05925274 -38.78525644
OS -4.05647906 -38.77138804
OS -4.05462994 -38.75751964
OS -4.05278082 -38.74180212
OS -4.05278082 -38.72516004
OS -4.05278082 -38.72423548
OS -4.05278082 -38.7214618
OS -4.05278082 -38.716839
OS -4.05370538 -38.71129164
OS -4.05370538 -38.70389516
OS -4.05462994 -38.69557412
OS -4.05740362 -38.67615836
OS -4.06202642 -38.65581804
OS -4.0694229 -38.6336286
OS -4.07959306 -38.61328828
OS -4.08514042 -38.60311812
OS -4.0925369 -38.59479708
OS -4.0925369 -38.59387252
OS -4.09438602 -38.59294796
OS -4.09993338 -38.5874006
OS -4.10825442 -38.58092868
OS -4.11934914 -38.57260764
OS -4.13321754 -38.5642866
OS -4.14985962 -38.55689012
OS -4.16835082 -38.55226732
OS -4.17852098 -38.55134276
OS -4.1896157 -38.5504182
OE
OB -2.43942362 -38.54764452 H
OS -2.44404642 -38.54764452
OS -2.44774466 -38.54856908
OS -2.45699026 -38.5504182
OS -2.46900954 -38.55319188
OS -2.48287794 -38.55873924
OS -2.4976709 -38.56706028
OS -2.50599194 -38.57260764
OS -2.51338842 -38.57907956
OS -2.5207849 -38.58647604
OS -2.52818138 -38.59479708
OS -2.52818138 -38.59572164
OS -2.5300305 -38.5966462
OS -2.53187962 -38.59941988
OS -2.53372874 -38.60311812
OS -2.53650242 -38.60866548
OS -2.54020066 -38.61421284
OS -2.5438989 -38.62160932
OS -2.54667258 -38.6290058
OS -2.55037082 -38.6382514
OS -2.55406906 -38.64842156
OS -2.55684274 -38.65951628
OS -2.56054098 -38.67153556
OS -2.5623901 -38.68540396
OS -2.56423922 -38.69927236
OS -2.56608834 -38.71406532
OS -2.56608834 -38.7307074
OS -2.56608834 -38.73163196
OS -2.56608834 -38.73440564
OS -2.56608834 -38.73902844
OS -2.56516378 -38.74550036
OS -2.56516378 -38.75289684
OS -2.56423922 -38.76121788
OS -2.56146554 -38.78063364
OS -2.55684274 -38.80282308
OS -2.55129538 -38.82408796
OS -2.54204978 -38.84535284
OS -2.53650242 -38.85459844
OS -2.5300305 -38.86291948
OS -2.52818138 -38.8647686
OS -2.52355858 -38.8693914
OS -2.5161621 -38.87678788
OS -2.50599194 -38.88418436
OS -2.4930481 -38.89158084
OS -2.47825514 -38.89897732
OS -2.46161306 -38.90360012
OS -2.45236746 -38.90452468
OS -2.44312186 -38.90544924
OS -2.4375745 -38.90544924
OS -2.43387626 -38.90452468
OS -2.42463066 -38.90267556
OS -2.41168682 -38.89990188
OS -2.39781842 -38.89435452
OS -2.38302546 -38.88695804
OS -2.3682325 -38.87586332
OS -2.36083602 -38.8693914
OS -2.35343954 -38.86199492
OS -2.35343954 -38.86107036
OS -2.35159042 -38.8601458
OS -2.3497413 -38.85737212
OS -2.34789218 -38.85367388
OS -2.34419394 -38.84905108
OS -2.34142026 -38.84257916
OS -2.33772202 -38.83610724
OS -2.33402378 -38.8277862
OS -2.3312501 -38.81946516
OS -2.32755186 -38.80837044
OS -2.32385362 -38.79727572
OS -2.32107994 -38.78525644
OS -2.31923082 -38.77138804
OS -2.3173817 -38.75659508
OS -2.31553258 -38.74087756
OS -2.31553258 -38.72423548
OS -2.31553258 -38.72331092
OS -2.31553258 -38.72053724
OS -2.31553258 -38.71591444
OS -2.31645714 -38.70944252
OS -2.31645714 -38.70204604
OS -2.3173817 -38.693725
OS -2.32015538 -38.67430924
OS -2.32477818 -38.65304436
OS -2.3312501 -38.63177948
OS -2.3404957 -38.6105146
OS -2.34604306 -38.60034444
OS -2.35251498 -38.5920234
OS -2.35251498 -38.59109884
OS -2.3543641 -38.59017428
OS -2.3589869 -38.58462692
OS -2.36638338 -38.578155
OS -2.37655354 -38.56983396
OS -2.38949738 -38.56151292
OS -2.40429034 -38.55411644
OS -2.42093242 -38.54949364
OS -2.43017802 -38.54856908
OS -2.43942362 -38.54764452
OE
OB -1.84308242 -38.72700916 H
OS -1.84400698 -38.72700916
OS -1.84493154 -38.72793372
OS -1.84770522 -38.72885828
OS -1.85140346 -38.72978284
OS -1.85602626 -38.73163196
OS -1.86157362 -38.73348108
OS -1.86804554 -38.7353302
OS -1.87544202 -38.73717932
OS -1.88376306 -38.739953
OS -1.89393322 -38.74180212
OS -1.90410338 -38.7445758
OS -1.91612266 -38.74734948
OS -1.9290665 -38.75012316
OS -1.94201034 -38.75289684
OS -1.9568033 -38.75474596
OS -1.97252082 -38.75751964
OS -1.97436994 -38.75751964
OS -1.9799173 -38.7584442
OS -1.9891629 -38.76029332
OS -1.99933306 -38.76214244
OS -2.01042778 -38.76399156
OS -2.0215225 -38.76676524
OS -2.03169266 -38.76953892
OS -2.04093826 -38.77323716
OS -2.04186282 -38.77323716
OS -2.0446365 -38.77508628
OS -2.04833474 -38.7769354
OS -2.05203298 -38.77970908
OS -2.0631277 -38.78710556
OS -2.0723733 -38.79820028
OS -2.0723733 -38.79912484
OS -2.07422242 -38.80097396
OS -2.07514698 -38.8046722
OS -2.0769961 -38.809295
OS -2.07884522 -38.81484236
OS -2.08069434 -38.82038972
OS -2.0816189 -38.8277862
OS -2.08254346 -38.83518268
OS -2.08254346 -38.83610724
OS -2.08254346 -38.84073004
OS -2.0816189 -38.8462774
OS -2.07976978 -38.85367388
OS -2.0769961 -38.86199492
OS -2.0723733 -38.87031596
OS -2.06682594 -38.87956156
OS -2.05942946 -38.8878826
OS -2.0585049 -38.88880716
OS -2.05480666 -38.89065628
OS -2.0492593 -38.89435452
OS -2.04186282 -38.89805276
OS -2.03169266 -38.901751
OS -2.01967338 -38.90544924
OS -2.00580498 -38.90729836
OS -1.9891629 -38.90822292
OS -1.98176642 -38.90822292
OS -1.97252082 -38.90729836
OS -1.96235066 -38.90544924
OS -1.94940682 -38.90360012
OS -1.93646298 -38.89990188
OS -1.92259458 -38.89527908
OS -1.90872618 -38.88880716
OS -1.90687706 -38.8878826
OS -1.90317882 -38.88510892
OS -1.8967069 -38.88048612
OS -1.88931042 -38.8740142
OS -1.88098938 -38.86661772
OS -1.87174378 -38.85737212
OS -1.8643473 -38.8462774
OS -1.85695082 -38.83425812
OS -1.85602626 -38.83333356
OS -1.8551017 -38.82963532
OS -1.85325258 -38.8231634
OS -1.8504789 -38.81484236
OS -1.84770522 -38.80374764
OS -1.8458561 -38.7908038
OS -1.84493154 -38.77508628
OS -1.84400698 -38.75659508
OS -1.84308242 -38.72700916
OE
OB -5.18444226 -38.5504182 H
OS -5.18998962 -38.5504182
OS -5.19461242 -38.55134276
OS -5.20478258 -38.55226732
OS -5.21865098 -38.55596556
OS -5.2343685 -38.56151292
OS -5.25101058 -38.5689094
OS -5.2667281 -38.58000412
OS -5.27504914 -38.5874006
OS -5.28244562 -38.59479708
OS -5.28244562 -38.59572164
OS -5.28429474 -38.5966462
OS -5.28614386 -38.59941988
OS -5.28891754 -38.60311812
OS -5.29169122 -38.60774092
OS -5.2944649 -38.61328828
OS -5.29816314 -38.62068476
OS -5.30186138 -38.62808124
OS -5.30555962 -38.63732684
OS -5.30925786 -38.64657244
OS -5.31203154 -38.65766716
OS -5.31480522 -38.66968644
OS -5.3175789 -38.68263028
OS -5.31942802 -38.69649868
OS -5.32035258 -38.7122162
OS -5.32127714 -38.72793372
OS -5.32127714 -38.72885828
OS -5.32127714 -38.73163196
OS -5.32127714 -38.73625476
OS -5.32035258 -38.74272668
OS -5.32035258 -38.75012316
OS -5.31942802 -38.7584442
OS -5.31665434 -38.77785996
OS -5.31203154 -38.8000494
OS -5.30463506 -38.82223884
OS -5.29538946 -38.84350372
OS -5.28891754 -38.85274932
OS -5.28244562 -38.86199492
OS -5.28152106 -38.86199492
OS -5.2805965 -38.86384404
OS -5.27504914 -38.86846684
OS -5.2667281 -38.87586332
OS -5.25563338 -38.8832598
OS -5.24176498 -38.89158084
OS -5.2251229 -38.89897732
OS -5.20570714 -38.90360012
OS -5.19553698 -38.90452468
OS -5.18444226 -38.90544924
OS -5.1788949 -38.90544924
OS -5.1742721 -38.90452468
OS -5.16410194 -38.90267556
OS -5.15023354 -38.89990188
OS -5.13544058 -38.89435452
OS -5.1187985 -38.88695804
OS -5.10308098 -38.87586332
OS -5.09475994 -38.86846684
OS -5.08736346 -38.86107036
OS -5.0864389 -38.8601458
OS -5.08551434 -38.85922124
OS -5.08366522 -38.85644756
OS -5.08089154 -38.85274932
OS -5.07811786 -38.84812652
OS -5.07441962 -38.84257916
OS -5.07072138 -38.83518268
OS -5.06702314 -38.8277862
OS -5.0633249 -38.8185406
OS -5.06055122 -38.80837044
OS -5.05685298 -38.79727572
OS -5.0540793 -38.78525644
OS -5.05130562 -38.77138804
OS -5.0494565 -38.75751964
OS -5.04760738 -38.74180212
OS -5.04760738 -38.72516004
OS -5.04760738 -38.72423548
OS -5.04760738 -38.7214618
OS -5.04760738 -38.716839
OS -5.04853194 -38.71129164
OS -5.04853194 -38.70389516
OS -5.0494565 -38.69557412
OS -5.05223018 -38.67615836
OS -5.05685298 -38.65581804
OS -5.06424946 -38.6336286
OS -5.07441962 -38.61328828
OS -5.07996698 -38.60311812
OS -5.08736346 -38.59479708
OS -5.08736346 -38.59387252
OS -5.08921258 -38.59294796
OS -5.09475994 -38.5874006
OS -5.10308098 -38.58092868
OS -5.1141757 -38.57260764
OS -5.1280441 -38.5642866
OS -5.14468618 -38.55689012
OS -5.16317738 -38.55226732
OS -5.17334754 -38.55134276
OS -5.18444226 -38.5504182
OE
SE
S P 0
OB -4.66714078 -36.5016923 I
OS -4.65465922 -36.5016923
OS -4.62553558 -36.50307914
OS -4.5950251 -36.50723966
OS -4.56174094 -36.51140018
OS -4.53123046 -36.51833438
OS -4.51597522 -36.5224949
OS -4.50349366 -36.52665542
OS -4.50210682 -36.52665542
OS -4.50071998 -36.52804226
OS -4.49239894 -36.53220278
OS -4.47991738 -36.53775014
OS -4.46466214 -36.54745802
OS -4.44802006 -36.55993958
OS -4.42999114 -36.57658166
OS -4.41334906 -36.59599742
OS -4.39670698 -36.61818686
OS -4.39670698 -36.6195737
OS -4.39532014 -36.62096054
OS -4.38977278 -36.62928158
OS -4.38422542 -36.64314998
OS -4.37590438 -36.6611789
OS -4.36897018 -36.6819815
OS -4.36203598 -36.70694462
OS -4.35787546 -36.73329458
OS -4.35648862 -36.76241822
OS -4.35648862 -36.76380506
OS -4.35648862 -36.76657874
OS -4.35648862 -36.7721261
OS -4.35787546 -36.7790603
OS -4.35787546 -36.78876818
OS -4.3592623 -36.79847606
OS -4.36480966 -36.82205234
OS -4.3731307 -36.84978914
OS -4.38422542 -36.87891278
OS -4.4008675 -36.90803642
OS -4.41196222 -36.92190482
OS -4.42305694 -36.93577322
OS -4.42444378 -36.93716006
OS -4.42583062 -36.9385469
OS -4.42999114 -36.94270742
OS -4.4355385 -36.94686794
OS -4.4424727 -36.9524153
OS -4.45079374 -36.95796266
OS -4.46188846 -36.96489686
OS -4.47298318 -36.9732179
OS -4.48685158 -36.9801521
OS -4.50210682 -36.9870863
OS -4.5187489 -36.99540734
OS -4.53677782 -37.00234154
OS -4.55758042 -37.0078889
OS -4.57838302 -37.0148231
OS -4.6019593 -37.01898362
OS -4.62692242 -37.02314414
OS -4.62414874 -37.02453098
OS -4.61860138 -37.02730466
OS -4.61028034 -37.03285202
OS -4.59918562 -37.03839938
OS -4.5742225 -37.05365462
OS -4.56174094 -37.0633625
OS -4.55064622 -37.07168354
OS -4.54787254 -37.07445722
OS -4.54093834 -37.08139142
OS -4.52984362 -37.09248614
OS -4.51597522 -37.10635454
OS -4.50071998 -37.1257703
OS -4.48269106 -37.1465729
OS -4.46466214 -37.17153602
OS -4.44524638 -37.19927282
OS -4.28021242 -37.45999874
OS -4.43831218 -37.45999874
OS -4.56451462 -37.26029378
OS -4.56451462 -37.25890694
OS -4.5672883 -37.25613326
OS -4.57006198 -37.25197274
OS -4.5742225 -37.24642538
OS -4.58393038 -37.23117014
OS -4.59641194 -37.21175438
OS -4.61166718 -37.19095178
OS -4.62692242 -37.16876234
OS -4.64217766 -37.14795974
OS -4.65604606 -37.12854398
OS -4.6574329 -37.12715714
OS -4.66159342 -37.12160978
OS -4.66852762 -37.11328874
OS -4.6782355 -37.10358086
OS -4.6990381 -37.08277826
OS -4.71013282 -37.07307038
OS -4.72122754 -37.06474934
OS -4.72261438 -37.0633625
OS -4.72538806 -37.06197566
OS -4.73093542 -37.05920198
OS -4.73925646 -37.05504146
OS -4.7475775 -37.05088094
OS -4.75728538 -37.04672042
OS -4.77947482 -37.03978622
OS -4.78086166 -37.03978622
OS -4.78363534 -37.03839938
OS -4.7891827 -37.03839938
OS -4.7961169 -37.03701254
OS -4.80582478 -37.0356257
OS -4.8169195 -37.0356257
OS -4.83217474 -37.03423886
OS -4.99582186 -37.03423886
OS -4.99582186 -37.45999874
OS -5.12341114 -37.45999874
OS -5.12341114 -36.50030546
OS -4.6782355 -36.50030546
OS -4.66714078 -36.5016923
OE
OB -1.0100437 -37.45999874 I
OS -1.13208562 -37.45999874
OS -1.13208562 -36.65701838
OS -1.4122273 -37.45999874
OS -1.52594818 -37.45999874
OS -1.80331618 -36.64314998
OS -1.80331618 -37.45999874
OS -1.9253581 -37.45999874
OS -1.9253581 -36.50030546
OS -1.73536102 -36.50030546
OS -1.50791926 -37.1812439
OS -1.50791926 -37.18263074
OS -1.50653242 -37.18540442
OS -1.50514558 -37.18956494
OS -1.5023719 -37.19649914
OS -1.49682454 -37.21314122
OS -1.48989034 -37.23394382
OS -1.48295614 -37.2575201
OS -1.4746351 -37.28109638
OS -1.4677009 -37.30328582
OS -1.46215354 -37.32270158
OS -1.4607667 -37.3199279
OS -1.45937986 -37.3129937
OS -1.45521934 -37.30051214
OS -1.44967198 -37.28387006
OS -1.44273778 -37.26168062
OS -1.4330299 -37.23533066
OS -1.42332202 -37.20482018
OS -1.41084046 -37.16876234
OS -1.18062502 -36.50030546
OS -1.0100437 -36.50030546
OS -1.0100437 -37.45999874
OE
OB -2.02382374 -37.45999874 I
OS -2.1680551 -37.45999874
OS -2.28038914 -37.16876234
OS -2.68257274 -37.16876234
OS -2.78658574 -37.45999874
OS -2.92110922 -37.45999874
OS -2.55498346 -36.50030546
OS -2.41629946 -36.50030546
OS -2.02382374 -37.45999874
OE
OB -3.02928274 -37.45999874 I
OS -3.16103254 -37.45999874
OS -3.66306862 -36.70694462
OS -3.66306862 -37.45999874
OS -3.78511054 -37.45999874
OS -3.78511054 -36.50030546
OS -3.65474758 -36.50030546
OS -3.15132466 -37.25474642
OS -3.15132466 -36.50030546
OS -3.02928274 -36.50030546
OS -3.02928274 -37.45999874
OE
OB -5.3231161 -36.61402634 I
OS -5.89033366 -36.61402634
OS -5.89033366 -36.90664958
OS -5.35917394 -36.90664958
OS -5.35917394 -37.02037046
OS -5.89033366 -37.02037046
OS -5.89033366 -37.34627786
OS -5.30092666 -37.34627786
OS -5.30092666 -37.45999874
OS -6.01792294 -37.45999874
OS -6.01792294 -36.50030546
OS -5.3231161 -36.50030546
OS -5.3231161 -36.61402634
OE
OB -0.10721086 -36.61402634 I
OS -0.67442842 -36.61402634
OS -0.67442842 -36.90664958
OS -0.1432687 -36.90664958
OS -0.1432687 -37.02037046
OS -0.67442842 -37.02037046
OS -0.67442842 -37.34627786
OS -0.08502142 -37.34627786
OS -0.08502142 -37.45999874
OS -0.8020177 -37.45999874
OS -0.8020177 -36.50030546
OS -0.10721086 -36.50030546
OS -0.10721086 -36.61402634
OE
OB -8.43241138 -37.34627786 I
OS -7.95949894 -37.34627786
OS -7.95949894 -37.45999874
OS -8.56000066 -37.45999874
OS -8.56000066 -36.50030546
OS -8.43241138 -36.50030546
OS -8.43241138 -37.34627786
OE
OB -6.51718534 -37.05365462 I
OS -6.51718534 -37.45999874
OS -6.64477462 -37.45999874
OS -6.64477462 -37.05365462
OS -7.0150609 -36.50030546
OS -6.86112166 -36.50030546
OS -6.67251142 -36.79154186
OS -6.67251142 -36.7929287
OS -6.66973774 -36.79570238
OS -6.66696406 -36.7998629
OS -6.66419038 -36.80541026
OS -6.65864302 -36.81234446
OS -6.65309566 -36.8206655
OS -6.6406141 -36.8414681
OS -6.62535886 -36.86643122
OS -6.60871678 -36.89416802
OS -6.59068786 -36.92329166
OS -6.57404578 -36.95380214
OS -6.57404578 -36.9524153
OS -6.57265894 -36.94964162
OS -6.56988526 -36.9454811
OS -6.56572474 -36.93993374
OS -6.56156422 -36.93299954
OS -6.55601686 -36.9246785
OS -6.5435353 -36.9038759
OS -6.52828006 -36.87891278
OS -6.51025114 -36.84978914
OS -6.48944854 -36.81789182
OS -6.4672591 -36.78322082
OS -6.28280938 -36.50030546
OS -6.1344175 -36.50030546
OS -6.51718534 -37.05365462
OE
OB -7.01644774 -37.45999874 I
OS -7.1606791 -37.45999874
OS -7.27301314 -37.16876234
OS -7.67519674 -37.16876234
OS -7.77920974 -37.45999874
OS -7.91373322 -37.45999874
OS -7.54760746 -36.50030546
OS -7.40892346 -36.50030546
OS -7.01644774 -37.45999874
OE
OB -7.48103914 -36.60015794 H
OS -7.48103914 -36.60154478
OS -7.48242598 -36.60431846
OS -7.48242598 -36.60986582
OS -7.48519966 -36.61541318
OS -7.4865865 -36.62512106
OS -7.48936018 -36.63482894
OS -7.49490754 -36.65840522
OS -7.50184174 -36.68614202
OS -7.51154962 -36.7166525
OS -7.5212575 -36.74993666
OS -7.53373906 -36.78460766
OS -7.63775206 -37.06474934
OS -7.3132315 -37.06474934
OS -7.41308398 -36.80124974
OS -7.41308398 -36.7998629
OS -7.41447082 -36.79570238
OS -7.4172445 -36.78876818
OS -7.42001818 -36.78044714
OS -7.4241787 -36.77073926
OS -7.42833922 -36.7582577
OS -7.43249974 -36.7443893
OS -7.4380471 -36.7305209
OS -7.44914182 -36.69862358
OS -7.46023654 -36.66533942
OS -7.47133126 -36.63205526
OS -7.48103914 -36.60015794
OE
OB -4.69349074 -36.60709214 H
OS -4.99582186 -36.60709214
OS -4.99582186 -36.9246785
OS -4.71013282 -36.9246785
OS -4.69349074 -36.92329166
OS -4.67407498 -36.92190482
OS -4.65188554 -36.92051798
OS -4.6296961 -36.9177443
OS -4.60750666 -36.91358378
OS -4.5880909 -36.90803642
OS -4.58531722 -36.90664958
OS -4.57976986 -36.9038759
OS -4.57144882 -36.89971538
OS -4.5603541 -36.89416802
OS -4.54787254 -36.88584698
OS -4.53539098 -36.8761391
OS -4.52290942 -36.86365754
OS -4.51320154 -36.84978914
OS -4.5118147 -36.8484023
OS -4.50904102 -36.84285494
OS -4.5048805 -36.8345339
OS -4.49933314 -36.82343918
OS -4.49517262 -36.81095762
OS -4.4910121 -36.79708922
OS -4.48823842 -36.78044714
OS -4.48685158 -36.76380506
OS -4.48685158 -36.76241822
OS -4.48685158 -36.76103138
OS -4.48823842 -36.75271034
OS -4.48962526 -36.74022878
OS -4.49239894 -36.7235867
OS -4.49933314 -36.70694462
OS -4.50765418 -36.68752886
OS -4.52013574 -36.66949994
OS -4.53677782 -36.65147102
OS -4.5395515 -36.65008418
OS -4.5464857 -36.64453682
OS -4.55758042 -36.63760262
OS -4.57560934 -36.62928158
OS -4.59641194 -36.62096054
OS -4.62414874 -36.61402634
OS -4.65604606 -36.60847898
OS -4.69349074 -36.60709214
OE
OB -2.48841514 -36.60015794 H
OS -2.48841514 -36.60154478
OS -2.48980198 -36.60431846
OS -2.48980198 -36.60986582
OS -2.49257566 -36.61541318
OS -2.4939625 -36.62512106
OS -2.49673618 -36.63482894
OS -2.50228354 -36.65840522
OS -2.50921774 -36.68614202
OS -2.51892562 -36.7166525
OS -2.5286335 -36.74993666
OS -2.54111506 -36.78460766
OS -2.64512806 -37.06474934
OS -2.3206075 -37.06474934
OS -2.42045998 -36.80124974
OS -2.42045998 -36.7998629
OS -2.42184682 -36.79570238
OS -2.4246205 -36.78876818
OS -2.42739418 -36.78044714
OS -2.4315547 -36.77073926
OS -2.43571522 -36.7582577
OS -2.43987574 -36.7443893
OS -2.4454231 -36.7305209
OS -2.45651782 -36.69862358
OS -2.46761254 -36.66533942
OS -2.47870726 -36.63205526
OS -2.48841514 -36.60015794
OE
SE
S P 0
OB 35.73690338 -37.45999874 I
OS 35.61486146 -37.45999874
OS 35.61486146 -36.65701838
OS 35.33471978 -37.45999874
OS 35.2209989 -37.45999874
OS 34.9436309 -36.64314998
OS 34.9436309 -37.45999874
OS 34.82158898 -37.45999874
OS 34.82158898 -36.50030546
OS 35.01158606 -36.50030546
OS 35.23902782 -37.1812439
OS 35.23902782 -37.18263074
OS 35.24041466 -37.18540442
OS 35.2418015 -37.18956494
OS 35.24457518 -37.19649914
OS 35.25012254 -37.21314122
OS 35.25705674 -37.23394382
OS 35.26399094 -37.2575201
OS 35.27231198 -37.28109638
OS 35.27924618 -37.30328582
OS 35.28479354 -37.32270158
OS 35.28618038 -37.3199279
OS 35.28756722 -37.3129937
OS 35.29172774 -37.30051214
OS 35.2972751 -37.28387006
OS 35.3042093 -37.26168062
OS 35.31391718 -37.23533066
OS 35.32362506 -37.20482018
OS 35.33610662 -37.16876234
OS 35.56632206 -36.50030546
OS 35.73690338 -36.50030546
OS 35.73690338 -37.45999874
OE
OB 34.61356298 -37.05504146 I
OS 34.61356298 -37.0564283
OS 34.61356298 -37.06197566
OS 34.61356298 -37.06890986
OS 34.61356298 -37.07861774
OS 34.61217614 -37.0910993
OS 34.61217614 -37.1049677
OS 34.6107893 -37.12160978
OS 34.60940246 -37.13825186
OS 34.60524194 -37.17569654
OS 34.59969458 -37.21452806
OS 34.59137354 -37.25197274
OS 34.58582618 -37.27000166
OS 34.58027882 -37.28664374
OS 34.58027882 -37.28803058
OS 34.57889198 -37.29080426
OS 34.5761183 -37.29496478
OS 34.57334462 -37.30051214
OS 34.56502358 -37.31576738
OS 34.55254202 -37.33518314
OS 34.53589994 -37.35737258
OS 34.51648418 -37.37956202
OS 34.49152106 -37.4031383
OS 34.46101058 -37.4239409
OS 34.45962374 -37.4239409
OS 34.45685006 -37.42671458
OS 34.45268954 -37.42810142
OS 34.44575534 -37.43226194
OS 34.4374343 -37.43642246
OS 34.42633958 -37.44058298
OS 34.41524486 -37.4447435
OS 34.40137646 -37.45029086
OS 34.38612122 -37.45583822
OS 34.36947914 -37.45999874
OS 34.35145022 -37.46415926
OS 34.33064762 -37.46831978
OS 34.30984502 -37.47109346
OS 34.28765558 -37.47386714
OS 34.23772934 -37.47664082
OS 34.22524778 -37.47664082
OS 34.2155399 -37.47525398
OS 34.20444518 -37.47525398
OS 34.19057678 -37.47386714
OS 34.17532154 -37.4724803
OS 34.1600663 -37.47109346
OS 34.1253953 -37.4655461
OS 34.08795062 -37.45722506
OS 34.05189278 -37.44613034
OS 34.01722178 -37.4308751
OS 34.01583494 -37.4308751
OS 34.01306126 -37.42810142
OS 34.00890074 -37.42532774
OS 34.00335338 -37.42255406
OS 33.98809814 -37.41145934
OS 33.97006922 -37.3962041
OS 33.94926662 -37.37678834
OS 33.92985086 -37.3545989
OS 33.9104351 -37.3268621
OS 33.89517986 -37.29635162
OS 33.89517986 -37.29496478
OS 33.89379302 -37.2921911
OS 33.89240618 -37.28664374
OS 33.8896325 -37.27970954
OS 33.88685882 -37.2713885
OS 33.88408514 -37.26029378
OS 33.87992462 -37.24781222
OS 33.87715094 -37.23255698
OS 33.87437726 -37.2159149
OS 33.87021674 -37.19788598
OS 33.86744306 -37.17847022
OS 33.86466938 -37.15766762
OS 33.8618957 -37.13409134
OS 33.86050886 -37.10912822
OS 33.85912202 -37.08277826
OS 33.85912202 -37.05504146
OS 33.85912202 -36.50030546
OS 33.9867113 -36.50030546
OS 33.9867113 -37.05504146
OS 33.9867113 -37.0564283
OS 33.9867113 -37.06058882
OS 33.9867113 -37.06752302
OS 33.9867113 -37.07584406
OS 33.98809814 -37.08555194
OS 33.98809814 -37.0980335
OS 33.98948498 -37.12438346
OS 33.99225866 -37.15489394
OS 33.99641918 -37.18540442
OS 34.00196654 -37.21452806
OS 34.00474022 -37.22700962
OS 34.00890074 -37.23949118
OS 34.01028758 -37.24226486
OS 34.01306126 -37.24919906
OS 34.01999546 -37.25890694
OS 34.0283165 -37.27277534
OS 34.03802438 -37.28664374
OS 34.05189278 -37.30189898
OS 34.06853486 -37.31715422
OS 34.08795062 -37.32963578
OS 34.0907243 -37.33102262
OS 34.0976585 -37.33518314
OS 34.11014006 -37.33934366
OS 34.12678214 -37.34489102
OS 34.1461979 -37.35182522
OS 34.17116102 -37.35598574
OS 34.19751098 -37.36014626
OS 34.22663462 -37.3615331
OS 34.24050302 -37.3615331
OS 34.24882406 -37.36014626
OS 34.26130562 -37.36014626
OS 34.27378718 -37.35875942
OS 34.30429766 -37.35321206
OS 34.33758182 -37.34627786
OS 34.36947914 -37.33518314
OS 34.39998962 -37.3199279
OS 34.41385802 -37.31022002
OS 34.42633958 -37.2991253
OS 34.42772642 -37.29773846
OS 34.42911326 -37.29635162
OS 34.43188694 -37.2921911
OS 34.43604746 -37.28664374
OS 34.44020798 -37.2783227
OS 34.44575534 -37.27000166
OS 34.4513027 -37.2575201
OS 34.45685006 -37.24503854
OS 34.46239742 -37.2297833
OS 34.46655794 -37.21175438
OS 34.4721053 -37.19095178
OS 34.47626582 -37.16876234
OS 34.48042634 -37.14379922
OS 34.48320002 -37.11744926
OS 34.4859737 -37.08693878
OS 34.4859737 -37.05504146
OS 34.4859737 -36.50030546
OS 34.61356298 -36.50030546
OS 34.61356298 -37.05504146
OE
OB 33.64416182 -37.45999874 I
OS 33.51241202 -37.45999874
OS 33.01037594 -36.70694462
OS 33.01037594 -37.45999874
OS 32.88833402 -37.45999874
OS 32.88833402 -36.50030546
OS 33.01869698 -36.50030546
OS 33.5221199 -37.25474642
OS 33.5221199 -36.50030546
OS 33.64416182 -36.50030546
OS 33.64416182 -37.45999874
OE
OB 38.19022334 -36.5016923 I
OS 38.2027049 -36.5016923
OS 38.23182854 -36.50307914
OS 38.26233902 -36.50723966
OS 38.29562318 -36.51140018
OS 38.32613366 -36.51833438
OS 38.3413889 -36.5224949
OS 38.35387046 -36.52665542
OS 38.3552573 -36.52665542
OS 38.35664414 -36.52804226
OS 38.36496518 -36.53220278
OS 38.37744674 -36.53775014
OS 38.39270198 -36.54745802
OS 38.40934406 -36.55993958
OS 38.42737298 -36.57658166
OS 38.44401506 -36.59599742
OS 38.46065714 -36.61818686
OS 38.46065714 -36.6195737
OS 38.46204398 -36.62096054
OS 38.46759134 -36.62928158
OS 38.4731387 -36.64314998
OS 38.48145974 -36.6611789
OS 38.48839394 -36.6819815
OS 38.49532814 -36.70694462
OS 38.49948866 -36.73329458
OS 38.5008755 -36.76241822
OS 38.5008755 -36.76380506
OS 38.5008755 -36.76657874
OS 38.5008755 -36.7721261
OS 38.49948866 -36.7790603
OS 38.49948866 -36.78876818
OS 38.49810182 -36.79847606
OS 38.49255446 -36.82205234
OS 38.48423342 -36.84978914
OS 38.4731387 -36.87891278
OS 38.45649662 -36.90803642
OS 38.4454019 -36.92190482
OS 38.43430718 -36.93577322
OS 38.43292034 -36.93716006
OS 38.4315335 -36.9385469
OS 38.42737298 -36.94270742
OS 38.42182562 -36.94686794
OS 38.41489142 -36.9524153
OS 38.40657038 -36.95796266
OS 38.39547566 -36.96489686
OS 38.38438094 -36.9732179
OS 38.37051254 -36.9801521
OS 38.3552573 -36.9870863
OS 38.33861522 -36.99540734
OS 38.3205863 -37.00234154
OS 38.2997837 -37.0078889
OS 38.2789811 -37.0148231
OS 38.25540482 -37.01898362
OS 38.2304417 -37.02314414
OS 38.23321538 -37.02453098
OS 38.23876274 -37.02730466
OS 38.24708378 -37.03285202
OS 38.2581785 -37.03839938
OS 38.28314162 -37.05365462
OS 38.29562318 -37.0633625
OS 38.3067179 -37.07168354
OS 38.30949158 -37.07445722
OS 38.31642578 -37.08139142
OS 38.3275205 -37.09248614
OS 38.3413889 -37.10635454
OS 38.35664414 -37.1257703
OS 38.37467306 -37.1465729
OS 38.39270198 -37.17153602
OS 38.41211774 -37.19927282
OS 38.5771517 -37.45999874
OS 38.41905194 -37.45999874
OS 38.2928495 -37.26029378
OS 38.2928495 -37.25890694
OS 38.29007582 -37.25613326
OS 38.28730214 -37.25197274
OS 38.28314162 -37.24642538
OS 38.27343374 -37.23117014
OS 38.26095218 -37.21175438
OS 38.24569694 -37.19095178
OS 38.2304417 -37.16876234
OS 38.21518646 -37.14795974
OS 38.20131806 -37.12854398
OS 38.19993122 -37.12715714
OS 38.1957707 -37.12160978
OS 38.1888365 -37.11328874
OS 38.17912862 -37.10358086
OS 38.15832602 -37.08277826
OS 38.1472313 -37.07307038
OS 38.13613658 -37.06474934
OS 38.13474974 -37.0633625
OS 38.13197606 -37.06197566
OS 38.1264287 -37.05920198
OS 38.11810766 -37.05504146
OS 38.10978662 -37.05088094
OS 38.10007874 -37.04672042
OS 38.0778893 -37.03978622
OS 38.07650246 -37.03978622
OS 38.07372878 -37.03839938
OS 38.06818142 -37.03839938
OS 38.06124722 -37.03701254
OS 38.05153934 -37.0356257
OS 38.04044462 -37.0356257
OS 38.02518938 -37.03423886
OS 37.86154226 -37.03423886
OS 37.86154226 -37.45999874
OS 37.73395298 -37.45999874
OS 37.73395298 -36.50030546
OS 38.17912862 -36.50030546
OS 38.19022334 -36.5016923
OE
OB 37.53424802 -36.61402634 I
OS 36.96703046 -36.61402634
OS 36.96703046 -36.90664958
OS 37.49819018 -36.90664958
OS 37.49819018 -37.02037046
OS 36.96703046 -37.02037046
OS 36.96703046 -37.34627786
OS 37.55643746 -37.34627786
OS 37.55643746 -37.45999874
OS 36.83944118 -37.45999874
OS 36.83944118 -36.50030546
OS 37.53424802 -36.50030546
OS 37.53424802 -36.61402634
OE
OB 36.32492354 -36.5016923 I
OS 36.33601826 -36.5016923
OS 36.36098138 -36.50446598
OS 36.38871818 -36.50723966
OS 36.41784182 -36.51278702
OS 36.44696546 -36.51972122
OS 36.47331542 -36.5294291
OS 36.47470226 -36.5294291
OS 36.4760891 -36.53081594
OS 36.48441014 -36.53497646
OS 36.4968917 -36.54191066
OS 36.5107601 -36.55161854
OS 36.52740218 -36.5641001
OS 36.5454311 -36.57935534
OS 36.56207318 -36.5987711
OS 36.57732842 -36.6195737
OS 36.57871526 -36.62234738
OS 36.58287578 -36.63066842
OS 36.58980998 -36.64176314
OS 36.59674418 -36.65840522
OS 36.60367838 -36.67782098
OS 36.61061258 -36.69862358
OS 36.6147731 -36.72219986
OS 36.61615994 -36.74577614
OS 36.61615994 -36.74854982
OS 36.61615994 -36.75548402
OS 36.6147731 -36.76796558
OS 36.61199942 -36.78322082
OS 36.6078389 -36.80124974
OS 36.6009047 -36.8206655
OS 36.59258366 -36.84008126
OS 36.58148894 -36.86088386
OS 36.5801021 -36.86365754
OS 36.57594158 -36.8692049
OS 36.56762054 -36.88029962
OS 36.55652582 -36.89139434
OS 36.54265742 -36.90526274
OS 36.52601534 -36.92051798
OS 36.50521274 -36.93438638
OS 36.48163646 -36.94825478
OS 36.4830233 -36.94825478
OS 36.48579698 -36.94964162
OS 36.4899575 -36.95102846
OS 36.49550486 -36.95380214
OS 36.51214694 -36.9593495
OS 36.5315627 -36.96905738
OS 36.5523653 -36.98153894
OS 36.57594158 -36.99679418
OS 36.59674418 -37.0148231
OS 36.61615994 -37.03701254
OS 36.61754678 -37.03978622
OS 36.62309414 -37.04810726
OS 36.63141518 -37.06058882
OS 36.63973622 -37.0772309
OS 36.64805726 -37.09942034
OS 36.6563783 -37.12299662
OS 36.66192566 -37.15073342
OS 36.6633125 -37.1812439
OS 36.6633125 -37.18263074
OS 36.6633125 -37.18401758
OS 36.6633125 -37.19233862
OS 36.66192566 -37.20620702
OS 36.65915198 -37.2228491
OS 36.6563783 -37.24226486
OS 36.65083094 -37.26306746
OS 36.64389674 -37.2852569
OS 36.63418886 -37.30744634
OS 36.63280202 -37.31022002
OS 36.6286415 -37.31715422
OS 36.62309414 -37.3268621
OS 36.6147731 -37.3407305
OS 36.60367838 -37.3545989
OS 36.59258366 -37.36985414
OS 36.57871526 -37.38510938
OS 36.56346002 -37.39759094
OS 36.56207318 -37.39897778
OS 36.55652582 -37.4031383
OS 36.54681794 -37.40868566
OS 36.53433638 -37.41423302
OS 36.51908114 -37.42255406
OS 36.50105222 -37.4308751
OS 36.48163646 -37.4378093
OS 36.45806018 -37.4447435
OS 36.4552865 -37.4447435
OS 36.44696546 -37.44751718
OS 36.43309706 -37.44890402
OS 36.41506814 -37.4516777
OS 36.3928787 -37.45445138
OS 36.36652874 -37.45722506
OS 36.3374051 -37.4586119
OS 36.30412094 -37.45999874
OS 35.93799518 -37.45999874
OS 35.93799518 -36.50030546
OS 36.31521566 -36.50030546
OS 36.32492354 -36.5016923
OE
OB 32.3849111 -36.61402634 I
OS 32.06871158 -36.61402634
OS 32.06871158 -37.45999874
OS 31.9411223 -37.45999874
OS 31.9411223 -36.61402634
OS 31.62492278 -36.61402634
OS 31.62492278 -36.50030546
OS 32.3849111 -36.50030546
OS 32.3849111 -36.61402634
OE
OB 30.62639798 -37.45999874 I
OS 30.48216662 -37.45999874
OS 30.36983258 -37.16876234
OS 29.96764898 -37.16876234
OS 29.86363598 -37.45999874
OS 29.7291125 -37.45999874
OS 30.09523826 -36.50030546
OS 30.23392226 -36.50030546
OS 30.62639798 -37.45999874
OE
OB 29.3546657 -36.5016923 I
OS 29.37824198 -36.50307914
OS 29.4032051 -36.50446598
OS 29.42678138 -36.50723966
OS 29.44758398 -36.51001334
OS 29.45035766 -36.51001334
OS 29.46006554 -36.51278702
OS 29.4725471 -36.5155607
OS 29.48918918 -36.51972122
OS 29.5072181 -36.52665542
OS 29.52663386 -36.53497646
OS 29.54743646 -36.54468434
OS 29.56546538 -36.55577906
OS 29.56823906 -36.5571659
OS 29.57378642 -36.56132642
OS 29.58210746 -36.56964746
OS 29.59320218 -36.57935534
OS 29.60568374 -36.5918369
OS 29.6181653 -36.60847898
OS 29.6320337 -36.6265079
OS 29.64312842 -36.6473105
OS 29.64451526 -36.65008418
OS 29.64728894 -36.65701838
OS 29.6528363 -36.66949994
OS 29.65838366 -36.68614202
OS 29.66254418 -36.70555778
OS 29.66809154 -36.72774722
OS 29.67086522 -36.75271034
OS 29.67225206 -36.7790603
OS 29.67225206 -36.78044714
OS 29.67225206 -36.78460766
OS 29.67225206 -36.79015502
OS 29.67086522 -36.7998629
OS 29.66947838 -36.80957078
OS 29.66809154 -36.82205234
OS 29.66531786 -36.83592074
OS 29.66254418 -36.85117598
OS 29.6528363 -36.8830733
OS 29.64728894 -36.89971538
OS 29.6389679 -36.9177443
OS 29.62926002 -36.93577322
OS 29.61955214 -36.9524153
OS 29.60707058 -36.96905738
OS 29.59320218 -36.98569946
OS 29.59181534 -36.9870863
OS 29.58904166 -36.98985998
OS 29.58488114 -36.9940205
OS 29.57794694 -36.99818102
OS 29.5696259 -37.00511522
OS 29.55853118 -37.01204942
OS 29.54466278 -37.02037046
OS 29.52940754 -37.02730466
OS 29.51137862 -37.0356257
OS 29.49057602 -37.04394674
OS 29.46838658 -37.05088094
OS 29.44203662 -37.0564283
OS 29.41429982 -37.06197566
OS 29.38378934 -37.06613618
OS 29.34911834 -37.06890986
OS 29.3130605 -37.0702967
OS 29.06758982 -37.0702967
OS 29.06758982 -37.45999874
OS 28.94000054 -37.45999874
OS 28.94000054 -36.50030546
OS 29.3338631 -36.50030546
OS 29.3546657 -36.5016923
OE
OB 31.18668134 -36.5016923 I
OS 31.1991629 -36.5016923
OS 31.22828654 -36.50307914
OS 31.25879702 -36.50723966
OS 31.29208118 -36.51140018
OS 31.32259166 -36.51833438
OS 31.3378469 -36.5224949
OS 31.35032846 -36.52665542
OS 31.3517153 -36.52665542
OS 31.35310214 -36.52804226
OS 31.36142318 -36.53220278
OS 31.37390474 -36.53775014
OS 31.38915998 -36.54745802
OS 31.40580206 -36.55993958
OS 31.42383098 -36.57658166
OS 31.44047306 -36.59599742
OS 31.45711514 -36.61818686
OS 31.45711514 -36.6195737
OS 31.45850198 -36.62096054
OS 31.46404934 -36.62928158
OS 31.4695967 -36.64314998
OS 31.47791774 -36.6611789
OS 31.48485194 -36.6819815
OS 31.49178614 -36.70694462
OS 31.49594666 -36.73329458
OS 31.4973335 -36.76241822
OS 31.4973335 -36.76380506
OS 31.4973335 -36.76657874
OS 31.4973335 -36.7721261
OS 31.49594666 -36.7790603
OS 31.49594666 -36.78876818
OS 31.49455982 -36.79847606
OS 31.48901246 -36.82205234
OS 31.48069142 -36.84978914
OS 31.4695967 -36.87891278
OS 31.45295462 -36.90803642
OS 31.4418599 -36.92190482
OS 31.43076518 -36.93577322
OS 31.42937834 -36.93716006
OS 31.4279915 -36.9385469
OS 31.42383098 -36.94270742
OS 31.41828362 -36.94686794
OS 31.41134942 -36.9524153
OS 31.40302838 -36.95796266
OS 31.39193366 -36.96489686
OS 31.38083894 -36.9732179
OS 31.36697054 -36.9801521
OS 31.3517153 -36.9870863
OS 31.33507322 -36.99540734
OS 31.3170443 -37.00234154
OS 31.2962417 -37.0078889
OS 31.2754391 -37.0148231
OS 31.25186282 -37.01898362
OS 31.2268997 -37.02314414
OS 31.22967338 -37.02453098
OS 31.23522074 -37.02730466
OS 31.24354178 -37.03285202
OS 31.2546365 -37.03839938
OS 31.27959962 -37.05365462
OS 31.29208118 -37.0633625
OS 31.3031759 -37.07168354
OS 31.30594958 -37.07445722
OS 31.31288378 -37.08139142
OS 31.3239785 -37.09248614
OS 31.3378469 -37.10635454
OS 31.35310214 -37.1257703
OS 31.37113106 -37.1465729
OS 31.38915998 -37.17153602
OS 31.40857574 -37.19927282
OS 31.5736097 -37.45999874
OS 31.41550994 -37.45999874
OS 31.2893075 -37.26029378
OS 31.2893075 -37.25890694
OS 31.28653382 -37.25613326
OS 31.28376014 -37.25197274
OS 31.27959962 -37.24642538
OS 31.26989174 -37.23117014
OS 31.25741018 -37.21175438
OS 31.24215494 -37.19095178
OS 31.2268997 -37.16876234
OS 31.21164446 -37.14795974
OS 31.19777606 -37.12854398
OS 31.19638922 -37.12715714
OS 31.1922287 -37.12160978
OS 31.1852945 -37.11328874
OS 31.17558662 -37.10358086
OS 31.15478402 -37.08277826
OS 31.1436893 -37.07307038
OS 31.13259458 -37.06474934
OS 31.13120774 -37.0633625
OS 31.12843406 -37.06197566
OS 31.1228867 -37.05920198
OS 31.11456566 -37.05504146
OS 31.10624462 -37.05088094
OS 31.09653674 -37.04672042
OS 31.0743473 -37.03978622
OS 31.07296046 -37.03978622
OS 31.07018678 -37.03839938
OS 31.06463942 -37.03839938
OS 31.05770522 -37.03701254
OS 31.04799734 -37.0356257
OS 31.03690262 -37.0356257
OS 31.02164738 -37.03423886
OS 30.85800026 -37.03423886
OS 30.85800026 -37.45999874
OS 30.73041098 -37.45999874
OS 30.73041098 -36.50030546
OS 31.17558662 -36.50030546
OS 31.18668134 -36.5016923
OE
OB 38.16387338 -36.60709214 H
OS 37.86154226 -36.60709214
OS 37.86154226 -36.9246785
OS 38.1472313 -36.9246785
OS 38.16387338 -36.92329166
OS 38.18328914 -36.92190482
OS 38.20547858 -36.92051798
OS 38.22766802 -36.9177443
OS 38.24985746 -36.91358378
OS 38.26927322 -36.90803642
OS 38.2720469 -36.90664958
OS 38.27759426 -36.9038759
OS 38.2859153 -36.89971538
OS 38.29701002 -36.89416802
OS 38.30949158 -36.88584698
OS 38.32197314 -36.8761391
OS 38.3344547 -36.86365754
OS 38.34416258 -36.84978914
OS 38.34554942 -36.8484023
OS 38.3483231 -36.84285494
OS 38.35248362 -36.8345339
OS 38.35803098 -36.82343918
OS 38.3621915 -36.81095762
OS 38.36635202 -36.79708922
OS 38.3691257 -36.78044714
OS 38.37051254 -36.76380506
OS 38.37051254 -36.76241822
OS 38.37051254 -36.76103138
OS 38.3691257 -36.75271034
OS 38.36773886 -36.74022878
OS 38.36496518 -36.7235867
OS 38.35803098 -36.70694462
OS 38.34970994 -36.68752886
OS 38.33722838 -36.66949994
OS 38.3205863 -36.65147102
OS 38.31781262 -36.65008418
OS 38.31087842 -36.64453682
OS 38.2997837 -36.63760262
OS 38.28175478 -36.62928158
OS 38.26095218 -36.62096054
OS 38.23321538 -36.61402634
OS 38.20131806 -36.60847898
OS 38.16387338 -36.60709214
OE
OB 29.34218414 -36.61402634 H
OS 29.06758982 -36.61402634
OS 29.06758982 -36.95657582
OS 29.32554206 -36.95657582
OS 29.33524994 -36.95518898
OS 29.34495782 -36.95518898
OS 29.35605254 -36.95380214
OS 29.3824025 -36.95102846
OS 29.41152614 -36.9454811
OS 29.44064978 -36.93716006
OS 29.46699974 -36.92606534
OS 29.4794813 -36.91913114
OS 29.48918918 -36.9108101
OS 29.49196286 -36.90803642
OS 29.49751022 -36.90248906
OS 29.50583126 -36.89139434
OS 29.51553914 -36.87752594
OS 29.52524702 -36.85949702
OS 29.53356806 -36.83730758
OS 29.53911542 -36.81234446
OS 29.5418891 -36.78322082
OS 29.5418891 -36.78183398
OS 29.5418891 -36.78044714
OS 29.5418891 -36.77351294
OS 29.54050226 -36.76103138
OS 29.53772858 -36.74716298
OS 29.5349549 -36.73190774
OS 29.52940754 -36.71387882
OS 29.5210865 -36.69723674
OS 29.51137862 -36.68059466
OS 29.50999178 -36.67920782
OS 29.50583126 -36.67366046
OS 29.49889706 -36.66672626
OS 29.49057602 -36.65701838
OS 29.47809446 -36.6473105
OS 29.46422606 -36.63898946
OS 29.44897082 -36.63066842
OS 29.4309419 -36.62373422
OS 29.42955506 -36.62373422
OS 29.4240077 -36.62234738
OS 29.41568666 -36.62096054
OS 29.40459194 -36.61818686
OS 29.38794986 -36.61680002
OS 29.36714726 -36.61541318
OS 29.34218414 -36.61402634
OE
OB 30.16180658 -36.60015794 H
OS 30.16180658 -36.60154478
OS 30.16041974 -36.60431846
OS 30.16041974 -36.60986582
OS 30.15764606 -36.61541318
OS 30.15625922 -36.62512106
OS 30.15348554 -36.63482894
OS 30.14793818 -36.65840522
OS 30.14100398 -36.68614202
OS 30.1312961 -36.7166525
OS 30.12158822 -36.74993666
OS 30.10910666 -36.78460766
OS 30.00509366 -37.06474934
OS 30.32961422 -37.06474934
OS 30.22976174 -36.80124974
OS 30.22976174 -36.7998629
OS 30.2283749 -36.79570238
OS 30.22560122 -36.78876818
OS 30.22282754 -36.78044714
OS 30.21866702 -36.77073926
OS 30.2145065 -36.7582577
OS 30.21034598 -36.7443893
OS 30.20479862 -36.7305209
OS 30.1937039 -36.69862358
OS 30.18260918 -36.66533942
OS 30.17151446 -36.63205526
OS 30.16180658 -36.60015794
OE
OB 31.16033138 -36.60709214 H
OS 30.85800026 -36.60709214
OS 30.85800026 -36.9246785
OS 31.1436893 -36.9246785
OS 31.16033138 -36.92329166
OS 31.17974714 -36.92190482
OS 31.20193658 -36.92051798
OS 31.22412602 -36.9177443
OS 31.24631546 -36.91358378
OS 31.26573122 -36.90803642
OS 31.2685049 -36.90664958
OS 31.27405226 -36.9038759
OS 31.2823733 -36.89971538
OS 31.29346802 -36.89416802
OS 31.30594958 -36.88584698
OS 31.31843114 -36.8761391
OS 31.3309127 -36.86365754
OS 31.34062058 -36.84978914
OS 31.34200742 -36.8484023
OS 31.3447811 -36.84285494
OS 31.34894162 -36.8345339
OS 31.35448898 -36.82343918
OS 31.3586495 -36.81095762
OS 31.36281002 -36.79708922
OS 31.3655837 -36.78044714
OS 31.36697054 -36.76380506
OS 31.36697054 -36.76241822
OS 31.36697054 -36.76103138
OS 31.3655837 -36.75271034
OS 31.36419686 -36.74022878
OS 31.36142318 -36.7235867
OS 31.35448898 -36.70694462
OS 31.34616794 -36.68752886
OS 31.33368638 -36.66949994
OS 31.3170443 -36.65147102
OS 31.31427062 -36.65008418
OS 31.30733642 -36.64453682
OS 31.2962417 -36.63760262
OS 31.27821278 -36.62928158
OS 31.25741018 -36.62096054
OS 31.22967338 -36.61402634
OS 31.19777606 -36.60847898
OS 31.16033138 -36.60709214
OE
OB 36.29302622 -36.61402634 H
OS 36.06558446 -36.61402634
OS 36.06558446 -36.90248906
OS 36.30134726 -36.90248906
OS 36.31937618 -36.90110222
OS 36.33879194 -36.89971538
OS 36.3582077 -36.89832854
OS 36.37762346 -36.89555486
OS 36.3928787 -36.89278118
OS 36.39565238 -36.89139434
OS 36.40119974 -36.8900075
OS 36.40952078 -36.88584698
OS 36.4206155 -36.88029962
OS 36.43171022 -36.87475226
OS 36.44419178 -36.86643122
OS 36.45667334 -36.8553365
OS 36.46638122 -36.84424178
OS 36.46776806 -36.84285494
OS 36.47054174 -36.83869442
OS 36.47470226 -36.83037338
OS 36.47886278 -36.8206655
OS 36.4830233 -36.80957078
OS 36.48718382 -36.79570238
OS 36.4899575 -36.7790603
OS 36.49134434 -36.76103138
OS 36.49134434 -36.7582577
OS 36.49134434 -36.75271034
OS 36.4899575 -36.7443893
OS 36.48857066 -36.73329458
OS 36.48579698 -36.71942618
OS 36.48163646 -36.70555778
OS 36.4760891 -36.69168938
OS 36.46776806 -36.67782098
OS 36.46638122 -36.67643414
OS 36.46360754 -36.67227362
OS 36.45806018 -36.66533942
OS 36.45112598 -36.65840522
OS 36.4414181 -36.65008418
OS 36.43032338 -36.64176314
OS 36.41645498 -36.6334421
OS 36.40119974 -36.62789474
OS 36.3998129 -36.62789474
OS 36.3928787 -36.62512106
OS 36.38317082 -36.62373422
OS 36.36791558 -36.62096054
OS 36.34711298 -36.61818686
OS 36.3235367 -36.61680002
OS 36.29302622 -36.61402634
OE
OB 36.31798934 -37.01620994 H
OS 36.06558446 -37.01620994
OS 36.06558446 -37.34627786
OS 36.33879194 -37.34627786
OS 36.36791558 -37.34489102
OS 36.38039714 -37.34350418
OS 36.39149186 -37.34211734
OS 36.3928787 -37.34211734
OS 36.39842606 -37.3407305
OS 36.4067471 -37.33934366
OS 36.41645498 -37.33656998
OS 36.44003126 -37.32824894
OS 36.46360754 -37.31715422
OS 36.46499438 -37.31576738
OS 36.4691549 -37.3129937
OS 36.47470226 -37.30883318
OS 36.48163646 -37.30328582
OS 36.48857066 -37.29496478
OS 36.49827854 -37.28664374
OS 36.50521274 -37.27554902
OS 36.51353378 -37.26306746
OS 36.51492062 -37.26168062
OS 36.51630746 -37.2575201
OS 36.51908114 -37.24919906
OS 36.52324166 -37.23949118
OS 36.52740218 -37.22839646
OS 36.53017586 -37.21452806
OS 36.5315627 -37.19788598
OS 36.53294954 -37.1812439
OS 36.53294954 -37.17847022
OS 36.53294954 -37.17292286
OS 36.5315627 -37.16182814
OS 36.52878902 -37.14934658
OS 36.52601534 -37.13547818
OS 36.52046798 -37.12022294
OS 36.51353378 -37.1049677
OS 36.5038259 -37.08971246
OS 36.50243906 -37.08832562
OS 36.49827854 -37.08277826
OS 36.49273118 -37.07584406
OS 36.48441014 -37.06752302
OS 36.47331542 -37.05781514
OS 36.45944702 -37.04810726
OS 36.44419178 -37.03978622
OS 36.42616286 -37.03285202
OS 36.42338918 -37.03146518
OS 36.41784182 -37.03007834
OS 36.40536026 -37.02730466
OS 36.39010502 -37.02453098
OS 36.37068926 -37.0217573
OS 36.34711298 -37.01898362
OS 36.31798934 -37.01620994
OE
SE
S P 0
OB 40.9056459 -38.32112732 I
OS 40.92136342 -38.32205188
OS 40.9380055 -38.32297644
OS 40.95372302 -38.32482556
OS 40.96759142 -38.32667468
OS 40.96944054 -38.32667468
OS 40.97591246 -38.3285238
OS 40.9842335 -38.33037292
OS 40.99532822 -38.3331466
OS 41.0073475 -38.3377694
OS 41.02029134 -38.34331676
OS 41.03415974 -38.34978868
OS 41.04617902 -38.35718516
OS 41.04802814 -38.35810972
OS 41.05172638 -38.3608834
OS 41.05727374 -38.36643076
OS 41.06467022 -38.37290268
OS 41.07299126 -38.38122372
OS 41.0813123 -38.39231844
OS 41.0905579 -38.40433772
OS 41.09795438 -38.41820612
OS 41.09887894 -38.42005524
OS 41.10072806 -38.42467804
OS 41.1044263 -38.43299908
OS 41.10812454 -38.4440938
OS 41.11089822 -38.45703764
OS 41.11459646 -38.4718306
OS 41.11644558 -38.48847268
OS 41.11737014 -38.50603932
OS 41.11737014 -38.50696388
OS 41.11737014 -38.50973756
OS 41.11737014 -38.5134358
OS 41.11644558 -38.51990772
OS 41.11552102 -38.52637964
OS 41.11459646 -38.53470068
OS 41.11274734 -38.54394628
OS 41.11089822 -38.55411644
OS 41.1044263 -38.57538132
OS 41.10072806 -38.58647604
OS 41.0951807 -38.59849532
OS 41.08870878 -38.6105146
OS 41.08223686 -38.62160932
OS 41.07391582 -38.63270404
OS 41.06467022 -38.64379876
OS 41.06374566 -38.64472332
OS 41.06189654 -38.64657244
OS 41.05912286 -38.64934612
OS 41.05450006 -38.6521198
OS 41.0489527 -38.6567426
OS 41.04155622 -38.6613654
OS 41.03231062 -38.66691276
OS 41.02214046 -38.67153556
OS 41.01012118 -38.67708292
OS 40.99625278 -38.68263028
OS 40.98145982 -38.68725308
OS 40.96389318 -38.69095132
OS 40.94540198 -38.69464956
OS 40.92506166 -38.69742324
OS 40.90194766 -38.69927236
OS 40.8779091 -38.70019692
OS 40.71426198 -38.70019692
OS 40.71426198 -38.95999828
OS 40.62920246 -38.95999828
OS 40.62920246 -38.32020276
OS 40.8917775 -38.32020276
OS 40.9056459 -38.32112732
OE
OB 40.49791494 -38.98403684 I
OS 40.49791494 -38.9849614
OS 40.49791494 -38.98773508
OS 40.49791494 -38.99235788
OS 40.49791494 -38.99790524
OS 40.49699038 -39.00530172
OS 40.49699038 -39.0126982
OS 40.49514126 -39.0311894
OS 40.49236758 -39.05060516
OS 40.48866934 -39.07094548
OS 40.48312198 -39.08851212
OS 40.47942374 -39.09683316
OS 40.4757255 -39.10330508
OS 40.4757255 -39.10422964
OS 40.47480094 -39.1051542
OS 40.47017814 -39.109777
OS 40.46278166 -39.11717348
OS 40.45353606 -39.12549452
OS 40.44059222 -39.13381556
OS 40.42395014 -39.14028748
OS 40.40453438 -39.14583484
OS 40.39343966 -39.1467594
OS 40.38142038 -39.14768396
OS 40.37587302 -39.14768396
OS 40.37032566 -39.1467594
OS 40.36200462 -39.1467594
OS 40.35275902 -39.14583484
OS 40.34258886 -39.14398572
OS 40.32039942 -39.13843836
OS 40.33519238 -39.07187004
OS 40.33611694 -39.07187004
OS 40.33889062 -39.0727946
OS 40.34351342 -39.07371916
OS 40.34813622 -39.07464372
OS 40.3601555 -39.0774174
OS 40.36570286 -39.07834196
OS 40.37494846 -39.07834196
OS 40.37957126 -39.0774174
OS 40.38511862 -39.07649284
OS 40.39066598 -39.07464372
OS 40.39621334 -39.07094548
OS 40.40268526 -39.06724724
OS 40.40730806 -39.06169988
OS 40.40823262 -39.06077532
OS 40.40915718 -39.05800164
OS 40.4110063 -39.05337884
OS 40.41377998 -39.04598236
OS 40.4156291 -39.0358122
OS 40.41655366 -39.02841572
OS 40.41747822 -39.0219438
OS 40.41840278 -39.01362276
OS 40.41840278 -39.0034526
OS 40.41932734 -38.99328244
OS 40.41932734 -38.98218772
OS 40.41932734 -38.49586916
OS 40.49791494 -38.49586916
OS 40.49791494 -38.98403684
OE
OB 41.51770462 -38.3100326 I
OS 41.52602566 -38.31095716
OS 41.53619582 -38.31188172
OS 41.54636598 -38.31280628
OS 41.55838526 -38.31557996
OS 41.58334838 -38.32112732
OS 41.61108518 -38.32944836
OS 41.62495358 -38.33499572
OS 41.63789742 -38.34146764
OS 41.65084126 -38.34978868
OS 41.6637851 -38.35810972
OS 41.66470966 -38.35903428
OS 41.66655878 -38.35995884
OS 41.67025702 -38.36273252
OS 41.67487982 -38.36735532
OS 41.67950262 -38.37197812
OS 41.68597454 -38.37845004
OS 41.69244646 -38.38584652
OS 41.69984294 -38.393243
OS 41.70723942 -38.4024886
OS 41.7146359 -38.41358332
OS 41.72295694 -38.42467804
OS 41.73035342 -38.43669732
OS 41.73682534 -38.45056572
OS 41.74422182 -38.46443412
OS 41.74976918 -38.47922708
OS 41.75531654 -38.49586916
OS 41.67210614 -38.51528492
OS 41.67210614 -38.51436036
OS 41.67118158 -38.51251124
OS 41.66933246 -38.508813
OS 41.66748334 -38.5041902
OS 41.66563422 -38.49864284
OS 41.66286054 -38.49124636
OS 41.65546406 -38.4764534
OS 41.64621846 -38.45981132
OS 41.63512374 -38.44316924
OS 41.62125534 -38.42745172
OS 41.60646238 -38.41358332
OS 41.60461326 -38.4117342
OS 41.5990659 -38.40803596
OS 41.5898203 -38.40341316
OS 41.57780102 -38.39694124
OS 41.5620835 -38.39139388
OS 41.54451686 -38.38584652
OS 41.52325198 -38.38214828
OS 41.50013798 -38.38122372
OS 41.4927415 -38.38122372
OS 41.4881187 -38.38214828
OS 41.48164678 -38.38214828
OS 41.4742503 -38.38307284
OS 41.45668366 -38.38584652
OS 41.4372679 -38.38954476
OS 41.41692758 -38.39601668
OS 41.3956627 -38.40526228
OS 41.37624694 -38.41728156
OS 41.37532238 -38.41728156
OS 41.37439782 -38.41913068
OS 41.3679259 -38.42375348
OS 41.35960486 -38.43114996
OS 41.3494347 -38.44224468
OS 41.33741542 -38.45611308
OS 41.3263207 -38.4718306
OS 41.31615054 -38.49124636
OS 41.30690494 -38.51251124
OS 41.30690494 -38.5134358
OS 41.30598038 -38.51528492
OS 41.30505582 -38.5180586
OS 41.30413126 -38.5226814
OS 41.30228214 -38.52822876
OS 41.30043302 -38.53470068
OS 41.29765934 -38.5504182
OS 41.2939611 -38.5689094
OS 41.29026286 -38.58924972
OS 41.28841374 -38.61143916
OS 41.28748918 -38.63547772
OS 41.28748918 -38.63640228
OS 41.28748918 -38.63917596
OS 41.28748918 -38.64379876
OS 41.28748918 -38.64934612
OS 41.28841374 -38.65581804
OS 41.28841374 -38.66413908
OS 41.2893383 -38.67338468
OS 41.29026286 -38.68355484
OS 41.29303654 -38.70574428
OS 41.29765934 -38.72978284
OS 41.3032067 -38.7538214
OS 41.31060318 -38.77785996
OS 41.31060318 -38.77878452
OS 41.31152774 -38.78063364
OS 41.31337686 -38.78340732
OS 41.31522598 -38.78803012
OS 41.32077334 -38.79912484
OS 41.32909438 -38.81206868
OS 41.33926454 -38.82686164
OS 41.35220838 -38.84257916
OS 41.36700134 -38.85644756
OS 41.38456798 -38.8693914
OS 41.38549254 -38.8693914
OS 41.38734166 -38.87031596
OS 41.39011534 -38.87216508
OS 41.39381358 -38.8740142
OS 41.39843638 -38.87586332
OS 41.40398374 -38.878637
OS 41.41692758 -38.88418436
OS 41.43356966 -38.88973172
OS 41.45206086 -38.89435452
OS 41.47240118 -38.89805276
OS 41.49366606 -38.89897732
OS 41.50013798 -38.89897732
OS 41.50568534 -38.89805276
OS 41.51215726 -38.89805276
OS 41.51862918 -38.8971282
OS 41.53527126 -38.89342996
OS 41.55468702 -38.88880716
OS 41.57410278 -38.88141068
OS 41.5944431 -38.87124052
OS 41.60461326 -38.86569316
OS 41.61385886 -38.85829668
OS 41.61478342 -38.85737212
OS 41.61570798 -38.85644756
OS 41.61848166 -38.85367388
OS 41.6221799 -38.8509002
OS 41.62587814 -38.8462774
OS 41.63050094 -38.84073004
OS 41.6360483 -38.83518268
OS 41.6406711 -38.8277862
OS 41.64621846 -38.81946516
OS 41.65269038 -38.81021956
OS 41.65823774 -38.80097396
OS 41.6637851 -38.78987924
OS 41.6684079 -38.77785996
OS 41.6730307 -38.76491612
OS 41.6776535 -38.75104772
OS 41.68135174 -38.73625476
OS 41.76641126 -38.75751964
OS 41.76641126 -38.7584442
OS 41.7654867 -38.76214244
OS 41.76363758 -38.7676898
OS 41.7608639 -38.77508628
OS 41.75809022 -38.78340732
OS 41.75439198 -38.79357748
OS 41.74976918 -38.8046722
OS 41.74422182 -38.81669148
OS 41.73127798 -38.84257916
OS 41.7146359 -38.86846684
OS 41.70446574 -38.88141068
OS 41.69429558 -38.89435452
OS 41.68320086 -38.90544924
OS 41.67025702 -38.91654396
OS 41.66933246 -38.91746852
OS 41.66748334 -38.91931764
OS 41.66286054 -38.92116676
OS 41.65823774 -38.924865
OS 41.65084126 -38.9294878
OS 41.64344478 -38.9341106
OS 41.63327462 -38.9387334
OS 41.62310446 -38.9433562
OS 41.61108518 -38.94890356
OS 41.59814134 -38.95352636
OS 41.58427294 -38.95814916
OS 41.56947998 -38.96277196
OS 41.55376246 -38.9664702
OS 41.53712038 -38.96831932
OS 41.51955374 -38.97016844
OS 41.50106254 -38.971093
OS 41.49089238 -38.971093
OS 41.4834959 -38.97016844
OS 41.47517486 -38.97016844
OS 41.4650047 -38.96924388
OS 41.45390998 -38.96739476
OS 41.44096614 -38.96554564
OS 41.4141539 -38.96092284
OS 41.3864171 -38.95352636
OS 41.3586803 -38.9433562
OS 41.34573646 -38.93688428
OS 41.33279262 -38.9294878
OS 41.33186806 -38.92856324
OS 41.33001894 -38.92763868
OS 41.3263207 -38.924865
OS 41.32262246 -38.92116676
OS 41.3170751 -38.91746852
OS 41.31060318 -38.91192116
OS 41.3032067 -38.90544924
OS 41.29581022 -38.89805276
OS 41.28841374 -38.88973172
OS 41.2800927 -38.88141068
OS 41.26345062 -38.8601458
OS 41.2477331 -38.83518268
OS 41.2338647 -38.80744588
OS 41.2338647 -38.80652132
OS 41.23201558 -38.80374764
OS 41.23109102 -38.79912484
OS 41.22831734 -38.79357748
OS 41.22646822 -38.786181
OS 41.22369454 -38.7769354
OS 41.2199963 -38.76676524
OS 41.21722262 -38.75567052
OS 41.21444894 -38.74365124
OS 41.2107507 -38.72978284
OS 41.2061279 -38.70112148
OS 41.20242966 -38.66876188
OS 41.20058054 -38.63547772
OS 41.20058054 -38.63455316
OS 41.20058054 -38.63085492
OS 41.20058054 -38.62530756
OS 41.2015051 -38.61883564
OS 41.2015051 -38.60959004
OS 41.20242966 -38.60034444
OS 41.20335422 -38.58832516
OS 41.20520334 -38.57630588
OS 41.20982614 -38.54949364
OS 41.21629806 -38.51990772
OS 41.22554366 -38.4903218
OS 41.2384875 -38.46166044
OS 41.23941206 -38.46073588
OS 41.24033662 -38.4579622
OS 41.24218574 -38.45426396
OS 41.24588398 -38.44964116
OS 41.24958222 -38.44316924
OS 41.25420502 -38.43577276
OS 41.2662243 -38.41913068
OS 41.28194182 -38.40063948
OS 41.30043302 -38.38214828
OS 41.3216979 -38.36365708
OS 41.34666102 -38.34793956
OS 41.34758558 -38.347015
OS 41.35035926 -38.34609044
OS 41.3540575 -38.34424132
OS 41.3586803 -38.34146764
OS 41.36607678 -38.33869396
OS 41.37347326 -38.33592028
OS 41.38271886 -38.33222204
OS 41.39288902 -38.3285238
OS 41.40398374 -38.32482556
OS 41.41600302 -38.32112732
OS 41.4418907 -38.31557996
OS 41.47147662 -38.31095716
OS 41.5019871 -38.30910804
OS 41.5112327 -38.30910804
OS 41.51770462 -38.3100326
OE
OB 42.90454462 -39.1375138 I
OS 42.38401734 -39.1375138
OS 42.38401734 -39.08111564
OS 42.90454462 -39.08111564
OS 42.90454462 -39.1375138
OE
OB 42.12514054 -38.32112732 I
OS 42.13253702 -38.32112732
OS 42.1491791 -38.32297644
OS 42.1676703 -38.32482556
OS 42.18708606 -38.3285238
OS 42.20650182 -38.3331466
OS 42.22406846 -38.33961852
OS 42.22499302 -38.33961852
OS 42.22591758 -38.34054308
OS 42.23146494 -38.34331676
OS 42.23978598 -38.34793956
OS 42.24903158 -38.35441148
OS 42.2601263 -38.36273252
OS 42.27214558 -38.37290268
OS 42.2832403 -38.38584652
OS 42.29341046 -38.39971492
OS 42.29433502 -38.40156404
OS 42.2971087 -38.4071114
OS 42.3017315 -38.41450788
OS 42.3063543 -38.4256026
OS 42.3109771 -38.43854644
OS 42.3155999 -38.45241484
OS 42.31837358 -38.46813236
OS 42.31929814 -38.48384988
OS 42.31929814 -38.485699
OS 42.31929814 -38.4903218
OS 42.31837358 -38.49864284
OS 42.31652446 -38.508813
OS 42.31375078 -38.52083228
OS 42.30912798 -38.53377612
OS 42.30358062 -38.54671996
OS 42.29618414 -38.56058836
OS 42.29525958 -38.56243748
OS 42.2924859 -38.56613572
OS 42.28693854 -38.5735322
OS 42.27954206 -38.58092868
OS 42.27029646 -38.59017428
OS 42.25920174 -38.60034444
OS 42.24533334 -38.60959004
OS 42.22961582 -38.61883564
OS 42.23054038 -38.61883564
OS 42.2323895 -38.6197602
OS 42.23516318 -38.62068476
OS 42.23886142 -38.62253388
OS 42.24995614 -38.62623212
OS 42.26289998 -38.63270404
OS 42.27676838 -38.64102508
OS 42.2924859 -38.65119524
OS 42.3063543 -38.66321452
OS 42.31929814 -38.67800748
OS 42.3202227 -38.6798566
OS 42.32392094 -38.68540396
OS 42.3294683 -38.693725
OS 42.33501566 -38.70481972
OS 42.34056302 -38.71961268
OS 42.34611038 -38.7353302
OS 42.34980862 -38.7538214
OS 42.35073318 -38.77416172
OS 42.35073318 -38.77508628
OS 42.35073318 -38.77601084
OS 42.35073318 -38.7815582
OS 42.34980862 -38.7908038
OS 42.3479595 -38.80189852
OS 42.34611038 -38.81484236
OS 42.34241214 -38.82871076
OS 42.33778934 -38.84350372
OS 42.33131742 -38.85829668
OS 42.33039286 -38.8601458
OS 42.32761918 -38.8647686
OS 42.32392094 -38.87124052
OS 42.31837358 -38.88048612
OS 42.3109771 -38.88973172
OS 42.30358062 -38.89990188
OS 42.29433502 -38.91007204
OS 42.28416486 -38.91839308
OS 42.2832403 -38.91931764
OS 42.27954206 -38.92209132
OS 42.27307014 -38.92578956
OS 42.2647491 -38.9294878
OS 42.25457894 -38.93503516
OS 42.24255966 -38.94058252
OS 42.22961582 -38.94520532
OS 42.2138983 -38.94982812
OS 42.21204918 -38.94982812
OS 42.20650182 -38.95167724
OS 42.19725622 -38.9526018
OS 42.18523694 -38.95445092
OS 42.17044398 -38.95630004
OS 42.15287734 -38.95814916
OS 42.13346158 -38.95907372
OS 42.11127214 -38.95999828
OS 41.8671883 -38.95999828
OS 41.8671883 -38.32020276
OS 42.11866862 -38.32020276
OS 42.12514054 -38.32112732
OE
OB 40.30745558 -38.48662356 I
OS 40.31762574 -38.48847268
OS 40.32964502 -38.49217092
OS 40.34258886 -38.49679372
OS 40.35738182 -38.50326564
OS 40.37309934 -38.51158668
OS 40.34443798 -38.58370236
OS 40.34351342 -38.5827778
OS 40.33981518 -38.58092868
OS 40.33426782 -38.578155
OS 40.32687134 -38.57538132
OS 40.3185503 -38.57260764
OS 40.30838014 -38.56983396
OS 40.29820998 -38.56798484
OS 40.28803982 -38.56706028
OS 40.28341702 -38.56706028
OS 40.27879422 -38.56798484
OS 40.2723223 -38.5689094
OS 40.26585038 -38.57075852
OS 40.25752934 -38.5735322
OS 40.2492083 -38.57723044
OS 40.24181182 -38.5827778
OS 40.24088726 -38.58370236
OS 40.23811358 -38.58555148
OS 40.2353399 -38.58924972
OS 40.2307171 -38.59387252
OS 40.2260943 -38.60034444
OS 40.2214715 -38.60774092
OS 40.2168487 -38.61606196
OS 40.21315046 -38.62623212
OS 40.2122259 -38.62808124
OS 40.21130134 -38.6336286
OS 40.20945222 -38.64194964
OS 40.20667854 -38.65304436
OS 40.20390486 -38.66691276
OS 40.20205574 -38.68263028
OS 40.20113118 -38.69927236
OS 40.20020662 -38.71776356
OS 40.20020662 -38.95999828
OS 40.12161902 -38.95999828
OS 40.12161902 -38.49586916
OS 40.19281014 -38.49586916
OS 40.19281014 -38.56613572
OS 40.1937347 -38.56521116
OS 40.19743294 -38.55873924
OS 40.20205574 -38.5504182
OS 40.20945222 -38.54024804
OS 40.2168487 -38.53007788
OS 40.22516974 -38.51898316
OS 40.23349078 -38.50973756
OS 40.24181182 -38.50234108
OS 40.24273638 -38.50141652
OS 40.24551006 -38.4995674
OS 40.25105742 -38.49679372
OS 40.25660478 -38.49402004
OS 40.26400126 -38.49124636
OS 40.27324686 -38.48847268
OS 40.28249246 -38.48662356
OS 40.29266262 -38.485699
OS 40.29913454 -38.485699
OS 40.30745558 -38.48662356
OE
OB 39.48829542 -38.95999828 I
OS 39.3986131 -38.95999828
OS 39.3986131 -38.87031596
OS 39.48829542 -38.87031596
OS 39.48829542 -38.95999828
OE
OB 38.6404739 -38.95999828 I
OS 38.55171614 -38.95999828
OS 38.30393406 -38.32020276
OS 38.39639006 -38.32020276
OS 38.56281086 -38.78525644
OS 38.56281086 -38.786181
OS 38.56373542 -38.78803012
OS 38.56465998 -38.7908038
OS 38.5665091 -38.79450204
OS 38.56743366 -38.8000494
OS 38.56928278 -38.80559676
OS 38.57390558 -38.81946516
OS 38.57945294 -38.83518268
OS 38.5850003 -38.85274932
OS 38.59609502 -38.88973172
OS 38.59609502 -38.88880716
OS 38.59701958 -38.88695804
OS 38.59794414 -38.88418436
OS 38.5988687 -38.88048612
OS 38.60164238 -38.87031596
OS 38.60626518 -38.85644756
OS 38.61088798 -38.84073004
OS 38.61643534 -38.8231634
OS 38.62290726 -38.8046722
OS 38.63030374 -38.78525644
OS 38.80412102 -38.32020276
OS 38.8901051 -38.32020276
OS 38.6404739 -38.95999828
OE
OB 39.27564662 -38.42745172 I
OS 39.25438174 -38.54671996
OS 39.20538006 -38.54671996
OS 39.1859643 -38.42745172
OS 39.1859643 -38.32020276
OS 39.27564662 -38.32020276
OS 39.27564662 -38.42745172
OE
OB 40.49791494 -38.4117342 I
OS 40.41932734 -38.4117342
OS 40.41932734 -38.32020276
OS 40.49791494 -38.32020276
OS 40.49791494 -38.4117342
OE
OB 39.84517558 -38.48662356 I
OS 39.8516475 -38.48754812
OS 39.8655159 -38.48939724
OS 39.88215798 -38.49309548
OS 39.89972462 -38.49864284
OS 39.91729126 -38.50696388
OS 39.9348579 -38.51713404
OS 39.93578246 -38.51713404
OS 39.93670702 -38.51898316
OS 39.94225438 -38.5226814
OS 39.95057542 -38.53007788
OS 39.96074558 -38.53932348
OS 39.9718403 -38.55134276
OS 39.98293502 -38.56613572
OS 39.99402974 -38.58370236
OS 40.00327534 -38.60311812
OS 40.00327534 -38.60404268
OS 40.0041999 -38.6058918
OS 40.00512446 -38.60866548
OS 40.00697358 -38.61236372
OS 40.0088227 -38.61791108
OS 40.01067182 -38.624383
OS 40.01529462 -38.63917596
OS 40.01991742 -38.65766716
OS 40.02361566 -38.67800748
OS 40.02638934 -38.70112148
OS 40.0273139 -38.72516004
OS 40.0273139 -38.7260846
OS 40.0273139 -38.72793372
OS 40.0273139 -38.73163196
OS 40.0273139 -38.73717932
OS 40.02638934 -38.74365124
OS 40.02638934 -38.75104772
OS 40.02454022 -38.7676898
OS 40.02084198 -38.78803012
OS 40.01621918 -38.809295
OS 40.00974726 -38.83148444
OS 40.00142622 -38.85367388
OS 40.00142622 -38.85459844
OS 40.00050166 -38.85644756
OS 39.99865254 -38.85922124
OS 39.99680342 -38.86291948
OS 39.9903315 -38.87308964
OS 39.98201046 -38.88603348
OS 39.9718403 -38.89990188
OS 39.95889646 -38.91377028
OS 39.9441035 -38.92763868
OS 39.92653686 -38.94058252
OS 39.9256123 -38.94058252
OS 39.92468774 -38.94150708
OS 39.92191406 -38.9433562
OS 39.91821582 -38.94520532
OS 39.90897022 -38.94982812
OS 39.89602638 -38.95537548
OS 39.88030886 -38.96092284
OS 39.86366678 -38.96554564
OS 39.84425102 -38.96924388
OS 39.82483526 -38.97016844
OS 39.81836334 -38.97016844
OS 39.81096686 -38.96924388
OS 39.80172126 -38.96831932
OS 39.79062654 -38.9664702
OS 39.77860726 -38.96369652
OS 39.76658798 -38.95999828
OS 39.7545687 -38.95445092
OS 39.75364414 -38.95352636
OS 39.74902134 -38.95167724
OS 39.74347398 -38.947979
OS 39.7360775 -38.94243164
OS 39.72868102 -38.93688428
OS 39.71943542 -38.9294878
OS 39.71111438 -38.92116676
OS 39.7037179 -38.91192116
OS 39.7037179 -39.1375138
OS 39.6251303 -39.1375138
OS 39.6251303 -38.49586916
OS 39.69632142 -38.49586916
OS 39.69632142 -38.55689012
OS 39.69724598 -38.555041
OS 39.70094422 -38.55134276
OS 39.70556702 -38.54487084
OS 39.7129635 -38.53747436
OS 39.72128454 -38.52822876
OS 39.73053014 -38.51990772
OS 39.74162486 -38.51158668
OS 39.75271958 -38.5041902
OS 39.7545687 -38.50326564
OS 39.75826694 -38.50141652
OS 39.76566342 -38.49864284
OS 39.77490902 -38.4949446
OS 39.78600374 -38.49124636
OS 39.79894758 -38.48847268
OS 39.81374054 -38.48662356
OS 39.83038262 -38.485699
OS 39.84055278 -38.485699
OS 39.84517558 -38.48662356
OE
OB 44.92193454 -38.40988508 I
OS 44.84334694 -38.40988508
OS 44.84334694 -38.32020276
OS 44.92193454 -38.32020276
OS 44.92193454 -38.40988508
OE
OB 45.24553054 -38.48662356 I
OS 45.25385158 -38.48754812
OS 45.26309718 -38.48939724
OS 45.27326734 -38.49124636
OS 45.28528662 -38.49309548
OS 45.31024974 -38.50141652
OS 45.32319358 -38.50603932
OS 45.33613742 -38.51251124
OS 45.34908126 -38.51898316
OS 45.3620251 -38.52822876
OS 45.37404438 -38.53747436
OS 45.38606366 -38.54856908
OS 45.38698822 -38.54949364
OS 45.38883734 -38.55134276
OS 45.39161102 -38.555041
OS 45.39530926 -38.5596638
OS 45.39993206 -38.56613572
OS 45.40547942 -38.57445676
OS 45.41102678 -38.58370236
OS 45.41657414 -38.59387252
OS 45.4221215 -38.60496724
OS 45.42766886 -38.61883564
OS 45.43321622 -38.63270404
OS 45.43783902 -38.64842156
OS 45.44153726 -38.66506364
OS 45.44431094 -38.68263028
OS 45.44616006 -38.70112148
OS 45.44708462 -38.7214618
OS 45.44708462 -38.72238636
OS 45.44708462 -38.72516004
OS 45.44708462 -38.72978284
OS 45.44708462 -38.73625476
OS 45.44616006 -38.74365124
OS 45.4452355 -38.75289684
OS 45.4452355 -38.76214244
OS 45.44338638 -38.7723126
OS 45.4406127 -38.7954266
OS 45.43506534 -38.8185406
OS 45.42859342 -38.8416546
OS 45.41934782 -38.86291948
OS 45.41934782 -38.86384404
OS 45.41842326 -38.8647686
OS 45.41657414 -38.86754228
OS 45.41472502 -38.87124052
OS 45.4082531 -38.88048612
OS 45.39993206 -38.89158084
OS 45.38883734 -38.90452468
OS 45.37496894 -38.91746852
OS 45.35925142 -38.93041236
OS 45.34076022 -38.94243164
OS 45.33983566 -38.94243164
OS 45.3389111 -38.9433562
OS 45.33613742 -38.94520532
OS 45.33151462 -38.94705444
OS 45.32689182 -38.94890356
OS 45.32134446 -38.95075268
OS 45.30747606 -38.95630004
OS 45.29175854 -38.96092284
OS 45.27234278 -38.96554564
OS 45.25200246 -38.96924388
OS 45.22981302 -38.97016844
OS 45.22056742 -38.97016844
OS 45.21317094 -38.96924388
OS 45.2048499 -38.96831932
OS 45.1956043 -38.9664702
OS 45.18450958 -38.96462108
OS 45.17341486 -38.96277196
OS 45.14845174 -38.95537548
OS 45.13458334 -38.94982812
OS 45.1216395 -38.94428076
OS 45.10869566 -38.93688428
OS 45.09575182 -38.92856324
OS 45.08373254 -38.91931764
OS 45.07171326 -38.90822292
OS 45.0707887 -38.90729836
OS 45.06893958 -38.90544924
OS 45.0661659 -38.901751
OS 45.06246766 -38.89620364
OS 45.05784486 -38.88973172
OS 45.05322206 -38.88233524
OS 45.0476747 -38.87308964
OS 45.04212734 -38.86199492
OS 45.03657998 -38.84997564
OS 45.03103262 -38.83610724
OS 45.02640982 -38.82131428
OS 45.02178702 -38.80559676
OS 45.01808878 -38.78803012
OS 45.0153151 -38.76953892
OS 45.01346598 -38.7491986
OS 45.01254142 -38.72793372
OS 45.01254142 -38.7260846
OS 45.01254142 -38.72238636
OS 45.01346598 -38.71591444
OS 45.01346598 -38.70666884
OS 45.01439054 -38.69649868
OS 45.01623966 -38.68355484
OS 45.01808878 -38.670611
OS 45.02178702 -38.65581804
OS 45.02548526 -38.64102508
OS 45.03010806 -38.62530756
OS 45.03565542 -38.60866548
OS 45.0430519 -38.59294796
OS 45.05044838 -38.578155
OS 45.06061854 -38.56336204
OS 45.0707887 -38.54949364
OS 45.08373254 -38.53747436
OS 45.0846571 -38.5365498
OS 45.08650622 -38.53562524
OS 45.09020446 -38.53285156
OS 45.09482726 -38.52915332
OS 45.10037462 -38.52545508
OS 45.1077711 -38.52083228
OS 45.11516758 -38.51620948
OS 45.12441318 -38.51158668
OS 45.13458334 -38.50696388
OS 45.14567806 -38.50234108
OS 45.17064118 -38.49402004
OS 45.19930254 -38.48754812
OS 45.2140955 -38.48662356
OS 45.22981302 -38.485699
OS 45.23905862 -38.485699
OS 45.24553054 -38.48662356
OE
OB 44.92193454 -38.95999828 I
OS 44.84334694 -38.95999828
OS 44.84334694 -38.49586916
OS 44.92193454 -38.49586916
OS 44.92193454 -38.95999828
OE
OB 46.10722046 -38.42745172 I
OS 46.08595558 -38.54671996
OS 46.0369539 -38.54671996
OS 46.01753814 -38.42745172
OS 46.01753814 -38.32020276
OS 46.10722046 -38.32020276
OS 46.10722046 -38.42745172
OE
OB 45.77160518 -38.48662356 I
OS 45.78177534 -38.48754812
OS 45.79379462 -38.48939724
OS 45.80673846 -38.49217092
OS 45.82060686 -38.49586916
OS 45.8335507 -38.50141652
OS 45.83539982 -38.50234108
OS 45.83909806 -38.5041902
OS 45.84556998 -38.50696388
OS 45.85296646 -38.51158668
OS 45.86221206 -38.51713404
OS 45.8705331 -38.52453052
OS 45.87885414 -38.531927
OS 45.88625062 -38.5411726
OS 45.88717518 -38.54209716
OS 45.8890243 -38.5457954
OS 45.89179798 -38.5504182
OS 45.89642078 -38.55689012
OS 45.90011902 -38.56613572
OS 45.90381726 -38.57538132
OS 45.90844006 -38.58647604
OS 45.91121374 -38.59849532
OS 45.91121374 -38.59941988
OS 45.9121383 -38.60311812
OS 45.91306286 -38.60866548
OS 45.91398742 -38.61606196
OS 45.91398742 -38.62715668
OS 45.91491198 -38.64010052
OS 45.91583654 -38.65581804
OS 45.91583654 -38.6752338
OS 45.91583654 -38.95999828
OS 45.83724894 -38.95999828
OS 45.83724894 -38.67893204
OS 45.83724894 -38.67800748
OS 45.83724894 -38.67708292
OS 45.83724894 -38.670611
OS 45.83724894 -38.66228996
OS 45.83632438 -38.6521198
OS 45.83539982 -38.64010052
OS 45.8335507 -38.62808124
OS 45.83077702 -38.61698652
OS 45.82800334 -38.60681636
OS 45.82800334 -38.6058918
OS 45.82615422 -38.60311812
OS 45.82338054 -38.59849532
OS 45.82060686 -38.59294796
OS 45.81598406 -38.5874006
OS 45.8104367 -38.58092868
OS 45.80304022 -38.57445676
OS 45.79471918 -38.5689094
OS 45.79379462 -38.56798484
OS 45.79102094 -38.56613572
OS 45.78547358 -38.5642866
OS 45.77900166 -38.56151292
OS 45.77160518 -38.55873924
OS 45.76235958 -38.55596556
OS 45.75126486 -38.555041
OS 45.74017014 -38.55411644
OS 45.73554734 -38.55411644
OS 45.7318491 -38.555041
OS 45.7226035 -38.55596556
OS 45.71058422 -38.55781468
OS 45.69764038 -38.56243748
OS 45.68284742 -38.56798484
OS 45.66805446 -38.57538132
OS 45.65418606 -38.58647604
OS 45.65233694 -38.58832516
OS 45.6486387 -38.59294796
OS 45.64586502 -38.5966462
OS 45.64309134 -38.601269
OS 45.6393931 -38.60681636
OS 45.63661942 -38.61328828
OS 45.63292118 -38.62068476
OS 45.62922294 -38.62993036
OS 45.62644926 -38.64010052
OS 45.62367558 -38.65119524
OS 45.62182646 -38.66321452
OS 45.61997734 -38.67615836
OS 45.61812822 -38.69187588
OS 45.61812822 -38.7075934
OS 45.61812822 -38.95999828
OS 45.53954062 -38.95999828
OS 45.53954062 -38.49586916
OS 45.60980718 -38.49586916
OS 45.60980718 -38.56243748
OS 45.61073174 -38.56151292
OS 45.61258086 -38.55873924
OS 45.61535454 -38.555041
OS 45.61905278 -38.5504182
OS 45.62460014 -38.54487084
OS 45.63107206 -38.53839892
OS 45.63846854 -38.53100244
OS 45.64771414 -38.52360596
OS 45.65695974 -38.51713404
OS 45.66805446 -38.50973756
OS 45.68007374 -38.50326564
OS 45.69301758 -38.49771828
OS 45.70781054 -38.49309548
OS 45.7226035 -38.48939724
OS 45.73924558 -38.48662356
OS 45.75681222 -38.485699
OS 45.7642087 -38.485699
OS 45.77160518 -38.48662356
OE
OB 44.2756671 -38.95999828 I
OS 44.1970795 -38.95999828
OS 44.1970795 -38.49586916
OS 44.2756671 -38.49586916
OS 44.2756671 -38.95999828
OE
OB 43.4574315 -38.48662356 I
OS 43.46482798 -38.48754812
OS 43.47407358 -38.48939724
OS 43.48424374 -38.49124636
OS 43.49626302 -38.49402004
OS 43.50735774 -38.49679372
OS 43.52030158 -38.50141652
OS 43.53232086 -38.50603932
OS 43.5452647 -38.51251124
OS 43.55820854 -38.51990772
OS 43.57115238 -38.52822876
OS 43.58317166 -38.53839892
OS 43.59426638 -38.54949364
OS 43.59519094 -38.5504182
OS 43.59704006 -38.55226732
OS 43.59981374 -38.55596556
OS 43.60351198 -38.56151292
OS 43.60813478 -38.56798484
OS 43.61275758 -38.57538132
OS 43.61830494 -38.58462692
OS 43.6238523 -38.59572164
OS 43.62939966 -38.60774092
OS 43.63494702 -38.62068476
OS 43.63956982 -38.63547772
OS 43.64419262 -38.65119524
OS 43.64789086 -38.66876188
OS 43.65066454 -38.68725308
OS 43.65251366 -38.70666884
OS 43.65343822 -38.72793372
OS 43.65343822 -38.72885828
OS 43.65343822 -38.73255652
OS 43.65343822 -38.73902844
OS 43.65251366 -38.74827404
OS 43.30580366 -38.74827404
OS 43.30580366 -38.7491986
OS 43.30580366 -38.75197228
OS 43.30672822 -38.75567052
OS 43.30672822 -38.76121788
OS 43.30765278 -38.7676898
OS 43.3095019 -38.77508628
OS 43.31227558 -38.79172836
OS 43.31782294 -38.81021956
OS 43.32521942 -38.83055988
OS 43.33538958 -38.84905108
OS 43.34833342 -38.86569316
OS 43.34925798 -38.86569316
OS 43.35018254 -38.86754228
OS 43.3557299 -38.87216508
OS 43.36405094 -38.878637
OS 43.37514566 -38.88510892
OS 43.38993862 -38.8925054
OS 43.4065807 -38.89897732
OS 43.4250719 -38.90360012
OS 43.43524206 -38.90452468
OS 43.44633678 -38.90544924
OS 43.45373326 -38.90544924
OS 43.4620543 -38.90452468
OS 43.47222446 -38.90267556
OS 43.48331918 -38.89990188
OS 43.49626302 -38.89620364
OS 43.5082823 -38.89065628
OS 43.52030158 -38.8832598
OS 43.52122614 -38.88233524
OS 43.52584894 -38.878637
OS 43.5313963 -38.87308964
OS 43.53786822 -38.86569316
OS 43.5452647 -38.855523
OS 43.55358574 -38.84257916
OS 43.56190678 -38.8277862
OS 43.56930326 -38.81021956
OS 43.65066454 -38.82038972
OS 43.65066454 -38.82131428
OS 43.64973998 -38.8231634
OS 43.64881542 -38.82686164
OS 43.6469663 -38.832409
OS 43.64419262 -38.83795636
OS 43.64141894 -38.84535284
OS 43.63402246 -38.86107036
OS 43.62477686 -38.878637
OS 43.61183302 -38.8971282
OS 43.59704006 -38.91469484
OS 43.57854886 -38.93133692
OS 43.5776243 -38.93133692
OS 43.57577518 -38.93318604
OS 43.5730015 -38.93503516
OS 43.56930326 -38.93780884
OS 43.5637559 -38.94058252
OS 43.55820854 -38.9433562
OS 43.55081206 -38.94705444
OS 43.54249102 -38.95075268
OS 43.53324542 -38.95445092
OS 43.52399982 -38.95814916
OS 43.50088582 -38.96369652
OS 43.47499814 -38.96831932
OS 43.44633678 -38.97016844
OS 43.43616662 -38.97016844
OS 43.4296947 -38.96924388
OS 43.42137366 -38.96831932
OS 43.4112035 -38.9664702
OS 43.40010878 -38.96462108
OS 43.3880895 -38.96277196
OS 43.36220182 -38.95537548
OS 43.34833342 -38.94982812
OS 43.33538958 -38.94428076
OS 43.32152118 -38.93688428
OS 43.30857734 -38.92856324
OS 43.29655806 -38.91931764
OS 43.28453878 -38.90822292
OS 43.28361422 -38.90729836
OS 43.2817651 -38.90544924
OS 43.27899142 -38.901751
OS 43.27529318 -38.89620364
OS 43.27067038 -38.88973172
OS 43.26604758 -38.88233524
OS 43.26050022 -38.87308964
OS 43.25495286 -38.86291948
OS 43.2494055 -38.8509002
OS 43.24385814 -38.83795636
OS 43.23923534 -38.8231634
OS 43.23461254 -38.80744588
OS 43.2309143 -38.7908038
OS 43.22814062 -38.7723126
OS 43.2262915 -38.75289684
OS 43.22536694 -38.73255652
OS 43.22536694 -38.73163196
OS 43.22536694 -38.72700916
OS 43.22536694 -38.7214618
OS 43.2262915 -38.71314076
OS 43.22721606 -38.7029706
OS 43.22814062 -38.69187588
OS 43.22998974 -38.67893204
OS 43.23276342 -38.6659882
OS 43.2401599 -38.63640228
OS 43.2447827 -38.62160932
OS 43.25033006 -38.6058918
OS 43.25772654 -38.59109884
OS 43.26604758 -38.57723044
OS 43.27529318 -38.56336204
OS 43.28546334 -38.5504182
OS 43.2863879 -38.54949364
OS 43.28823702 -38.54764452
OS 43.29193526 -38.54487084
OS 43.29655806 -38.54024804
OS 43.30210542 -38.53562524
OS 43.3095019 -38.53007788
OS 43.31782294 -38.52360596
OS 43.3279931 -38.5180586
OS 43.33816326 -38.51158668
OS 43.35018254 -38.50603932
OS 43.36312638 -38.50049196
OS 43.37699478 -38.49586916
OS 43.39178774 -38.49124636
OS 43.40750526 -38.48847268
OS 43.42414734 -38.48662356
OS 43.44171398 -38.485699
OS 43.45095958 -38.485699
OS 43.4574315 -38.48662356
OE
OB 43.13938286 -38.48662356 I
OS 43.14955302 -38.48847268
OS 43.1615723 -38.49217092
OS 43.17451614 -38.49679372
OS 43.1893091 -38.50326564
OS 43.20502662 -38.51158668
OS 43.17636526 -38.58370236
OS 43.1754407 -38.5827778
OS 43.17174246 -38.58092868
OS 43.1661951 -38.578155
OS 43.15879862 -38.57538132
OS 43.15047758 -38.57260764
OS 43.14030742 -38.56983396
OS 43.13013726 -38.56798484
OS 43.1199671 -38.56706028
OS 43.1153443 -38.56706028
OS 43.1107215 -38.56798484
OS 43.10424958 -38.5689094
OS 43.09777766 -38.57075852
OS 43.08945662 -38.5735322
OS 43.08113558 -38.57723044
OS 43.0737391 -38.5827778
OS 43.07281454 -38.58370236
OS 43.07004086 -38.58555148
OS 43.06726718 -38.58924972
OS 43.06264438 -38.59387252
OS 43.05802158 -38.60034444
OS 43.05339878 -38.60774092
OS 43.04877598 -38.61606196
OS 43.04507774 -38.62623212
OS 43.04415318 -38.62808124
OS 43.04322862 -38.6336286
OS 43.0413795 -38.64194964
OS 43.03860582 -38.65304436
OS 43.03583214 -38.66691276
OS 43.03398302 -38.68263028
OS 43.03305846 -38.69927236
OS 43.0321339 -38.71776356
OS 43.0321339 -38.95999828
OS 42.9535463 -38.95999828
OS 42.9535463 -38.49586916
OS 43.02473742 -38.49586916
OS 43.02473742 -38.56613572
OS 43.02566198 -38.56521116
OS 43.02936022 -38.55873924
OS 43.03398302 -38.5504182
OS 43.0413795 -38.54024804
OS 43.04877598 -38.53007788
OS 43.05709702 -38.51898316
OS 43.06541806 -38.50973756
OS 43.0737391 -38.50234108
OS 43.07466366 -38.50141652
OS 43.07743734 -38.4995674
OS 43.0829847 -38.49679372
OS 43.08853206 -38.49402004
OS 43.09592854 -38.49124636
OS 43.10517414 -38.48847268
OS 43.11441974 -38.48662356
OS 43.1245899 -38.485699
OS 43.13106182 -38.485699
OS 43.13938286 -38.48662356
OE
OB 43.95022198 -38.95999828 I
OS 43.87533262 -38.95999828
OS 43.70059078 -38.49586916
OS 43.78380118 -38.49586916
OS 43.88365366 -38.77416172
OS 43.88365366 -38.77508628
OS 43.88457822 -38.77601084
OS 43.88550278 -38.77878452
OS 43.88642734 -38.7815582
OS 43.88920102 -38.7908038
OS 43.89289926 -38.80282308
OS 43.89752206 -38.81669148
OS 43.90306942 -38.832409
OS 43.90769222 -38.84997564
OS 43.91323958 -38.86754228
OS 43.91416414 -38.86569316
OS 43.9150887 -38.86107036
OS 43.91786238 -38.85367388
OS 43.92063606 -38.84257916
OS 43.92525886 -38.83055988
OS 43.92988166 -38.81484236
OS 43.93635358 -38.79820028
OS 43.9428255 -38.77970908
OS 44.04545166 -38.49586916
OS 44.12681294 -38.49586916
OS 43.95022198 -38.95999828
OE
OB 44.2756671 -38.40988508 I
OS 44.1970795 -38.40988508
OS 44.1970795 -38.32020276
OS 44.2756671 -38.32020276
OS 44.2756671 -38.40988508
OE
OB 44.5669035 -38.48662356 I
OS 44.5807719 -38.48754812
OS 44.59556486 -38.48939724
OS 44.61128238 -38.49309548
OS 44.62792446 -38.49679372
OS 44.64364198 -38.50234108
OS 44.64456654 -38.50234108
OS 44.6454911 -38.50326564
OS 44.6501139 -38.50511476
OS 44.65751038 -38.508813
OS 44.66675598 -38.5134358
OS 44.67692614 -38.51990772
OS 44.6870963 -38.5273042
OS 44.6963419 -38.53562524
OS 44.70466294 -38.54487084
OS 44.7055875 -38.5457954
OS 44.70743662 -38.54949364
OS 44.71113486 -38.55596556
OS 44.71575766 -38.56336204
OS 44.72038046 -38.57445676
OS 44.72500326 -38.58647604
OS 44.7287015 -38.60034444
OS 44.73239974 -38.61606196
OS 44.65566126 -38.62623212
OS 44.65566126 -38.624383
OS 44.6547367 -38.62068476
OS 44.65288758 -38.61421284
OS 44.6501139 -38.6058918
OS 44.6454911 -38.59757076
OS 44.63994374 -38.58832516
OS 44.63347182 -38.57907956
OS 44.62422622 -38.57075852
OS 44.62330166 -38.56983396
OS 44.61960342 -38.56798484
OS 44.61405606 -38.5642866
OS 44.60573502 -38.56058836
OS 44.59648942 -38.55689012
OS 44.58447014 -38.55319188
OS 44.56967718 -38.55134276
OS 44.55395966 -38.5504182
OS 44.54471406 -38.5504182
OS 44.53546846 -38.55134276
OS 44.52344918 -38.55226732
OS 44.5114299 -38.555041
OS 44.49848606 -38.55781468
OS 44.48646678 -38.56243748
OS 44.47629662 -38.5689094
OS 44.47537206 -38.56983396
OS 44.47259838 -38.57168308
OS 44.46890014 -38.57538132
OS 44.4652019 -38.58092868
OS 44.4605791 -38.58647604
OS 44.45688086 -38.59387252
OS 44.45410718 -38.60219356
OS 44.45318262 -38.6105146
OS 44.45318262 -38.61143916
OS 44.45318262 -38.61328828
OS 44.45410718 -38.61606196
OS 44.45410718 -38.6197602
OS 44.45688086 -38.6290058
OS 44.46242822 -38.6382514
OS 44.46335278 -38.63917596
OS 44.46427734 -38.64010052
OS 44.46612646 -38.6428742
OS 44.4698247 -38.64564788
OS 44.47352294 -38.64842156
OS 44.4790703 -38.6521198
OS 44.48554222 -38.65489348
OS 44.4929387 -38.65859172
OS 44.49386326 -38.65859172
OS 44.49571238 -38.65951628
OS 44.49941062 -38.66044084
OS 44.50588254 -38.66321452
OS 44.51512814 -38.6659882
OS 44.52714742 -38.66876188
OS 44.5345439 -38.67153556
OS 44.54286494 -38.67338468
OS 44.55211054 -38.67615836
OS 44.5622807 -38.67893204
OS 44.56320526 -38.67893204
OS 44.56597894 -38.6798566
OS 44.57060174 -38.68078116
OS 44.5761491 -38.68263028
OS 44.58262102 -38.6844794
OS 44.59094206 -38.68632852
OS 44.6085087 -38.69187588
OS 44.62792446 -38.69742324
OS 44.64734022 -38.70389516
OS 44.66490686 -38.71036708
OS 44.67230334 -38.71314076
OS 44.67877526 -38.71591444
OS 44.68062438 -38.716839
OS 44.68432262 -38.71868812
OS 44.68986998 -38.7214618
OS 44.69819102 -38.7260846
OS 44.70651206 -38.73163196
OS 44.7148331 -38.73902844
OS 44.72315414 -38.74734948
OS 44.73055062 -38.75659508
OS 44.73147518 -38.75751964
OS 44.7333243 -38.76121788
OS 44.73702254 -38.76676524
OS 44.74072078 -38.77508628
OS 44.74349446 -38.78525644
OS 44.7471927 -38.79635116
OS 44.74904182 -38.809295
OS 44.74996638 -38.82408796
OS 44.74996638 -38.82593708
OS 44.74996638 -38.83055988
OS 44.74904182 -38.83795636
OS 44.7471927 -38.84812652
OS 44.74441902 -38.85922124
OS 44.73979622 -38.87124052
OS 44.73424886 -38.88510892
OS 44.72685238 -38.89805276
OS 44.72592782 -38.89990188
OS 44.72222958 -38.90360012
OS 44.71760678 -38.91007204
OS 44.7102103 -38.91746852
OS 44.70004014 -38.92578956
OS 44.68894542 -38.93503516
OS 44.67600158 -38.9433562
OS 44.66028406 -38.95167724
OS 44.6593595 -38.95167724
OS 44.65843494 -38.9526018
OS 44.65288758 -38.95445092
OS 44.64364198 -38.9572246
OS 44.6316227 -38.96092284
OS 44.61682974 -38.96462108
OS 44.60018766 -38.96739476
OS 44.58262102 -38.96924388
OS 44.5622807 -38.97016844
OS 44.55395966 -38.97016844
OS 44.54748774 -38.96924388
OS 44.54009126 -38.96924388
OS 44.53084566 -38.96831932
OS 44.52160006 -38.96739476
OS 44.5114299 -38.96554564
OS 44.48924046 -38.96092284
OS 44.46612646 -38.95445092
OS 44.44393702 -38.94520532
OS 44.43376686 -38.93965796
OS 44.42452126 -38.93318604
OS 44.4235967 -38.93226148
OS 44.42267214 -38.93133692
OS 44.41712478 -38.92578956
OS 44.40880374 -38.91746852
OS 44.39955814 -38.90452468
OS 44.38938798 -38.88880716
OS 44.37921782 -38.87031596
OS 44.37089678 -38.84720196
OS 44.36442486 -38.82131428
OS 44.4420879 -38.809295
OS 44.4420879 -38.81021956
OS 44.4420879 -38.81114412
OS 44.44393702 -38.81669148
OS 44.44578614 -38.82593708
OS 44.44948438 -38.83610724
OS 44.45410718 -38.84720196
OS 44.45965454 -38.85922124
OS 44.46797558 -38.87124052
OS 44.47814574 -38.88141068
OS 44.47999486 -38.88233524
OS 44.4836931 -38.88510892
OS 44.49108958 -38.88880716
OS 44.50033518 -38.89342996
OS 44.51235446 -38.89805276
OS 44.52622286 -38.901751
OS 44.54286494 -38.90452468
OS 44.5622807 -38.90544924
OS 44.5715263 -38.90544924
OS 44.5807719 -38.90452468
OS 44.59279118 -38.90267556
OS 44.60573502 -38.89990188
OS 44.61960342 -38.89620364
OS 44.6316227 -38.89158084
OS 44.64271742 -38.88418436
OS 44.64364198 -38.8832598
OS 44.64734022 -38.88048612
OS 44.65103846 -38.87586332
OS 44.65658582 -38.8693914
OS 44.66120862 -38.86199492
OS 44.66583142 -38.85274932
OS 44.6686051 -38.84350372
OS 44.66952966 -38.832409
OS 44.66952966 -38.83148444
OS 44.66952966 -38.8277862
OS 44.6686051 -38.8231634
OS 44.66675598 -38.81669148
OS 44.6639823 -38.81021956
OS 44.6593595 -38.80374764
OS 44.65381214 -38.79635116
OS 44.6454911 -38.7908038
OS 44.64456654 -38.78987924
OS 44.64179286 -38.78895468
OS 44.63717006 -38.786181
OS 44.62977358 -38.78340732
OS 44.61867886 -38.77970908
OS 44.61220694 -38.7769354
OS 44.60481046 -38.77508628
OS 44.59648942 -38.7723126
OS 44.58724382 -38.76953892
OS 44.57707366 -38.76676524
OS 44.56505438 -38.76399156
OS 44.56412982 -38.76399156
OS 44.56135614 -38.763067
OS 44.55673334 -38.76214244
OS 44.55118598 -38.76029332
OS 44.5437895 -38.7584442
OS 44.53546846 -38.75567052
OS 44.51790182 -38.75104772
OS 44.4975615 -38.7445758
OS 44.47814574 -38.73902844
OS 44.45965454 -38.73255652
OS 44.4513335 -38.72885828
OS 44.44486158 -38.7260846
OS 44.44301246 -38.72516004
OS 44.43931422 -38.72331092
OS 44.43376686 -38.71961268
OS 44.42637038 -38.71498988
OS 44.41804934 -38.70851796
OS 44.4097283 -38.70112148
OS 44.40140726 -38.69280044
OS 44.39401078 -38.68263028
OS 44.39308622 -38.68170572
OS 44.3912371 -38.67800748
OS 44.38846342 -38.67153556
OS 44.38568974 -38.66413908
OS 44.38291606 -38.65489348
OS 44.38014238 -38.64379876
OS 44.37829326 -38.63270404
OS 44.3773687 -38.6197602
OS 44.3773687 -38.61791108
OS 44.3773687 -38.61421284
OS 44.37829326 -38.60866548
OS 44.37921782 -38.60034444
OS 44.38106694 -38.5920234
OS 44.38291606 -38.58185324
OS 44.3866143 -38.57260764
OS 44.3912371 -38.56243748
OS 44.39216166 -38.56151292
OS 44.39401078 -38.55781468
OS 44.39678446 -38.55319188
OS 44.40140726 -38.54671996
OS 44.40695462 -38.54024804
OS 44.41342654 -38.531927
OS 44.42082302 -38.52453052
OS 44.43006862 -38.5180586
OS 44.43099318 -38.51713404
OS 44.43376686 -38.51620948
OS 44.4374651 -38.5134358
OS 44.44301246 -38.51066212
OS 44.45040894 -38.50696388
OS 44.45872998 -38.50326564
OS 44.46890014 -38.4995674
OS 44.47999486 -38.49586916
OS 44.48184398 -38.4949446
OS 44.48554222 -38.49402004
OS 44.49201414 -38.49217092
OS 44.50033518 -38.4903218
OS 44.51050534 -38.48847268
OS 44.52160006 -38.48754812
OS 44.5345439 -38.485699
OS 44.55673334 -38.485699
OS 44.5669035 -38.48662356
OE
OB 33.15968222 -38.32112732 I
OS 33.17539974 -38.32205188
OS 33.19204182 -38.32297644
OS 33.20775934 -38.32482556
OS 33.22162774 -38.32667468
OS 33.22347686 -38.32667468
OS 33.22994878 -38.3285238
OS 33.23826982 -38.33037292
OS 33.24936454 -38.3331466
OS 33.26138382 -38.3377694
OS 33.27432766 -38.34331676
OS 33.28819606 -38.34978868
OS 33.30021534 -38.35718516
OS 33.30206446 -38.35810972
OS 33.3057627 -38.3608834
OS 33.31131006 -38.36643076
OS 33.31870654 -38.37290268
OS 33.32702758 -38.38122372
OS 33.33534862 -38.39231844
OS 33.34459422 -38.40433772
OS 33.3519907 -38.41820612
OS 33.35291526 -38.42005524
OS 33.35476438 -38.42467804
OS 33.35846262 -38.43299908
OS 33.36216086 -38.4440938
OS 33.36493454 -38.45703764
OS 33.36863278 -38.4718306
OS 33.3704819 -38.48847268
OS 33.37140646 -38.50603932
OS 33.37140646 -38.50696388
OS 33.37140646 -38.50973756
OS 33.37140646 -38.5134358
OS 33.3704819 -38.51990772
OS 33.36955734 -38.52637964
OS 33.36863278 -38.53470068
OS 33.36678366 -38.54394628
OS 33.36493454 -38.55411644
OS 33.35846262 -38.57538132
OS 33.35476438 -38.58647604
OS 33.34921702 -38.59849532
OS 33.3427451 -38.6105146
OS 33.33627318 -38.62160932
OS 33.32795214 -38.63270404
OS 33.31870654 -38.64379876
OS 33.31778198 -38.64472332
OS 33.31593286 -38.64657244
OS 33.31315918 -38.64934612
OS 33.30853638 -38.6521198
OS 33.30298902 -38.6567426
OS 33.29559254 -38.6613654
OS 33.28634694 -38.66691276
OS 33.27617678 -38.67153556
OS 33.2641575 -38.67708292
OS 33.2502891 -38.68263028
OS 33.23549614 -38.68725308
OS 33.2179295 -38.69095132
OS 33.1994383 -38.69464956
OS 33.17909798 -38.69742324
OS 33.15598398 -38.69927236
OS 33.13194542 -38.70019692
OS 32.9682983 -38.70019692
OS 32.9682983 -38.95999828
OS 32.88323878 -38.95999828
OS 32.88323878 -38.32020276
OS 33.14581382 -38.32020276
OS 33.15968222 -38.32112732
OE
OB 32.75195126 -38.98403684 I
OS 32.75195126 -38.9849614
OS 32.75195126 -38.98773508
OS 32.75195126 -38.99235788
OS 32.75195126 -38.99790524
OS 32.7510267 -39.00530172
OS 32.7510267 -39.0126982
OS 32.74917758 -39.0311894
OS 32.7464039 -39.05060516
OS 32.74270566 -39.07094548
OS 32.7371583 -39.08851212
OS 32.73346006 -39.09683316
OS 32.72976182 -39.10330508
OS 32.72976182 -39.10422964
OS 32.72883726 -39.1051542
OS 32.72421446 -39.109777
OS 32.71681798 -39.11717348
OS 32.70757238 -39.12549452
OS 32.69462854 -39.13381556
OS 32.67798646 -39.14028748
OS 32.6585707 -39.14583484
OS 32.64747598 -39.1467594
OS 32.6354567 -39.14768396
OS 32.62990934 -39.14768396
OS 32.62436198 -39.1467594
OS 32.61604094 -39.1467594
OS 32.60679534 -39.14583484
OS 32.59662518 -39.14398572
OS 32.57443574 -39.13843836
OS 32.5892287 -39.07187004
OS 32.59015326 -39.07187004
OS 32.59292694 -39.0727946
OS 32.59754974 -39.07371916
OS 32.60217254 -39.07464372
OS 32.61419182 -39.0774174
OS 32.61973918 -39.07834196
OS 32.62898478 -39.07834196
OS 32.63360758 -39.0774174
OS 32.63915494 -39.07649284
OS 32.6447023 -39.07464372
OS 32.65024966 -39.07094548
OS 32.65672158 -39.06724724
OS 32.66134438 -39.06169988
OS 32.66226894 -39.06077532
OS 32.6631935 -39.05800164
OS 32.66504262 -39.05337884
OS 32.6678163 -39.04598236
OS 32.66966542 -39.0358122
OS 32.67058998 -39.02841572
OS 32.67151454 -39.0219438
OS 32.6724391 -39.01362276
OS 32.6724391 -39.0034526
OS 32.67336366 -38.99328244
OS 32.67336366 -38.98218772
OS 32.67336366 -38.49586916
OS 32.75195126 -38.49586916
OS 32.75195126 -38.98403684
OE
OB 33.77174094 -38.3100326 I
OS 33.78006198 -38.31095716
OS 33.79023214 -38.31188172
OS 33.8004023 -38.31280628
OS 33.81242158 -38.31557996
OS 33.8373847 -38.32112732
OS 33.8651215 -38.32944836
OS 33.8789899 -38.33499572
OS 33.89193374 -38.34146764
OS 33.90487758 -38.34978868
OS 33.91782142 -38.35810972
OS 33.91874598 -38.35903428
OS 33.9205951 -38.35995884
OS 33.92429334 -38.36273252
OS 33.92891614 -38.36735532
OS 33.93353894 -38.37197812
OS 33.94001086 -38.37845004
OS 33.94648278 -38.38584652
OS 33.95387926 -38.393243
OS 33.96127574 -38.4024886
OS 33.96867222 -38.41358332
OS 33.97699326 -38.42467804
OS 33.98438974 -38.43669732
OS 33.99086166 -38.45056572
OS 33.99825814 -38.46443412
OS 34.0038055 -38.47922708
OS 34.00935286 -38.49586916
OS 33.92614246 -38.51528492
OS 33.92614246 -38.51436036
OS 33.9252179 -38.51251124
OS 33.92336878 -38.508813
OS 33.92151966 -38.5041902
OS 33.91967054 -38.49864284
OS 33.91689686 -38.49124636
OS 33.90950038 -38.4764534
OS 33.90025478 -38.45981132
OS 33.88916006 -38.44316924
OS 33.87529166 -38.42745172
OS 33.8604987 -38.41358332
OS 33.85864958 -38.4117342
OS 33.85310222 -38.40803596
OS 33.84385662 -38.40341316
OS 33.83183734 -38.39694124
OS 33.81611982 -38.39139388
OS 33.79855318 -38.38584652
OS 33.7772883 -38.38214828
OS 33.7541743 -38.38122372
OS 33.74677782 -38.38122372
OS 33.74215502 -38.38214828
OS 33.7356831 -38.38214828
OS 33.72828662 -38.38307284
OS 33.71071998 -38.38584652
OS 33.69130422 -38.38954476
OS 33.6709639 -38.39601668
OS 33.64969902 -38.40526228
OS 33.63028326 -38.41728156
OS 33.6293587 -38.41728156
OS 33.62843414 -38.41913068
OS 33.62196222 -38.42375348
OS 33.61364118 -38.43114996
OS 33.60347102 -38.44224468
OS 33.59145174 -38.45611308
OS 33.58035702 -38.4718306
OS 33.57018686 -38.49124636
OS 33.56094126 -38.51251124
OS 33.56094126 -38.5134358
OS 33.5600167 -38.51528492
OS 33.55909214 -38.5180586
OS 33.55816758 -38.5226814
OS 33.55631846 -38.52822876
OS 33.55446934 -38.53470068
OS 33.55169566 -38.5504182
OS 33.54799742 -38.5689094
OS 33.54429918 -38.58924972
OS 33.54245006 -38.61143916
OS 33.5415255 -38.63547772
OS 33.5415255 -38.63640228
OS 33.5415255 -38.63917596
OS 33.5415255 -38.64379876
OS 33.5415255 -38.64934612
OS 33.54245006 -38.65581804
OS 33.54245006 -38.66413908
OS 33.54337462 -38.67338468
OS 33.54429918 -38.68355484
OS 33.54707286 -38.70574428
OS 33.55169566 -38.72978284
OS 33.55724302 -38.7538214
OS 33.5646395 -38.77785996
OS 33.5646395 -38.77878452
OS 33.56556406 -38.78063364
OS 33.56741318 -38.78340732
OS 33.5692623 -38.78803012
OS 33.57480966 -38.79912484
OS 33.5831307 -38.81206868
OS 33.59330086 -38.82686164
OS 33.6062447 -38.84257916
OS 33.62103766 -38.85644756
OS 33.6386043 -38.8693914
OS 33.63952886 -38.8693914
OS 33.64137798 -38.87031596
OS 33.64415166 -38.87216508
OS 33.6478499 -38.8740142
OS 33.6524727 -38.87586332
OS 33.65802006 -38.878637
OS 33.6709639 -38.88418436
OS 33.68760598 -38.88973172
OS 33.70609718 -38.89435452
OS 33.7264375 -38.89805276
OS 33.74770238 -38.89897732
OS 33.7541743 -38.89897732
OS 33.75972166 -38.89805276
OS 33.76619358 -38.89805276
OS 33.7726655 -38.8971282
OS 33.78930758 -38.89342996
OS 33.80872334 -38.88880716
OS 33.8281391 -38.88141068
OS 33.84847942 -38.87124052
OS 33.85864958 -38.86569316
OS 33.86789518 -38.85829668
OS 33.86881974 -38.85737212
OS 33.8697443 -38.85644756
OS 33.87251798 -38.85367388
OS 33.87621622 -38.8509002
OS 33.87991446 -38.8462774
OS 33.88453726 -38.84073004
OS 33.89008462 -38.83518268
OS 33.89470742 -38.8277862
OS 33.90025478 -38.81946516
OS 33.9067267 -38.81021956
OS 33.91227406 -38.80097396
OS 33.91782142 -38.78987924
OS 33.92244422 -38.77785996
OS 33.92706702 -38.76491612
OS 33.93168982 -38.75104772
OS 33.93538806 -38.73625476
OS 34.02044758 -38.75751964
OS 34.02044758 -38.7584442
OS 34.01952302 -38.76214244
OS 34.0176739 -38.7676898
OS 34.01490022 -38.77508628
OS 34.01212654 -38.78340732
OS 34.0084283 -38.79357748
OS 34.0038055 -38.8046722
OS 33.99825814 -38.81669148
OS 33.9853143 -38.84257916
OS 33.96867222 -38.86846684
OS 33.95850206 -38.88141068
OS 33.9483319 -38.89435452
OS 33.93723718 -38.90544924
OS 33.92429334 -38.91654396
OS 33.92336878 -38.91746852
OS 33.92151966 -38.91931764
OS 33.91689686 -38.92116676
OS 33.91227406 -38.924865
OS 33.90487758 -38.9294878
OS 33.8974811 -38.9341106
OS 33.88731094 -38.9387334
OS 33.87714078 -38.9433562
OS 33.8651215 -38.94890356
OS 33.85217766 -38.95352636
OS 33.83830926 -38.95814916
OS 33.8235163 -38.96277196
OS 33.80779878 -38.9664702
OS 33.7911567 -38.96831932
OS 33.77359006 -38.97016844
OS 33.75509886 -38.971093
OS 33.7449287 -38.971093
OS 33.73753222 -38.97016844
OS 33.72921118 -38.97016844
OS 33.71904102 -38.96924388
OS 33.7079463 -38.96739476
OS 33.69500246 -38.96554564
OS 33.66819022 -38.96092284
OS 33.64045342 -38.95352636
OS 33.61271662 -38.9433562
OS 33.59977278 -38.93688428
OS 33.58682894 -38.9294878
OS 33.58590438 -38.92856324
OS 33.58405526 -38.92763868
OS 33.58035702 -38.924865
OS 33.57665878 -38.92116676
OS 33.57111142 -38.91746852
OS 33.5646395 -38.91192116
OS 33.55724302 -38.90544924
OS 33.54984654 -38.89805276
OS 33.54245006 -38.88973172
OS 33.53412902 -38.88141068
OS 33.51748694 -38.8601458
OS 33.50176942 -38.83518268
OS 33.48790102 -38.80744588
OS 33.48790102 -38.80652132
OS 33.4860519 -38.80374764
OS 33.48512734 -38.79912484
OS 33.48235366 -38.79357748
OS 33.48050454 -38.786181
OS 33.47773086 -38.7769354
OS 33.47403262 -38.76676524
OS 33.47125894 -38.75567052
OS 33.46848526 -38.74365124
OS 33.46478702 -38.72978284
OS 33.46016422 -38.70112148
OS 33.45646598 -38.66876188
OS 33.45461686 -38.63547772
OS 33.45461686 -38.63455316
OS 33.45461686 -38.63085492
OS 33.45461686 -38.62530756
OS 33.45554142 -38.61883564
OS 33.45554142 -38.60959004
OS 33.45646598 -38.60034444
OS 33.45739054 -38.58832516
OS 33.45923966 -38.57630588
OS 33.46386246 -38.54949364
OS 33.47033438 -38.51990772
OS 33.47957998 -38.4903218
OS 33.49252382 -38.46166044
OS 33.49344838 -38.46073588
OS 33.49437294 -38.4579622
OS 33.49622206 -38.45426396
OS 33.4999203 -38.44964116
OS 33.50361854 -38.44316924
OS 33.50824134 -38.43577276
OS 33.52026062 -38.41913068
OS 33.53597814 -38.40063948
OS 33.55446934 -38.38214828
OS 33.57573422 -38.36365708
OS 33.60069734 -38.34793956
OS 33.6016219 -38.347015
OS 33.60439558 -38.34609044
OS 33.60809382 -38.34424132
OS 33.61271662 -38.34146764
OS 33.6201131 -38.33869396
OS 33.62750958 -38.33592028
OS 33.63675518 -38.33222204
OS 33.64692534 -38.3285238
OS 33.65802006 -38.32482556
OS 33.67003934 -38.32112732
OS 33.69592702 -38.31557996
OS 33.72551294 -38.31095716
OS 33.75602342 -38.30910804
OS 33.76526902 -38.30910804
OS 33.77174094 -38.3100326
OE
OB 35.15858094 -39.1375138 I
OS 34.63805366 -39.1375138
OS 34.63805366 -39.08111564
OS 35.15858094 -39.08111564
OS 35.15858094 -39.1375138
OE
OB 34.37917686 -38.32112732 I
OS 34.38657334 -38.32112732
OS 34.40321542 -38.32297644
OS 34.42170662 -38.32482556
OS 34.44112238 -38.3285238
OS 34.46053814 -38.3331466
OS 34.47810478 -38.33961852
OS 34.47902934 -38.33961852
OS 34.4799539 -38.34054308
OS 34.48550126 -38.34331676
OS 34.4938223 -38.34793956
OS 34.5030679 -38.35441148
OS 34.51416262 -38.36273252
OS 34.5261819 -38.37290268
OS 34.53727662 -38.38584652
OS 34.54744678 -38.39971492
OS 34.54837134 -38.40156404
OS 34.55114502 -38.4071114
OS 34.55576782 -38.41450788
OS 34.56039062 -38.4256026
OS 34.56501342 -38.43854644
OS 34.56963622 -38.45241484
OS 34.5724099 -38.46813236
OS 34.57333446 -38.48384988
OS 34.57333446 -38.485699
OS 34.57333446 -38.4903218
OS 34.5724099 -38.49864284
OS 34.57056078 -38.508813
OS 34.5677871 -38.52083228
OS 34.5631643 -38.53377612
OS 34.55761694 -38.54671996
OS 34.55022046 -38.56058836
OS 34.5492959 -38.56243748
OS 34.54652222 -38.56613572
OS 34.54097486 -38.5735322
OS 34.53357838 -38.58092868
OS 34.52433278 -38.59017428
OS 34.51323806 -38.60034444
OS 34.49936966 -38.60959004
OS 34.48365214 -38.61883564
OS 34.4845767 -38.61883564
OS 34.48642582 -38.6197602
OS 34.4891995 -38.62068476
OS 34.49289774 -38.62253388
OS 34.50399246 -38.62623212
OS 34.5169363 -38.63270404
OS 34.5308047 -38.64102508
OS 34.54652222 -38.65119524
OS 34.56039062 -38.66321452
OS 34.57333446 -38.67800748
OS 34.57425902 -38.6798566
OS 34.57795726 -38.68540396
OS 34.58350462 -38.693725
OS 34.58905198 -38.70481972
OS 34.59459934 -38.71961268
OS 34.6001467 -38.7353302
OS 34.60384494 -38.7538214
OS 34.6047695 -38.77416172
OS 34.6047695 -38.77508628
OS 34.6047695 -38.77601084
OS 34.6047695 -38.7815582
OS 34.60384494 -38.7908038
OS 34.60199582 -38.80189852
OS 34.6001467 -38.81484236
OS 34.59644846 -38.82871076
OS 34.59182566 -38.84350372
OS 34.58535374 -38.85829668
OS 34.58442918 -38.8601458
OS 34.5816555 -38.8647686
OS 34.57795726 -38.87124052
OS 34.5724099 -38.88048612
OS 34.56501342 -38.88973172
OS 34.55761694 -38.89990188
OS 34.54837134 -38.91007204
OS 34.53820118 -38.91839308
OS 34.53727662 -38.91931764
OS 34.53357838 -38.92209132
OS 34.52710646 -38.92578956
OS 34.51878542 -38.9294878
OS 34.50861526 -38.93503516
OS 34.49659598 -38.94058252
OS 34.48365214 -38.94520532
OS 34.46793462 -38.94982812
OS 34.4660855 -38.94982812
OS 34.46053814 -38.95167724
OS 34.45129254 -38.9526018
OS 34.43927326 -38.95445092
OS 34.4244803 -38.95630004
OS 34.40691366 -38.95814916
OS 34.3874979 -38.95907372
OS 34.36530846 -38.95999828
OS 34.12122462 -38.95999828
OS 34.12122462 -38.32020276
OS 34.37270494 -38.32020276
OS 34.37917686 -38.32112732
OE
OB 31.74233174 -38.95999828 I
OS 31.65264942 -38.95999828
OS 31.65264942 -38.87031596
OS 31.74233174 -38.87031596
OS 31.74233174 -38.95999828
OE
OB 31.52968294 -38.42745172 I
OS 31.50841806 -38.54671996
OS 31.45941638 -38.54671996
OS 31.44000062 -38.42745172
OS 31.44000062 -38.32020276
OS 31.52968294 -38.32020276
OS 31.52968294 -38.42745172
OE
OB 32.0992119 -38.48662356 I
OS 32.10568382 -38.48754812
OS 32.11955222 -38.48939724
OS 32.1361943 -38.49309548
OS 32.15376094 -38.49864284
OS 32.17132758 -38.50696388
OS 32.18889422 -38.51713404
OS 32.18981878 -38.51713404
OS 32.19074334 -38.51898316
OS 32.1962907 -38.5226814
OS 32.20461174 -38.53007788
OS 32.2147819 -38.53932348
OS 32.22587662 -38.55134276
OS 32.23697134 -38.56613572
OS 32.24806606 -38.58370236
OS 32.25731166 -38.60311812
OS 32.25731166 -38.60404268
OS 32.25823622 -38.6058918
OS 32.25916078 -38.60866548
OS 32.2610099 -38.61236372
OS 32.26285902 -38.61791108
OS 32.26470814 -38.624383
OS 32.26933094 -38.63917596
OS 32.27395374 -38.65766716
OS 32.27765198 -38.67800748
OS 32.28042566 -38.70112148
OS 32.28135022 -38.72516004
OS 32.28135022 -38.7260846
OS 32.28135022 -38.72793372
OS 32.28135022 -38.73163196
OS 32.28135022 -38.73717932
OS 32.28042566 -38.74365124
OS 32.28042566 -38.75104772
OS 32.27857654 -38.7676898
OS 32.2748783 -38.78803012
OS 32.2702555 -38.809295
OS 32.26378358 -38.83148444
OS 32.25546254 -38.85367388
OS 32.25546254 -38.85459844
OS 32.25453798 -38.85644756
OS 32.25268886 -38.85922124
OS 32.25083974 -38.86291948
OS 32.24436782 -38.87308964
OS 32.23604678 -38.88603348
OS 32.22587662 -38.89990188
OS 32.21293278 -38.91377028
OS 32.19813982 -38.92763868
OS 32.18057318 -38.94058252
OS 32.17964862 -38.94058252
OS 32.17872406 -38.94150708
OS 32.17595038 -38.9433562
OS 32.17225214 -38.94520532
OS 32.16300654 -38.94982812
OS 32.1500627 -38.95537548
OS 32.13434518 -38.96092284
OS 32.1177031 -38.96554564
OS 32.09828734 -38.96924388
OS 32.07887158 -38.97016844
OS 32.07239966 -38.97016844
OS 32.06500318 -38.96924388
OS 32.05575758 -38.96831932
OS 32.04466286 -38.9664702
OS 32.03264358 -38.96369652
OS 32.0206243 -38.95999828
OS 32.00860502 -38.95445092
OS 32.00768046 -38.95352636
OS 32.00305766 -38.95167724
OS 31.9975103 -38.947979
OS 31.99011382 -38.94243164
OS 31.98271734 -38.93688428
OS 31.97347174 -38.9294878
OS 31.9651507 -38.92116676
OS 31.95775422 -38.91192116
OS 31.95775422 -39.1375138
OS 31.87916662 -39.1375138
OS 31.87916662 -38.49586916
OS 31.95035774 -38.49586916
OS 31.95035774 -38.55689012
OS 31.9512823 -38.555041
OS 31.95498054 -38.55134276
OS 31.95960334 -38.54487084
OS 31.96699982 -38.53747436
OS 31.97532086 -38.52822876
OS 31.98456646 -38.51990772
OS 31.99566118 -38.51158668
OS 32.0067559 -38.5041902
OS 32.00860502 -38.50326564
OS 32.01230326 -38.50141652
OS 32.01969974 -38.49864284
OS 32.02894534 -38.4949446
OS 32.04004006 -38.49124636
OS 32.0529839 -38.48847268
OS 32.06777686 -38.48662356
OS 32.08441894 -38.485699
OS 32.0945891 -38.485699
OS 32.0992119 -38.48662356
OE
OB 32.5614919 -38.48662356 I
OS 32.57166206 -38.48847268
OS 32.58368134 -38.49217092
OS 32.59662518 -38.49679372
OS 32.61141814 -38.50326564
OS 32.62713566 -38.51158668
OS 32.5984743 -38.58370236
OS 32.59754974 -38.5827778
OS 32.5938515 -38.58092868
OS 32.58830414 -38.578155
OS 32.58090766 -38.57538132
OS 32.57258662 -38.57260764
OS 32.56241646 -38.56983396
OS 32.5522463 -38.56798484
OS 32.54207614 -38.56706028
OS 32.53745334 -38.56706028
OS 32.53283054 -38.56798484
OS 32.52635862 -38.5689094
OS 32.5198867 -38.57075852
OS 32.51156566 -38.5735322
OS 32.50324462 -38.57723044
OS 32.49584814 -38.5827778
OS 32.49492358 -38.58370236
OS 32.4921499 -38.58555148
OS 32.48937622 -38.58924972
OS 32.48475342 -38.59387252
OS 32.48013062 -38.60034444
OS 32.47550782 -38.60774092
OS 32.47088502 -38.61606196
OS 32.46718678 -38.62623212
OS 32.46626222 -38.62808124
OS 32.46533766 -38.6336286
OS 32.46348854 -38.64194964
OS 32.46071486 -38.65304436
OS 32.45794118 -38.66691276
OS 32.45609206 -38.68263028
OS 32.4551675 -38.69927236
OS 32.45424294 -38.71776356
OS 32.45424294 -38.95999828
OS 32.37565534 -38.95999828
OS 32.37565534 -38.49586916
OS 32.44684646 -38.49586916
OS 32.44684646 -38.56613572
OS 32.44777102 -38.56521116
OS 32.45146926 -38.55873924
OS 32.45609206 -38.5504182
OS 32.46348854 -38.54024804
OS 32.47088502 -38.53007788
OS 32.47920606 -38.51898316
OS 32.4875271 -38.50973756
OS 32.49584814 -38.50234108
OS 32.4967727 -38.50141652
OS 32.49954638 -38.4995674
OS 32.50509374 -38.49679372
OS 32.5106411 -38.49402004
OS 32.51803758 -38.49124636
OS 32.52728318 -38.48847268
OS 32.53652878 -38.48662356
OS 32.54669894 -38.485699
OS 32.55317086 -38.485699
OS 32.5614919 -38.48662356
OE
OB 32.75195126 -38.4117342 I
OS 32.67336366 -38.4117342
OS 32.67336366 -38.32020276
OS 32.75195126 -38.32020276
OS 32.75195126 -38.4117342
OE
OB 36.56668582 -38.95999828 I
OS 36.47885262 -38.95999828
OS 36.1441619 -38.4579622
OS 36.1441619 -38.95999828
OS 36.06280062 -38.95999828
OS 36.06280062 -38.32020276
OS 36.14970926 -38.32020276
OS 36.48532454 -38.8231634
OS 36.48532454 -38.32020276
OS 36.56668582 -38.32020276
OS 36.56668582 -38.95999828
OE
OB 35.74382742 -38.32112732 I
OS 35.75954494 -38.32205188
OS 35.77618702 -38.32297644
OS 35.79190454 -38.32482556
OS 35.80577294 -38.32667468
OS 35.80762206 -38.32667468
OS 35.81409398 -38.3285238
OS 35.82241502 -38.33037292
OS 35.83350974 -38.3331466
OS 35.84552902 -38.3377694
OS 35.85847286 -38.34331676
OS 35.87234126 -38.34978868
OS 35.88436054 -38.35718516
OS 35.88620966 -38.35810972
OS 35.8899079 -38.3608834
OS 35.89545526 -38.36643076
OS 35.90285174 -38.37290268
OS 35.91117278 -38.38122372
OS 35.91949382 -38.39231844
OS 35.92873942 -38.40433772
OS 35.9361359 -38.41820612
OS 35.93706046 -38.42005524
OS 35.93890958 -38.42467804
OS 35.94260782 -38.43299908
OS 35.94630606 -38.4440938
OS 35.94907974 -38.45703764
OS 35.95277798 -38.4718306
OS 35.9546271 -38.48847268
OS 35.95555166 -38.50603932
OS 35.95555166 -38.50696388
OS 35.95555166 -38.50973756
OS 35.95555166 -38.5134358
OS 35.9546271 -38.51990772
OS 35.95370254 -38.52637964
OS 35.95277798 -38.53470068
OS 35.95092886 -38.54394628
OS 35.94907974 -38.55411644
OS 35.94260782 -38.57538132
OS 35.93890958 -38.58647604
OS 35.93336222 -38.59849532
OS 35.9268903 -38.6105146
OS 35.92041838 -38.62160932
OS 35.91209734 -38.63270404
OS 35.90285174 -38.64379876
OS 35.90192718 -38.64472332
OS 35.90007806 -38.64657244
OS 35.89730438 -38.64934612
OS 35.89268158 -38.6521198
OS 35.88713422 -38.6567426
OS 35.87973774 -38.6613654
OS 35.87049214 -38.66691276
OS 35.86032198 -38.67153556
OS 35.8483027 -38.67708292
OS 35.8344343 -38.68263028
OS 35.81964134 -38.68725308
OS 35.8020747 -38.69095132
OS 35.7835835 -38.69464956
OS 35.76324318 -38.69742324
OS 35.74012918 -38.69927236
OS 35.71609062 -38.70019692
OS 35.5524435 -38.70019692
OS 35.5524435 -38.95999828
OS 35.46738398 -38.95999828
OS 35.46738398 -38.32020276
OS 35.72995902 -38.32020276
OS 35.74382742 -38.32112732
OE
OB 36.76916446 -38.42745172 I
OS 36.74789958 -38.54671996
OS 36.6988979 -38.54671996
OS 36.67948214 -38.42745172
OS 36.67948214 -38.32020276
OS 36.76916446 -38.32020276
OS 36.76916446 -38.42745172
OE
OB 38.2382903 -38.39601668 I
OS 37.86014526 -38.39601668
OS 37.86014526 -38.59109884
OS 38.21425174 -38.59109884
OS 38.21425174 -38.66691276
OS 37.86014526 -38.66691276
OS 37.86014526 -38.88418436
OS 38.25308326 -38.88418436
OS 38.25308326 -38.95999828
OS 37.77508574 -38.95999828
OS 37.77508574 -38.32020276
OS 38.2382903 -38.32020276
OS 38.2382903 -38.39601668
OE
OB 37.4339231 -38.32112732 I
OS 37.44224414 -38.32112732
OS 37.4616599 -38.32205188
OS 37.48200022 -38.32482556
OS 37.50418966 -38.32759924
OS 37.52452998 -38.33222204
OS 37.53470014 -38.33499572
OS 37.54302118 -38.3377694
OS 37.54394574 -38.3377694
OS 37.5448703 -38.33869396
OS 37.55041766 -38.34146764
OS 37.5587387 -38.34516588
OS 37.56890886 -38.3516378
OS 37.58000358 -38.35995884
OS 37.59202286 -38.37105356
OS 37.60311758 -38.3839974
OS 37.6142123 -38.39879036
OS 37.6142123 -38.39971492
OS 37.61513686 -38.40063948
OS 37.6188351 -38.40618684
OS 37.62253334 -38.41543244
OS 37.6280807 -38.42745172
OS 37.6327035 -38.44132012
OS 37.6373263 -38.4579622
OS 37.64009998 -38.47552884
OS 37.64102454 -38.4949446
OS 37.64102454 -38.49586916
OS 37.64102454 -38.49771828
OS 37.64102454 -38.50141652
OS 37.64009998 -38.50603932
OS 37.64009998 -38.51251124
OS 37.63917542 -38.51898316
OS 37.63547718 -38.53470068
OS 37.62992982 -38.55319188
OS 37.62253334 -38.57260764
OS 37.61143862 -38.5920234
OS 37.60404214 -38.601269
OS 37.59664566 -38.6105146
OS 37.5957211 -38.61143916
OS 37.59479654 -38.61236372
OS 37.59202286 -38.6151374
OS 37.58832462 -38.61791108
OS 37.58370182 -38.62160932
OS 37.57815446 -38.62530756
OS 37.57075798 -38.62993036
OS 37.5633615 -38.63547772
OS 37.5541159 -38.64010052
OS 37.54394574 -38.64472332
OS 37.53285102 -38.65027068
OS 37.52083174 -38.65489348
OS 37.50696334 -38.65859172
OS 37.49309494 -38.66321452
OS 37.47737742 -38.6659882
OS 37.46073534 -38.66876188
OS 37.46258446 -38.66968644
OS 37.4662827 -38.67153556
OS 37.47183006 -38.6752338
OS 37.47922654 -38.67893204
OS 37.49586862 -38.6891022
OS 37.50418966 -38.69557412
OS 37.51158614 -38.70112148
OS 37.51343526 -38.7029706
OS 37.51805806 -38.7075934
OS 37.52545454 -38.71498988
OS 37.53470014 -38.72423548
OS 37.5448703 -38.73717932
OS 37.55688958 -38.75104772
OS 37.56890886 -38.7676898
OS 37.5818527 -38.786181
OS 37.69187534 -38.95999828
OS 37.5864755 -38.95999828
OS 37.50234054 -38.82686164
OS 37.50234054 -38.82593708
OS 37.50049142 -38.82408796
OS 37.4986423 -38.82131428
OS 37.49586862 -38.81761604
OS 37.4893967 -38.80744588
OS 37.48107566 -38.79450204
OS 37.4709055 -38.78063364
OS 37.46073534 -38.76584068
OS 37.45056518 -38.75197228
OS 37.44131958 -38.73902844
OS 37.44039502 -38.73810388
OS 37.43762134 -38.73440564
OS 37.43299854 -38.72885828
OS 37.42652662 -38.72238636
OS 37.41265822 -38.70851796
OS 37.40526174 -38.70204604
OS 37.39786526 -38.69649868
OS 37.3969407 -38.69557412
OS 37.39509158 -38.69464956
OS 37.39139334 -38.69280044
OS 37.38584598 -38.69002676
OS 37.38029862 -38.68725308
OS 37.3738267 -38.6844794
OS 37.35903374 -38.6798566
OS 37.35810918 -38.6798566
OS 37.35626006 -38.67893204
OS 37.35256182 -38.67893204
OS 37.34793902 -38.67800748
OS 37.3414671 -38.67708292
OS 37.33407062 -38.67708292
OS 37.32390046 -38.67615836
OS 37.21480238 -38.67615836
OS 37.21480238 -38.95999828
OS 37.12974286 -38.95999828
OS 37.12974286 -38.32020276
OS 37.42652662 -38.32020276
OS 37.4339231 -38.32112732
OE
OB 35.31760526 -38.95999828 I
OS 35.23254574 -38.95999828
OS 35.23254574 -38.32020276
OS 35.31760526 -38.32020276
OS 35.31760526 -38.95999828
OE
OB 42.12051774 -38.66413908 H
OS 41.95224782 -38.66413908
OS 41.95224782 -38.88418436
OS 42.13438614 -38.88418436
OS 42.1538019 -38.8832598
OS 42.16212294 -38.88233524
OS 42.16951942 -38.88141068
OS 42.17044398 -38.88141068
OS 42.17414222 -38.88048612
OS 42.17968958 -38.87956156
OS 42.1861615 -38.87771244
OS 42.20187902 -38.87216508
OS 42.21759654 -38.8647686
OS 42.2185211 -38.86384404
OS 42.22129478 -38.86199492
OS 42.22499302 -38.85922124
OS 42.22961582 -38.855523
OS 42.23423862 -38.84997564
OS 42.24071054 -38.84442828
OS 42.24533334 -38.8370318
OS 42.2508807 -38.82871076
OS 42.25180526 -38.8277862
OS 42.25272982 -38.82501252
OS 42.25457894 -38.81946516
OS 42.25735262 -38.81299324
OS 42.2601263 -38.80559676
OS 42.26197542 -38.79635116
OS 42.26289998 -38.78525644
OS 42.26382454 -38.77416172
OS 42.26382454 -38.7723126
OS 42.26382454 -38.76861436
OS 42.26289998 -38.76121788
OS 42.26105086 -38.75289684
OS 42.25920174 -38.74365124
OS 42.2555035 -38.73348108
OS 42.2508807 -38.72331092
OS 42.24440878 -38.71314076
OS 42.24348422 -38.7122162
OS 42.24071054 -38.70851796
OS 42.2370123 -38.70389516
OS 42.23146494 -38.6983478
OS 42.22406846 -38.69187588
OS 42.21482286 -38.68540396
OS 42.2046527 -38.6798566
OS 42.19263342 -38.6752338
OS 42.1907843 -38.67430924
OS 42.18708606 -38.67338468
OS 42.17876502 -38.67153556
OS 42.16859486 -38.66968644
OS 42.15565102 -38.66783732
OS 42.1399335 -38.6659882
OS 42.12051774 -38.66413908
OE
OB 45.22981302 -38.5504182 H
OS 45.22426566 -38.5504182
OS 45.21964286 -38.55134276
OS 45.2094727 -38.55226732
OS 45.1956043 -38.55596556
OS 45.17988678 -38.56151292
OS 45.1632447 -38.5689094
OS 45.14752718 -38.58000412
OS 45.13920614 -38.5874006
OS 45.13180966 -38.59479708
OS 45.13180966 -38.59572164
OS 45.12996054 -38.5966462
OS 45.12811142 -38.59941988
OS 45.12533774 -38.60311812
OS 45.12256406 -38.60774092
OS 45.11979038 -38.61328828
OS 45.11609214 -38.62068476
OS 45.1123939 -38.62808124
OS 45.10869566 -38.63732684
OS 45.10499742 -38.64657244
OS 45.10222374 -38.65766716
OS 45.09945006 -38.66968644
OS 45.09667638 -38.68263028
OS 45.09482726 -38.69649868
OS 45.0939027 -38.7122162
OS 45.09297814 -38.72793372
OS 45.09297814 -38.72885828
OS 45.09297814 -38.73163196
OS 45.09297814 -38.73625476
OS 45.0939027 -38.74272668
OS 45.0939027 -38.75012316
OS 45.09482726 -38.7584442
OS 45.09760094 -38.77785996
OS 45.10222374 -38.8000494
OS 45.10962022 -38.82223884
OS 45.11886582 -38.84350372
OS 45.12533774 -38.85274932
OS 45.13180966 -38.86199492
OS 45.13273422 -38.86199492
OS 45.13365878 -38.86384404
OS 45.13920614 -38.86846684
OS 45.14752718 -38.87586332
OS 45.1586219 -38.8832598
OS 45.1724903 -38.89158084
OS 45.18913238 -38.89897732
OS 45.20854814 -38.90360012
OS 45.2187183 -38.90452468
OS 45.22981302 -38.90544924
OS 45.23536038 -38.90544924
OS 45.23998318 -38.90452468
OS 45.25015334 -38.90267556
OS 45.26402174 -38.89990188
OS 45.2788147 -38.89435452
OS 45.29545678 -38.88695804
OS 45.3111743 -38.87586332
OS 45.31949534 -38.86846684
OS 45.32689182 -38.86107036
OS 45.32781638 -38.8601458
OS 45.32874094 -38.85922124
OS 45.33059006 -38.85644756
OS 45.33336374 -38.85274932
OS 45.33613742 -38.84812652
OS 45.33983566 -38.84257916
OS 45.3435339 -38.83518268
OS 45.34723214 -38.8277862
OS 45.35093038 -38.8185406
OS 45.35370406 -38.80837044
OS 45.3574023 -38.79727572
OS 45.36017598 -38.78525644
OS 45.36294966 -38.77138804
OS 45.36479878 -38.75751964
OS 45.3666479 -38.74180212
OS 45.3666479 -38.72516004
OS 45.3666479 -38.72423548
OS 45.3666479 -38.7214618
OS 45.3666479 -38.716839
OS 45.36572334 -38.71129164
OS 45.36572334 -38.70389516
OS 45.36479878 -38.69557412
OS 45.3620251 -38.67615836
OS 45.3574023 -38.65581804
OS 45.35000582 -38.6336286
OS 45.33983566 -38.61328828
OS 45.3342883 -38.60311812
OS 45.32689182 -38.59479708
OS 45.32689182 -38.59387252
OS 45.3250427 -38.59294796
OS 45.31949534 -38.5874006
OS 45.3111743 -38.58092868
OS 45.30007958 -38.57260764
OS 45.28621118 -38.5642866
OS 45.2695691 -38.55689012
OS 45.2510779 -38.55226732
OS 45.24090774 -38.55134276
OS 45.22981302 -38.5504182
OE
OB 32.07702246 -38.54764452 H
OS 32.07239966 -38.54764452
OS 32.06870142 -38.54856908
OS 32.05945582 -38.5504182
OS 32.04743654 -38.55319188
OS 32.03356814 -38.55873924
OS 32.01877518 -38.56706028
OS 32.01045414 -38.57260764
OS 32.00305766 -38.57907956
OS 31.99566118 -38.58647604
OS 31.9882647 -38.59479708
OS 31.9882647 -38.59572164
OS 31.98641558 -38.5966462
OS 31.98456646 -38.59941988
OS 31.98271734 -38.60311812
OS 31.97994366 -38.60866548
OS 31.97624542 -38.61421284
OS 31.97254718 -38.62160932
OS 31.9697735 -38.6290058
OS 31.96607526 -38.6382514
OS 31.96237702 -38.64842156
OS 31.95960334 -38.65951628
OS 31.9559051 -38.67153556
OS 31.95405598 -38.68540396
OS 31.95220686 -38.69927236
OS 31.95035774 -38.71406532
OS 31.95035774 -38.7307074
OS 31.95035774 -38.73163196
OS 31.95035774 -38.73440564
OS 31.95035774 -38.73902844
OS 31.9512823 -38.74550036
OS 31.9512823 -38.75289684
OS 31.95220686 -38.76121788
OS 31.95498054 -38.78063364
OS 31.95960334 -38.80282308
OS 31.9651507 -38.82408796
OS 31.9743963 -38.84535284
OS 31.97994366 -38.85459844
OS 31.98641558 -38.86291948
OS 31.9882647 -38.8647686
OS 31.9928875 -38.8693914
OS 32.00028398 -38.87678788
OS 32.01045414 -38.88418436
OS 32.02339798 -38.89158084
OS 32.03819094 -38.89897732
OS 32.05483302 -38.90360012
OS 32.06407862 -38.90452468
OS 32.07332422 -38.90544924
OS 32.07887158 -38.90544924
OS 32.08256982 -38.90452468
OS 32.09181542 -38.90267556
OS 32.10475926 -38.89990188
OS 32.11862766 -38.89435452
OS 32.13342062 -38.88695804
OS 32.14821358 -38.87586332
OS 32.15561006 -38.8693914
OS 32.16300654 -38.86199492
OS 32.16300654 -38.86107036
OS 32.16485566 -38.8601458
OS 32.16670478 -38.85737212
OS 32.1685539 -38.85367388
OS 32.17225214 -38.84905108
OS 32.17502582 -38.84257916
OS 32.17872406 -38.83610724
OS 32.1824223 -38.8277862
OS 32.18519598 -38.81946516
OS 32.18889422 -38.80837044
OS 32.19259246 -38.79727572
OS 32.19536614 -38.78525644
OS 32.19721526 -38.77138804
OS 32.19906438 -38.75659508
OS 32.2009135 -38.74087756
OS 32.2009135 -38.72423548
OS 32.2009135 -38.72331092
OS 32.2009135 -38.72053724
OS 32.2009135 -38.71591444
OS 32.19998894 -38.70944252
OS 32.19998894 -38.70204604
OS 32.19906438 -38.693725
OS 32.1962907 -38.67430924
OS 32.1916679 -38.65304436
OS 32.18519598 -38.63177948
OS 32.17595038 -38.6105146
OS 32.17040302 -38.60034444
OS 32.1639311 -38.5920234
OS 32.1639311 -38.59109884
OS 32.16208198 -38.59017428
OS 32.15745918 -38.58462692
OS 32.1500627 -38.578155
OS 32.13989254 -38.56983396
OS 32.1269487 -38.56151292
OS 32.11215574 -38.55411644
OS 32.09551366 -38.54949364
OS 32.08626806 -38.54856908
OS 32.07702246 -38.54764452
OE
OB 42.10387566 -38.39601668 H
OS 41.95224782 -38.39601668
OS 41.95224782 -38.58832516
OS 42.10942302 -38.58832516
OS 42.1214423 -38.5874006
OS 42.13438614 -38.58647604
OS 42.14732998 -38.58555148
OS 42.16027382 -38.58370236
OS 42.17044398 -38.58185324
OS 42.1722931 -38.58092868
OS 42.17599134 -38.58000412
OS 42.1815387 -38.57723044
OS 42.18893518 -38.5735322
OS 42.19633166 -38.56983396
OS 42.2046527 -38.5642866
OS 42.21297374 -38.55689012
OS 42.21944566 -38.54949364
OS 42.22037022 -38.54856908
OS 42.22221934 -38.5457954
OS 42.22499302 -38.54024804
OS 42.2277667 -38.53377612
OS 42.23054038 -38.52637964
OS 42.23331406 -38.51713404
OS 42.23516318 -38.50603932
OS 42.23608774 -38.49402004
OS 42.23608774 -38.49217092
OS 42.23608774 -38.48847268
OS 42.23516318 -38.48292532
OS 42.23423862 -38.47552884
OS 42.2323895 -38.46628324
OS 42.22961582 -38.45703764
OS 42.22591758 -38.44779204
OS 42.22037022 -38.43854644
OS 42.21944566 -38.43762188
OS 42.21759654 -38.4348482
OS 42.2138983 -38.4302254
OS 42.2092755 -38.4256026
OS 42.20280358 -38.42005524
OS 42.1954071 -38.41450788
OS 42.1861615 -38.40896052
OS 42.17599134 -38.40526228
OS 42.17506678 -38.40526228
OS 42.17044398 -38.40341316
OS 42.16397206 -38.4024886
OS 42.1538019 -38.40063948
OS 42.1399335 -38.39879036
OS 42.12421598 -38.3978658
OS 42.10387566 -38.39601668
OE
OB 37.41635646 -38.39139388 H
OS 37.21480238 -38.39139388
OS 37.21480238 -38.60311812
OS 37.40526174 -38.60311812
OS 37.41635646 -38.60219356
OS 37.4293003 -38.601269
OS 37.44409326 -38.60034444
OS 37.45888622 -38.59849532
OS 37.47367918 -38.59572164
OS 37.48662302 -38.5920234
OS 37.48847214 -38.59109884
OS 37.49217038 -38.58924972
OS 37.49771774 -38.58647604
OS 37.50511422 -38.5827778
OS 37.51343526 -38.57723044
OS 37.5217563 -38.57075852
OS 37.53007734 -38.56243748
OS 37.53654926 -38.55319188
OS 37.53747382 -38.55226732
OS 37.53932294 -38.54856908
OS 37.54209662 -38.54302172
OS 37.54579486 -38.53562524
OS 37.54856854 -38.5273042
OS 37.55134222 -38.5180586
OS 37.55319134 -38.50696388
OS 37.5541159 -38.49586916
OS 37.5541159 -38.4949446
OS 37.5541159 -38.49402004
OS 37.55319134 -38.48847268
OS 37.55226678 -38.48015164
OS 37.55041766 -38.46905692
OS 37.54579486 -38.4579622
OS 37.5402475 -38.44501836
OS 37.53192646 -38.43299908
OS 37.52083174 -38.4209798
OS 37.51898262 -38.42005524
OS 37.51435982 -38.416357
OS 37.50696334 -38.4117342
OS 37.49494406 -38.40618684
OS 37.48107566 -38.40063948
OS 37.46258446 -38.39601668
OS 37.44131958 -38.39231844
OS 37.41635646 -38.39139388
OE
OB 39.82298614 -38.54764452 H
OS 39.81836334 -38.54764452
OS 39.8146651 -38.54856908
OS 39.8054195 -38.5504182
OS 39.79340022 -38.55319188
OS 39.77953182 -38.55873924
OS 39.76473886 -38.56706028
OS 39.75641782 -38.57260764
OS 39.74902134 -38.57907956
OS 39.74162486 -38.58647604
OS 39.73422838 -38.59479708
OS 39.73422838 -38.59572164
OS 39.73237926 -38.5966462
OS 39.73053014 -38.59941988
OS 39.72868102 -38.60311812
OS 39.72590734 -38.60866548
OS 39.7222091 -38.61421284
OS 39.71851086 -38.62160932
OS 39.71573718 -38.6290058
OS 39.71203894 -38.6382514
OS 39.7083407 -38.64842156
OS 39.70556702 -38.65951628
OS 39.70186878 -38.67153556
OS 39.70001966 -38.68540396
OS 39.69817054 -38.69927236
OS 39.69632142 -38.71406532
OS 39.69632142 -38.7307074
OS 39.69632142 -38.73163196
OS 39.69632142 -38.73440564
OS 39.69632142 -38.73902844
OS 39.69724598 -38.74550036
OS 39.69724598 -38.75289684
OS 39.69817054 -38.76121788
OS 39.70094422 -38.78063364
OS 39.70556702 -38.80282308
OS 39.71111438 -38.82408796
OS 39.72035998 -38.84535284
OS 39.72590734 -38.85459844
OS 39.73237926 -38.86291948
OS 39.73422838 -38.8647686
OS 39.73885118 -38.8693914
OS 39.74624766 -38.87678788
OS 39.75641782 -38.88418436
OS 39.76936166 -38.89158084
OS 39.78415462 -38.89897732
OS 39.8007967 -38.90360012
OS 39.8100423 -38.90452468
OS 39.8192879 -38.90544924
OS 39.82483526 -38.90544924
OS 39.8285335 -38.90452468
OS 39.8377791 -38.90267556
OS 39.85072294 -38.89990188
OS 39.86459134 -38.89435452
OS 39.8793843 -38.88695804
OS 39.89417726 -38.87586332
OS 39.90157374 -38.8693914
OS 39.90897022 -38.86199492
OS 39.90897022 -38.86107036
OS 39.91081934 -38.8601458
OS 39.91266846 -38.85737212
OS 39.91451758 -38.85367388
OS 39.91821582 -38.84905108
OS 39.9209895 -38.84257916
OS 39.92468774 -38.83610724
OS 39.92838598 -38.8277862
OS 39.93115966 -38.81946516
OS 39.9348579 -38.80837044
OS 39.93855614 -38.79727572
OS 39.94132982 -38.78525644
OS 39.94317894 -38.77138804
OS 39.94502806 -38.75659508
OS 39.94687718 -38.74087756
OS 39.94687718 -38.72423548
OS 39.94687718 -38.72331092
OS 39.94687718 -38.72053724
OS 39.94687718 -38.71591444
OS 39.94595262 -38.70944252
OS 39.94595262 -38.70204604
OS 39.94502806 -38.693725
OS 39.94225438 -38.67430924
OS 39.93763158 -38.65304436
OS 39.93115966 -38.63177948
OS 39.92191406 -38.6105146
OS 39.9163667 -38.60034444
OS 39.90989478 -38.5920234
OS 39.90989478 -38.59109884
OS 39.90804566 -38.59017428
OS 39.90342286 -38.58462692
OS 39.89602638 -38.578155
OS 39.88585622 -38.56983396
OS 39.87291238 -38.56151292
OS 39.85811942 -38.55411644
OS 39.84147734 -38.54949364
OS 39.83223174 -38.54856908
OS 39.82298614 -38.54764452
OE
OB 35.73550638 -38.39601668 H
OS 35.5524435 -38.39601668
OS 35.5524435 -38.624383
OS 35.72441166 -38.624383
OS 35.73088358 -38.62345844
OS 35.7373555 -38.62345844
OS 35.74475198 -38.62253388
OS 35.76231862 -38.62068476
OS 35.78173438 -38.61698652
OS 35.80115014 -38.61143916
OS 35.81871678 -38.60404268
OS 35.82703782 -38.59941988
OS 35.83350974 -38.59387252
OS 35.83535886 -38.5920234
OS 35.8390571 -38.58832516
OS 35.84460446 -38.58092868
OS 35.85107638 -38.57168308
OS 35.8575483 -38.5596638
OS 35.86309566 -38.54487084
OS 35.8667939 -38.52822876
OS 35.86864302 -38.508813
OS 35.86864302 -38.50788844
OS 35.86864302 -38.50696388
OS 35.86864302 -38.50234108
OS 35.86771846 -38.49402004
OS 35.86586934 -38.48477444
OS 35.86402022 -38.47460428
OS 35.86032198 -38.462585
OS 35.85477462 -38.45149028
OS 35.8483027 -38.44039556
OS 35.84737814 -38.439471
OS 35.84460446 -38.43577276
OS 35.83998166 -38.43114996
OS 35.8344343 -38.42467804
OS 35.82611326 -38.41820612
OS 35.81686766 -38.41265876
OS 35.8066975 -38.4071114
OS 35.79467822 -38.4024886
OS 35.79375366 -38.4024886
OS 35.79005542 -38.40156404
OS 35.78450806 -38.40063948
OS 35.77711158 -38.39879036
OS 35.76601686 -38.3978658
OS 35.75214846 -38.39694124
OS 35.73550638 -38.39601668
OE
OB 43.44263854 -38.5504182 H
OS 43.43709118 -38.5504182
OS 43.43339294 -38.55134276
OS 43.42322278 -38.55226732
OS 43.4112035 -38.555041
OS 43.39641054 -38.5596638
OS 43.38069302 -38.56613572
OS 43.36590006 -38.57538132
OS 43.3511071 -38.5874006
OS 43.34925798 -38.58924972
OS 43.34555974 -38.59387252
OS 43.33908782 -38.60219356
OS 43.3326159 -38.61328828
OS 43.32521942 -38.62623212
OS 43.3187475 -38.6428742
OS 43.31320014 -38.66228996
OS 43.31042646 -38.68355484
OS 43.57022782 -38.68355484
OS 43.57022782 -38.68263028
OS 43.57022782 -38.68078116
OS 43.56930326 -38.67800748
OS 43.56930326 -38.67430924
OS 43.56745414 -38.66321452
OS 43.56468046 -38.65119524
OS 43.56005766 -38.63640228
OS 43.55543486 -38.62253388
OS 43.54803838 -38.60866548
OS 43.53971734 -38.5966462
OS 43.53971734 -38.59572164
OS 43.53786822 -38.59479708
OS 43.53324542 -38.58924972
OS 43.52492438 -38.58185324
OS 43.51382966 -38.5735322
OS 43.49996126 -38.56521116
OS 43.48331918 -38.55781468
OS 43.46390342 -38.55226732
OS 43.45373326 -38.55134276
OS 43.44263854 -38.5504182
OE
OB 34.35791198 -38.39601668 H
OS 34.20628414 -38.39601668
OS 34.20628414 -38.58832516
OS 34.36345934 -38.58832516
OS 34.37547862 -38.5874006
OS 34.38842246 -38.58647604
OS 34.4013663 -38.58555148
OS 34.41431014 -38.58370236
OS 34.4244803 -38.58185324
OS 34.42632942 -38.58092868
OS 34.43002766 -38.58000412
OS 34.43557502 -38.57723044
OS 34.4429715 -38.5735322
OS 34.45036798 -38.56983396
OS 34.45868902 -38.5642866
OS 34.46701006 -38.55689012
OS 34.47348198 -38.54949364
OS 34.47440654 -38.54856908
OS 34.47625566 -38.5457954
OS 34.47902934 -38.54024804
OS 34.48180302 -38.53377612
OS 34.4845767 -38.52637964
OS 34.48735038 -38.51713404
OS 34.4891995 -38.50603932
OS 34.49012406 -38.49402004
OS 34.49012406 -38.49217092
OS 34.49012406 -38.48847268
OS 34.4891995 -38.48292532
OS 34.48827494 -38.47552884
OS 34.48642582 -38.46628324
OS 34.48365214 -38.45703764
OS 34.4799539 -38.44779204
OS 34.47440654 -38.43854644
OS 34.47348198 -38.43762188
OS 34.47163286 -38.4348482
OS 34.46793462 -38.4302254
OS 34.46331182 -38.4256026
OS 34.4568399 -38.42005524
OS 34.44944342 -38.41450788
OS 34.44019782 -38.40896052
OS 34.43002766 -38.40526228
OS 34.4291031 -38.40526228
OS 34.4244803 -38.40341316
OS 34.41800838 -38.4024886
OS 34.40783822 -38.40063948
OS 34.39396982 -38.39879036
OS 34.3782523 -38.3978658
OS 34.35791198 -38.39601668
OE
OB 40.89732486 -38.39601668 H
OS 40.71426198 -38.39601668
OS 40.71426198 -38.624383
OS 40.88623014 -38.624383
OS 40.89270206 -38.62345844
OS 40.89917398 -38.62345844
OS 40.90657046 -38.62253388
OS 40.9241371 -38.62068476
OS 40.94355286 -38.61698652
OS 40.96296862 -38.61143916
OS 40.98053526 -38.60404268
OS 40.9888563 -38.59941988
OS 40.99532822 -38.59387252
OS 40.99717734 -38.5920234
OS 41.00087558 -38.58832516
OS 41.00642294 -38.58092868
OS 41.01289486 -38.57168308
OS 41.01936678 -38.5596638
OS 41.02491414 -38.54487084
OS 41.02861238 -38.52822876
OS 41.0304615 -38.508813
OS 41.0304615 -38.50788844
OS 41.0304615 -38.50696388
OS 41.0304615 -38.50234108
OS 41.02953694 -38.49402004
OS 41.02768782 -38.48477444
OS 41.0258387 -38.47460428
OS 41.02214046 -38.462585
OS 41.0165931 -38.45149028
OS 41.01012118 -38.44039556
OS 41.00919662 -38.439471
OS 41.00642294 -38.43577276
OS 41.00180014 -38.43114996
OS 40.99625278 -38.42467804
OS 40.98793174 -38.41820612
OS 40.97868614 -38.41265876
OS 40.96851598 -38.4071114
OS 40.9564967 -38.4024886
OS 40.95557214 -38.4024886
OS 40.9518739 -38.40156404
OS 40.94632654 -38.40063948
OS 40.93893006 -38.39879036
OS 40.92783534 -38.3978658
OS 40.91396694 -38.39694124
OS 40.89732486 -38.39601668
OE
OB 33.15136118 -38.39601668 H
OS 32.9682983 -38.39601668
OS 32.9682983 -38.624383
OS 33.14026646 -38.624383
OS 33.14673838 -38.62345844
OS 33.1532103 -38.62345844
OS 33.16060678 -38.62253388
OS 33.17817342 -38.62068476
OS 33.19758918 -38.61698652
OS 33.21700494 -38.61143916
OS 33.23457158 -38.60404268
OS 33.24289262 -38.59941988
OS 33.24936454 -38.59387252
OS 33.25121366 -38.5920234
OS 33.2549119 -38.58832516
OS 33.26045926 -38.58092868
OS 33.26693118 -38.57168308
OS 33.2734031 -38.5596638
OS 33.27895046 -38.54487084
OS 33.2826487 -38.52822876
OS 33.28449782 -38.508813
OS 33.28449782 -38.50788844
OS 33.28449782 -38.50696388
OS 33.28449782 -38.50234108
OS 33.28357326 -38.49402004
OS 33.28172414 -38.48477444
OS 33.27987502 -38.47460428
OS 33.27617678 -38.462585
OS 33.27062942 -38.45149028
OS 33.2641575 -38.44039556
OS 33.26323294 -38.439471
OS 33.26045926 -38.43577276
OS 33.25583646 -38.43114996
OS 33.2502891 -38.42467804
OS 33.24196806 -38.41820612
OS 33.23272246 -38.41265876
OS 33.2225523 -38.4071114
OS 33.21053302 -38.4024886
OS 33.20960846 -38.4024886
OS 33.20591022 -38.40156404
OS 33.20036286 -38.40063948
OS 33.19296638 -38.39879036
OS 33.18187166 -38.3978658
OS 33.16800326 -38.39694124
OS 33.15136118 -38.39601668
OE
OB 34.37455406 -38.66413908 H
OS 34.20628414 -38.66413908
OS 34.20628414 -38.88418436
OS 34.38842246 -38.88418436
OS 34.40783822 -38.8832598
OS 34.41615926 -38.88233524
OS 34.42355574 -38.88141068
OS 34.4244803 -38.88141068
OS 34.42817854 -38.88048612
OS 34.4337259 -38.87956156
OS 34.44019782 -38.87771244
OS 34.45591534 -38.87216508
OS 34.47163286 -38.8647686
OS 34.47255742 -38.86384404
OS 34.4753311 -38.86199492
OS 34.47902934 -38.85922124
OS 34.48365214 -38.855523
OS 34.48827494 -38.84997564
OS 34.49474686 -38.84442828
OS 34.49936966 -38.8370318
OS 34.50491702 -38.82871076
OS 34.50584158 -38.8277862
OS 34.50676614 -38.82501252
OS 34.50861526 -38.81946516
OS 34.51138894 -38.81299324
OS 34.51416262 -38.80559676
OS 34.51601174 -38.79635116
OS 34.5169363 -38.78525644
OS 34.51786086 -38.77416172
OS 34.51786086 -38.7723126
OS 34.51786086 -38.76861436
OS 34.5169363 -38.76121788
OS 34.51508718 -38.75289684
OS 34.51323806 -38.74365124
OS 34.50953982 -38.73348108
OS 34.50491702 -38.72331092
OS 34.4984451 -38.71314076
OS 34.49752054 -38.7122162
OS 34.49474686 -38.70851796
OS 34.49104862 -38.70389516
OS 34.48550126 -38.6983478
OS 34.47810478 -38.69187588
OS 34.46885918 -38.68540396
OS 34.45868902 -38.6798566
OS 34.44666974 -38.6752338
OS 34.44482062 -38.67430924
OS 34.44112238 -38.67338468
OS 34.43280134 -38.67153556
OS 34.42263118 -38.66968644
OS 34.40968734 -38.66783732
OS 34.39396982 -38.6659882
OS 34.37455406 -38.66413908
OE
SE
S P 0
OB 48.49040086 -36.61402634 I
OS 48.17420134 -36.61402634
OS 48.17420134 -37.45999874
OS 48.04661206 -37.45999874
OS 48.04661206 -36.61402634
OS 47.73041254 -36.61402634
OS 47.73041254 -36.50030546
OS 48.49040086 -36.50030546
OS 48.49040086 -36.61402634
OE
OB 47.69990206 -37.45999874 I
OS 47.5556707 -37.45999874
OS 47.44333666 -37.16876234
OS 47.04115306 -37.16876234
OS 46.93714006 -37.45999874
OS 46.80261658 -37.45999874
OS 47.16874234 -36.50030546
OS 47.30742634 -36.50030546
OS 47.69990206 -37.45999874
OE
OB 49.31834434 -36.61402634 I
OS 48.75112678 -36.61402634
OS 48.75112678 -36.90664958
OS 49.2822865 -36.90664958
OS 49.2822865 -37.02037046
OS 48.75112678 -37.02037046
OS 48.75112678 -37.34627786
OS 49.34053378 -37.34627786
OS 49.34053378 -37.45999874
OS 48.6235375 -37.45999874
OS 48.6235375 -36.50030546
OS 49.31834434 -36.50030546
OS 49.31834434 -36.61402634
OE
OB 46.33386466 -36.5016923 I
OS 46.36160146 -36.50307914
OS 46.38933826 -36.50585282
OS 46.41707506 -36.51001334
OS 46.44065134 -36.51417386
OS 46.44203818 -36.51417386
OS 46.44481186 -36.5155607
OS 46.44897238 -36.5155607
OS 46.45451974 -36.51833438
OS 46.46977498 -36.5224949
OS 46.48919074 -36.5294291
OS 46.51138018 -36.53913698
OS 46.53495646 -36.55161854
OS 46.55853274 -36.56548694
OS 46.58072218 -36.58351586
OS 46.58210902 -36.5849027
OS 46.58349586 -36.58628954
OS 46.58765638 -36.59045006
OS 46.59320374 -36.59461058
OS 46.60707214 -36.60847898
OS 46.62371422 -36.62789474
OS 46.64174314 -36.65147102
OS 46.6611589 -36.67920782
OS 46.67918782 -36.71110514
OS 46.69444306 -36.74716298
OS 46.69444306 -36.74854982
OS 46.6958299 -36.7513235
OS 46.69860358 -36.75687086
OS 46.69999042 -36.7651919
OS 46.70415094 -36.77489978
OS 46.70692462 -36.7859945
OS 46.7096983 -36.79847606
OS 46.71385882 -36.8137313
OS 46.71801934 -36.82898654
OS 46.72079302 -36.84701546
OS 46.72772722 -36.88584698
OS 46.73188774 -36.92883902
OS 46.73327458 -36.97599158
OS 46.73327458 -36.97737842
OS 46.73327458 -36.9801521
OS 46.73327458 -36.9870863
OS 46.73327458 -36.9940205
OS 46.73188774 -37.00372838
OS 46.73188774 -37.0148231
OS 46.7305009 -37.04117306
OS 46.72634038 -37.07168354
OS 46.72217986 -37.10358086
OS 46.71524566 -37.13686502
OS 46.70692462 -37.17014918
OS 46.70692462 -37.17153602
OS 46.70553778 -37.1743097
OS 46.70415094 -37.17847022
OS 46.7027641 -37.18401758
OS 46.69721674 -37.19927282
OS 46.6888957 -37.21868858
OS 46.68057466 -37.24087802
OS 46.66947994 -37.26306746
OS 46.65561154 -37.28664374
OS 46.64174314 -37.30883318
OS 46.6403563 -37.31160686
OS 46.63480894 -37.31854106
OS 46.6264879 -37.32824894
OS 46.61539318 -37.3407305
OS 46.60291162 -37.3545989
OS 46.58765638 -37.3684673
OS 46.57240114 -37.38372254
OS 46.55437222 -37.3962041
OS 46.55159854 -37.39759094
OS 46.54605118 -37.40175146
OS 46.5363433 -37.40729882
OS 46.5224749 -37.41423302
OS 46.50583282 -37.42255406
OS 46.48641706 -37.42948826
OS 46.46422762 -37.4378093
OS 46.4392645 -37.4447435
OS 46.43649082 -37.4447435
OS 46.4323303 -37.44613034
OS 46.42816978 -37.44751718
OS 46.41430138 -37.44890402
OS 46.39488562 -37.4516777
OS 46.37269618 -37.45445138
OS 46.34634622 -37.45722506
OS 46.31722258 -37.4586119
OS 46.28532526 -37.45999874
OS 45.9400021 -37.45999874
OS 45.9400021 -36.50030546
OS 46.30890154 -36.50030546
OS 46.33386466 -36.5016923
OE
OB 46.28948578 -36.61402634 H
OS 46.06759138 -36.61402634
OS 46.06759138 -37.34627786
OS 46.29503314 -37.34627786
OS 46.30474102 -37.34489102
OS 46.32554362 -37.34350418
OS 46.3491199 -37.34211734
OS 46.37408302 -37.33934366
OS 46.39904614 -37.33518314
OS 46.41984874 -37.32963578
OS 46.42262242 -37.32824894
OS 46.42955662 -37.3268621
OS 46.4392645 -37.32270158
OS 46.45174606 -37.31715422
OS 46.46561446 -37.30883318
OS 46.47948286 -37.30051214
OS 46.49335126 -37.29080426
OS 46.50721966 -37.27970954
OS 46.5086065 -37.27693586
OS 46.51415386 -37.2713885
OS 46.5224749 -37.26168062
OS 46.53218278 -37.24781222
OS 46.5432775 -37.2297833
OS 46.55575906 -37.2089807
OS 46.56685378 -37.18540442
OS 46.57656166 -37.15905446
OS 46.57656166 -37.15766762
OS 46.5779485 -37.15489394
OS 46.57933534 -37.15073342
OS 46.58072218 -37.14518606
OS 46.58210902 -37.13825186
OS 46.5848827 -37.12854398
OS 46.58765638 -37.1188361
OS 46.59043006 -37.10774138
OS 46.59459058 -37.08000458
OS 46.5987511 -37.04810726
OS 46.60152478 -37.01204942
OS 46.60291162 -36.9732179
OS 46.60291162 -36.97183106
OS 46.60291162 -36.9662837
OS 46.60291162 -36.9593495
OS 46.60152478 -36.94825478
OS 46.60152478 -36.93577322
OS 46.60013794 -36.92190482
OS 46.5987511 -36.90526274
OS 46.59736426 -36.88862066
OS 46.59043006 -36.85117598
OS 46.58210902 -36.81234446
OS 46.56962746 -36.77628662
OS 46.56130642 -36.7582577
OS 46.55298538 -36.74300246
OS 46.55298538 -36.74161562
OS 46.5502117 -36.73884194
OS 46.54743802 -36.73468142
OS 46.54466434 -36.72913406
OS 46.53356962 -36.71526566
OS 46.51970122 -36.69862358
OS 46.5016723 -36.68059466
OS 46.4808697 -36.66256574
OS 46.45729342 -36.6473105
OS 46.4323303 -36.63482894
OS 46.42955662 -36.6334421
OS 46.42262242 -36.63205526
OS 46.41014086 -36.62789474
OS 46.39211194 -36.62373422
OS 46.3699225 -36.62096054
OS 46.3421857 -36.61680002
OS 46.32554362 -36.61541318
OS 46.3075147 -36.61541318
OS 46.28948578 -36.61402634
OE
OB 47.23531066 -36.60015794 H
OS 47.23531066 -36.60154478
OS 47.23392382 -36.60431846
OS 47.23392382 -36.60986582
OS 47.23115014 -36.61541318
OS 47.2297633 -36.62512106
OS 47.22698962 -36.63482894
OS 47.22144226 -36.65840522
OS 47.21450806 -36.68614202
OS 47.20480018 -36.7166525
OS 47.1950923 -36.74993666
OS 47.18261074 -36.78460766
OS 47.07859774 -37.06474934
OS 47.4031183 -37.06474934
OS 47.30326582 -36.80124974
OS 47.30326582 -36.7998629
OS 47.30187898 -36.79570238
OS 47.2991053 -36.78876818
OS 47.29633162 -36.78044714
OS 47.2921711 -36.77073926
OS 47.28801058 -36.7582577
OS 47.28385006 -36.7443893
OS 47.2783027 -36.7305209
OS 47.26720798 -36.69862358
OS 47.25611326 -36.66533942
OS 47.24501854 -36.63205526
OS 47.23531066 -36.60015794
OE
SE
S P 0
OB 53.64989524 -38.94890356 I
OS 53.57130764 -38.94890356
OS 53.57130764 -38.4487166
OS 53.57038308 -38.44964116
OS 53.56576028 -38.4533394
OS 53.56021292 -38.45888676
OS 53.55096732 -38.46535868
OS 53.54079716 -38.47367972
OS 53.52785332 -38.48292532
OS 53.51306036 -38.49309548
OS 53.49641828 -38.50326564
OS 53.49549372 -38.50326564
OS 53.49456916 -38.5041902
OS 53.4890218 -38.50788844
OS 53.4797762 -38.51251124
OS 53.46868148 -38.5180586
OS 53.45573764 -38.52453052
OS 53.44186924 -38.53100244
OS 53.42800084 -38.53747436
OS 53.41413244 -38.54302172
OS 53.41413244 -38.4672078
OS 53.415057 -38.4672078
OS 53.41690612 -38.46535868
OS 53.42060436 -38.46443412
OS 53.42522716 -38.46166044
OS 53.43077452 -38.45888676
OS 53.43724644 -38.45518852
OS 53.45296396 -38.44594292
OS 53.47145516 -38.43577276
OS 53.48994636 -38.42282892
OS 53.50936212 -38.40803596
OS 53.52877788 -38.39231844
OS 53.52970244 -38.39139388
OS 53.530627 -38.39046932
OS 53.53340068 -38.38769564
OS 53.53709892 -38.38492196
OS 53.54541996 -38.37567636
OS 53.55651468 -38.36458164
OS 53.5676094 -38.3516378
OS 53.57962868 -38.33684484
OS 53.58979884 -38.32205188
OS 53.59904444 -38.30633436
OS 53.64989524 -38.30633436
OS 53.64989524 -38.94890356
OE
OB 54.07334372 -38.30725892 I
OS 54.0807402 -38.30818348
OS 54.08906124 -38.30910804
OS 54.09830684 -38.3100326
OS 54.10755244 -38.31280628
OS 54.12974188 -38.31835364
OS 54.15193132 -38.32667468
OS 54.16302604 -38.33222204
OS 54.17412076 -38.33869396
OS 54.18429092 -38.347015
OS 54.19446108 -38.35533604
OS 54.19538564 -38.3562606
OS 54.1963102 -38.35718516
OS 54.19908388 -38.35995884
OS 54.20278212 -38.36365708
OS 54.20648036 -38.36920444
OS 54.21110316 -38.3747518
OS 54.22034876 -38.3886202
OS 54.22959436 -38.40618684
OS 54.2379154 -38.42652716
OS 54.24438732 -38.44964116
OS 54.24531188 -38.46166044
OS 54.24623644 -38.47460428
OS 54.24623644 -38.47552884
OS 54.24623644 -38.4764534
OS 54.24623644 -38.48200076
OS 54.24531188 -38.4903218
OS 54.24346276 -38.50049196
OS 54.24068908 -38.5134358
OS 54.23606628 -38.52637964
OS 54.23051892 -38.53932348
OS 54.22219788 -38.55226732
OS 54.22127332 -38.55411644
OS 54.21757508 -38.55781468
OS 54.21202772 -38.56336204
OS 54.20463124 -38.57075852
OS 54.19446108 -38.57907956
OS 54.1824418 -38.5874006
OS 54.1685734 -38.59572164
OS 54.15193132 -38.60311812
OS 54.15285588 -38.60311812
OS 54.154705 -38.60404268
OS 54.15747868 -38.60496724
OS 54.16117692 -38.60681636
OS 54.17227164 -38.61143916
OS 54.18521548 -38.61791108
OS 54.19908388 -38.62715668
OS 54.21387684 -38.63732684
OS 54.22774524 -38.65027068
OS 54.24068908 -38.66506364
OS 54.24068908 -38.6659882
OS 54.24161364 -38.66691276
OS 54.24531188 -38.67246012
OS 54.25085924 -38.68170572
OS 54.2564066 -38.693725
OS 54.26195396 -38.70851796
OS 54.26750132 -38.7260846
OS 54.27119956 -38.74550036
OS 54.27212412 -38.76676524
OS 54.27212412 -38.7676898
OS 54.27212412 -38.77046348
OS 54.27212412 -38.77508628
OS 54.27119956 -38.78063364
OS 54.270275 -38.78710556
OS 54.26935044 -38.7954266
OS 54.26750132 -38.8046722
OS 54.26472764 -38.81484236
OS 54.25825572 -38.83610724
OS 54.25363292 -38.84812652
OS 54.247161 -38.85922124
OS 54.24068908 -38.87124052
OS 54.2332926 -38.88233524
OS 54.224047 -38.89342996
OS 54.21387684 -38.90452468
OS 54.21295228 -38.90544924
OS 54.21110316 -38.90729836
OS 54.20832948 -38.91007204
OS 54.20370668 -38.91284572
OS 54.19723476 -38.91746852
OS 54.19076284 -38.92209132
OS 54.1824418 -38.92671412
OS 54.1731962 -38.93226148
OS 54.16302604 -38.93780884
OS 54.15100676 -38.94243164
OS 54.13806292 -38.94705444
OS 54.12511908 -38.95167724
OS 54.11032612 -38.95445092
OS 54.0946086 -38.9572246
OS 54.07889108 -38.95907372
OS 54.06132444 -38.95999828
OS 54.05207884 -38.95999828
OS 54.04560692 -38.95907372
OS 54.03728588 -38.95814916
OS 54.02804028 -38.9572246
OS 54.01787012 -38.95537548
OS 54.0067754 -38.9526018
OS 53.98181228 -38.94612988
OS 53.96886844 -38.94150708
OS 53.95684916 -38.93688428
OS 53.94390532 -38.93041236
OS 53.93096148 -38.92301588
OS 53.9189422 -38.91469484
OS 53.90784748 -38.90452468
OS 53.90692292 -38.90360012
OS 53.9050738 -38.901751
OS 53.90230012 -38.89897732
OS 53.89860188 -38.89435452
OS 53.89490364 -38.88880716
OS 53.88935628 -38.88233524
OS 53.88473348 -38.87493876
OS 53.87918612 -38.86569316
OS 53.87363876 -38.85644756
OS 53.86901596 -38.84535284
OS 53.85977036 -38.82223884
OS 53.85607212 -38.80837044
OS 53.85329844 -38.79450204
OS 53.85144932 -38.77970908
OS 53.85052476 -38.76491612
OS 53.85052476 -38.76399156
OS 53.85052476 -38.76214244
OS 53.85052476 -38.7584442
OS 53.85144932 -38.75474596
OS 53.85144932 -38.7491986
OS 53.85237388 -38.74272668
OS 53.854223 -38.72793372
OS 53.85792124 -38.71129164
OS 53.8634686 -38.69464956
OS 53.87178964 -38.67708292
OS 53.8819598 -38.66044084
OS 53.8819598 -38.65951628
OS 53.88380892 -38.65859172
OS 53.88750716 -38.65396892
OS 53.89490364 -38.64657244
OS 53.9050738 -38.63732684
OS 53.91801764 -38.62808124
OS 53.93373516 -38.61791108
OS 53.9513018 -38.60959004
OS 53.97256668 -38.60311812
OS 53.97164212 -38.60311812
OS 53.97071756 -38.60219356
OS 53.96794388 -38.601269
OS 53.96424564 -38.59941988
OS 53.9559246 -38.59572164
OS 53.94482988 -38.59017428
OS 53.9328106 -38.5827778
OS 53.92079132 -38.5735322
OS 53.9096966 -38.56336204
OS 53.89952644 -38.55226732
OS 53.89860188 -38.5504182
OS 53.8958282 -38.54671996
OS 53.89212996 -38.53932348
OS 53.88843172 -38.53007788
OS 53.88380892 -38.5180586
OS 53.88011068 -38.5041902
OS 53.877337 -38.48847268
OS 53.87641244 -38.4718306
OS 53.87641244 -38.47090604
OS 53.87641244 -38.46905692
OS 53.87641244 -38.46535868
OS 53.877337 -38.45981132
OS 53.87826156 -38.45426396
OS 53.87918612 -38.44686748
OS 53.88288436 -38.43114996
OS 53.88843172 -38.41265876
OS 53.89767732 -38.393243
OS 53.90322468 -38.38307284
OS 53.9096966 -38.37290268
OS 53.91801764 -38.36365708
OS 53.92633868 -38.35441148
OS 53.92726324 -38.35348692
OS 53.92911236 -38.35256236
OS 53.93188604 -38.34978868
OS 53.93558428 -38.347015
OS 53.94020708 -38.34331676
OS 53.946679 -38.33961852
OS 53.95407548 -38.33499572
OS 53.96147196 -38.33037292
OS 53.97071756 -38.32575012
OS 53.98088772 -38.32112732
OS 53.99198244 -38.31742908
OS 54.00400172 -38.31373084
OS 54.0298894 -38.30818348
OS 54.04468236 -38.30725892
OS 54.05947532 -38.30633436
OS 54.06779636 -38.30633436
OS 54.07334372 -38.30725892
OE
OB 53.23846604 -38.94890356 I
OS 53.14878372 -38.94890356
OS 53.14878372 -38.85922124
OS 53.23846604 -38.85922124
OS 53.23846604 -38.94890356
OE
OB 53.00177868 -38.39231844 I
OS 52.74567556 -38.39231844
OS 52.71146684 -38.56521116
OS 52.7123914 -38.5642866
OS 52.71424052 -38.56336204
OS 52.7170142 -38.56151292
OS 52.721637 -38.55873924
OS 52.72718436 -38.55596556
OS 52.73365628 -38.55226732
OS 52.74844924 -38.54487084
OS 52.76694044 -38.53747436
OS 52.78728076 -38.53100244
OS 52.8094702 -38.52637964
OS 52.82056492 -38.52453052
OS 52.84090524 -38.52453052
OS 52.8464526 -38.52545508
OS 52.85384908 -38.52637964
OS 52.86217012 -38.5273042
OS 52.87141572 -38.52915332
OS 52.88158588 -38.531927
OS 52.90377532 -38.53839892
OS 52.9157946 -38.54302172
OS 52.92781388 -38.54949364
OS 52.93983316 -38.55596556
OS 52.95185244 -38.56336204
OS 52.96294716 -38.57260764
OS 52.97404188 -38.5827778
OS 52.97496644 -38.58370236
OS 52.97681556 -38.58555148
OS 52.97958924 -38.58832516
OS 52.98328748 -38.59294796
OS 52.98791028 -38.59941988
OS 52.99253308 -38.6058918
OS 52.99808044 -38.61421284
OS 53.0036278 -38.62345844
OS 53.0082506 -38.6336286
OS 53.01379796 -38.64472332
OS 53.01842076 -38.65766716
OS 53.02304356 -38.670611
OS 53.0267418 -38.6844794
OS 53.02951548 -38.70019692
OS 53.0313646 -38.71591444
OS 53.03228916 -38.73255652
OS 53.03228916 -38.73348108
OS 53.03228916 -38.73625476
OS 53.03228916 -38.74087756
OS 53.0313646 -38.74734948
OS 53.03044004 -38.75474596
OS 53.02951548 -38.763067
OS 53.02766636 -38.77323716
OS 53.02581724 -38.78340732
OS 53.02026988 -38.80744588
OS 53.01102428 -38.832409
OS 53.00547692 -38.84535284
OS 52.99808044 -38.85737212
OS 52.99068396 -38.87031596
OS 52.98143836 -38.88233524
OS 52.9805138 -38.8832598
OS 52.97866468 -38.88603348
OS 52.97496644 -38.88973172
OS 52.97034364 -38.89435452
OS 52.96387172 -38.89990188
OS 52.95647524 -38.90729836
OS 52.94722964 -38.91377028
OS 52.93705948 -38.92116676
OS 52.92596476 -38.92856324
OS 52.91302092 -38.93503516
OS 52.89915252 -38.94150708
OS 52.88435956 -38.947979
OS 52.86864204 -38.9526018
OS 52.8510754 -38.95630004
OS 52.8325842 -38.95907372
OS 52.81316844 -38.95999828
OS 52.8048474 -38.95999828
OS 52.79837548 -38.95907372
OS 52.790979 -38.95814916
OS 52.78265796 -38.9572246
OS 52.7724878 -38.95630004
OS 52.76231764 -38.95352636
OS 52.73920364 -38.947979
OS 52.71608964 -38.93965796
OS 52.70407036 -38.9341106
OS 52.69205108 -38.92763868
OS 52.68095636 -38.9202422
OS 52.66986164 -38.91192116
OS 52.66893708 -38.9109966
OS 52.66708796 -38.91007204
OS 52.66523884 -38.9063738
OS 52.6615406 -38.90267556
OS 52.6569178 -38.89805276
OS 52.652295 -38.8925054
OS 52.64674764 -38.88510892
OS 52.64212484 -38.87678788
OS 52.63657748 -38.86846684
OS 52.63103012 -38.85829668
OS 52.62085996 -38.83610724
OS 52.61253892 -38.81021956
OS 52.60976524 -38.79635116
OS 52.60791612 -38.7815582
OS 52.69020196 -38.77508628
OS 52.69020196 -38.77601084
OS 52.69020196 -38.77785996
OS 52.69112652 -38.78063364
OS 52.69205108 -38.78525644
OS 52.69482476 -38.7954266
OS 52.698523 -38.809295
OS 52.70407036 -38.8231634
OS 52.71146684 -38.83888092
OS 52.72071244 -38.85274932
OS 52.73180716 -38.86569316
OS 52.73365628 -38.86661772
OS 52.73735452 -38.87031596
OS 52.744751 -38.87493876
OS 52.75492116 -38.88048612
OS 52.76601588 -38.88603348
OS 52.77988428 -38.89065628
OS 52.7956018 -38.89435452
OS 52.81316844 -38.89527908
OS 52.8187158 -38.89527908
OS 52.82241404 -38.89435452
OS 52.83350876 -38.89342996
OS 52.8464526 -38.88973172
OS 52.86217012 -38.88510892
OS 52.87788764 -38.87771244
OS 52.89452972 -38.86661772
OS 52.9019262 -38.8601458
OS 52.90932268 -38.85274932
OS 52.91024724 -38.85182476
OS 52.9111718 -38.8509002
OS 52.91302092 -38.84812652
OS 52.9157946 -38.84535284
OS 52.92226652 -38.83518268
OS 52.929663 -38.82223884
OS 52.93613492 -38.80652132
OS 52.94260684 -38.78710556
OS 52.94722964 -38.76399156
OS 52.94907876 -38.75197228
OS 52.94907876 -38.73902844
OS 52.94907876 -38.73810388
OS 52.94907876 -38.73625476
OS 52.94907876 -38.73255652
OS 52.9481542 -38.72793372
OS 52.9481542 -38.72238636
OS 52.94722964 -38.71591444
OS 52.94445596 -38.70112148
OS 52.93983316 -38.68355484
OS 52.93336124 -38.6659882
OS 52.92411564 -38.64934612
OS 52.9111718 -38.6336286
OS 52.9111718 -38.63270404
OS 52.90932268 -38.63177948
OS 52.90469988 -38.62715668
OS 52.89637884 -38.62068476
OS 52.88528412 -38.61328828
OS 52.87049116 -38.60681636
OS 52.85384908 -38.60034444
OS 52.83443332 -38.59572164
OS 52.8233386 -38.59387252
OS 52.80577196 -38.59387252
OS 52.79837548 -38.59479708
OS 52.78912988 -38.59572164
OS 52.77803516 -38.59849532
OS 52.76694044 -38.601269
OS 52.75492116 -38.6058918
OS 52.74290188 -38.61143916
OS 52.74197732 -38.61236372
OS 52.73827908 -38.61421284
OS 52.73273172 -38.61883564
OS 52.72533524 -38.62345844
OS 52.71793876 -38.62993036
OS 52.71054228 -38.6382514
OS 52.70222124 -38.64657244
OS 52.69574932 -38.6567426
OS 52.62178452 -38.64657244
OS 52.68373004 -38.31742908
OS 53.00177868 -38.31742908
OS 53.00177868 -38.39231844
OE
OB 53.23846604 -38.57445676 I
OS 53.14878372 -38.57445676
OS 53.14878372 -38.48477444
OS 53.23846604 -38.48477444
OS 53.23846604 -38.57445676
OE
OB 54.48199924 -38.57445676 I
OS 54.39231692 -38.57445676
OS 54.39231692 -38.48477444
OS 54.48199924 -38.48477444
OS 54.48199924 -38.57445676
OE
OB 56.14990548 -38.3100326 I
OS 56.165623 -38.31095716
OS 56.18226508 -38.31188172
OS 56.1979826 -38.31373084
OS 56.211851 -38.31557996
OS 56.21370012 -38.31557996
OS 56.22017204 -38.31742908
OS 56.22849308 -38.3192782
OS 56.2395878 -38.32205188
OS 56.25160708 -38.32667468
OS 56.26455092 -38.33222204
OS 56.27841932 -38.33869396
OS 56.2904386 -38.34609044
OS 56.29228772 -38.347015
OS 56.29598596 -38.34978868
OS 56.30153332 -38.35533604
OS 56.3089298 -38.36180796
OS 56.31725084 -38.370129
OS 56.32557188 -38.38122372
OS 56.33481748 -38.393243
OS 56.34221396 -38.4071114
OS 56.34313852 -38.40896052
OS 56.34498764 -38.41358332
OS 56.34868588 -38.42190436
OS 56.35238412 -38.43299908
OS 56.3551578 -38.44594292
OS 56.35885604 -38.46073588
OS 56.36070516 -38.47737796
OS 56.36162972 -38.4949446
OS 56.36162972 -38.49586916
OS 56.36162972 -38.49864284
OS 56.36162972 -38.50234108
OS 56.36070516 -38.508813
OS 56.3597806 -38.51528492
OS 56.35885604 -38.52360596
OS 56.35700692 -38.53285156
OS 56.3551578 -38.54302172
OS 56.34868588 -38.5642866
OS 56.34498764 -38.57538132
OS 56.33944028 -38.5874006
OS 56.33296836 -38.59941988
OS 56.32649644 -38.6105146
OS 56.3181754 -38.62160932
OS 56.3089298 -38.63270404
OS 56.30800524 -38.6336286
OS 56.30615612 -38.63547772
OS 56.30338244 -38.6382514
OS 56.29875964 -38.64102508
OS 56.29321228 -38.64564788
OS 56.2858158 -38.65027068
OS 56.2765702 -38.65581804
OS 56.26640004 -38.66044084
OS 56.25438076 -38.6659882
OS 56.24051236 -38.67153556
OS 56.2257194 -38.67615836
OS 56.20815276 -38.6798566
OS 56.18966156 -38.68355484
OS 56.16932124 -38.68632852
OS 56.14620724 -38.68817764
OS 56.12216868 -38.6891022
OS 55.95852156 -38.6891022
OS 55.95852156 -38.94890356
OS 55.87346204 -38.94890356
OS 55.87346204 -38.30910804
OS 56.13603708 -38.30910804
OS 56.14990548 -38.3100326
OE
OB 57.07723916 -38.94890356 I
OS 56.99587788 -38.94890356
OS 56.99587788 -38.41358332
OS 56.80911676 -38.94890356
OS 56.73330284 -38.94890356
OS 56.54839084 -38.40433772
OS 56.54839084 -38.94890356
OS 56.46702956 -38.94890356
OS 56.46702956 -38.30910804
OS 56.59369428 -38.30910804
OS 56.74532212 -38.763067
OS 56.74532212 -38.76399156
OS 56.74624668 -38.76584068
OS 56.74717124 -38.76861436
OS 56.74902036 -38.77323716
OS 56.7527186 -38.78433188
OS 56.7573414 -38.79820028
OS 56.7619642 -38.8139178
OS 56.76751156 -38.82963532
OS 56.77213436 -38.84442828
OS 56.7758326 -38.85737212
OS 56.77675716 -38.855523
OS 56.77768172 -38.8509002
OS 56.7804554 -38.84257916
OS 56.78415364 -38.83148444
OS 56.78877644 -38.81669148
OS 56.79524836 -38.79912484
OS 56.80172028 -38.77878452
OS 56.81004132 -38.75474596
OS 56.96351828 -38.30910804
OS 57.07723916 -38.30910804
OS 57.07723916 -38.94890356
OE
OB 55.39084172 -38.94890356 I
OS 55.31225412 -38.94890356
OS 55.31225412 -38.4487166
OS 55.31132956 -38.44964116
OS 55.30670676 -38.4533394
OS 55.3011594 -38.45888676
OS 55.2919138 -38.46535868
OS 55.28174364 -38.47367972
OS 55.2687998 -38.48292532
OS 55.25400684 -38.49309548
OS 55.23736476 -38.50326564
OS 55.2364402 -38.50326564
OS 55.23551564 -38.5041902
OS 55.22996828 -38.50788844
OS 55.22072268 -38.51251124
OS 55.20962796 -38.5180586
OS 55.19668412 -38.52453052
OS 55.18281572 -38.53100244
OS 55.16894732 -38.53747436
OS 55.15507892 -38.54302172
OS 55.15507892 -38.4672078
OS 55.15600348 -38.4672078
OS 55.1578526 -38.46535868
OS 55.16155084 -38.46443412
OS 55.16617364 -38.46166044
OS 55.171721 -38.45888676
OS 55.17819292 -38.45518852
OS 55.19391044 -38.44594292
OS 55.21240164 -38.43577276
OS 55.23089284 -38.42282892
OS 55.2503086 -38.40803596
OS 55.26972436 -38.39231844
OS 55.27064892 -38.39139388
OS 55.27157348 -38.39046932
OS 55.27434716 -38.38769564
OS 55.2780454 -38.38492196
OS 55.28636644 -38.37567636
OS 55.29746116 -38.36458164
OS 55.30855588 -38.3516378
OS 55.32057516 -38.33684484
OS 55.33074532 -38.32205188
OS 55.33999092 -38.30633436
OS 55.39084172 -38.30633436
OS 55.39084172 -38.94890356
OE
OB 54.48199924 -38.94890356 I
OS 54.39231692 -38.94890356
OS 54.39231692 -38.85922124
OS 54.48199924 -38.85922124
OS 54.48199924 -38.94890356
OE
OB 54.825011 -38.30725892 I
OS 54.83703028 -38.30910804
OS 54.85089868 -38.31188172
OS 54.86569164 -38.31557996
OS 54.88140916 -38.32020276
OS 54.89620212 -38.32759924
OS 54.89712668 -38.32759924
OS 54.89805124 -38.3285238
OS 54.90267404 -38.33129748
OS 54.91007052 -38.33592028
OS 54.91931612 -38.3423922
OS 54.92948628 -38.3516378
OS 54.940581 -38.36180796
OS 54.95075116 -38.37382724
OS 54.96092132 -38.38769564
OS 54.96184588 -38.38954476
OS 54.96554412 -38.39416756
OS 54.96924236 -38.4024886
OS 54.97571428 -38.41450788
OS 54.98126164 -38.42837628
OS 54.98865812 -38.4440938
OS 54.99513004 -38.462585
OS 55.0006774 -38.48292532
OS 55.0006774 -38.48384988
OS 55.00160196 -38.485699
OS 55.00252652 -38.48847268
OS 55.00345108 -38.49309548
OS 55.00437564 -38.49864284
OS 55.0053002 -38.50511476
OS 55.00714932 -38.5134358
OS 55.00807388 -38.5226814
OS 55.009923 -38.53285156
OS 55.01084756 -38.54394628
OS 55.01177212 -38.55689012
OS 55.01362124 -38.56983396
OS 55.0145458 -38.58462692
OS 55.0145458 -38.59941988
OS 55.01547036 -38.61606196
OS 55.01547036 -38.6336286
OS 55.01547036 -38.63455316
OS 55.01547036 -38.6382514
OS 55.01547036 -38.64472332
OS 55.01547036 -38.6521198
OS 55.0145458 -38.66228996
OS 55.0145458 -38.67338468
OS 55.01362124 -38.68540396
OS 55.01269668 -38.6983478
OS 55.009923 -38.72793372
OS 55.0053002 -38.7584442
OS 54.99975284 -38.78803012
OS 54.9960546 -38.80189852
OS 54.9914318 -38.81576692
OS 54.9914318 -38.81669148
OS 54.99050724 -38.8185406
OS 54.98865812 -38.82223884
OS 54.986809 -38.82686164
OS 54.98495988 -38.83333356
OS 54.98126164 -38.83980548
OS 54.97386516 -38.855523
OS 54.96461956 -38.87216508
OS 54.95260028 -38.89065628
OS 54.93873188 -38.90729836
OS 54.9220898 -38.92301588
OS 54.92116524 -38.92301588
OS 54.92024068 -38.924865
OS 54.917467 -38.92671412
OS 54.91376876 -38.92856324
OS 54.90914596 -38.93133692
OS 54.90452316 -38.93503516
OS 54.89065476 -38.94150708
OS 54.87401268 -38.947979
OS 54.85459692 -38.95445092
OS 54.83148292 -38.95814916
OS 54.8065198 -38.95999828
OS 54.7972742 -38.95999828
OS 54.79080228 -38.95907372
OS 54.7834058 -38.95814916
OS 54.7741602 -38.95630004
OS 54.76399004 -38.95445092
OS 54.75289532 -38.95167724
OS 54.7418006 -38.947979
OS 54.72978132 -38.94428076
OS 54.71776204 -38.9387334
OS 54.70574276 -38.93226148
OS 54.69372348 -38.924865
OS 54.6817042 -38.9156194
OS 54.67060948 -38.90544924
OS 54.66043932 -38.89435452
OS 54.65951476 -38.89342996
OS 54.65766564 -38.89065628
OS 54.65489196 -38.88603348
OS 54.65026916 -38.878637
OS 54.64564636 -38.87031596
OS 54.64102356 -38.85922124
OS 54.63455164 -38.8462774
OS 54.62900428 -38.83148444
OS 54.62345692 -38.81484236
OS 54.61790956 -38.7954266
OS 54.6123622 -38.77416172
OS 54.6077394 -38.75012316
OS 54.6031166 -38.72423548
OS 54.60034292 -38.69649868
OS 54.5984938 -38.6659882
OS 54.59756924 -38.6336286
OS 54.59756924 -38.63270404
OS 54.59756924 -38.6290058
OS 54.59756924 -38.62253388
OS 54.59756924 -38.6151374
OS 54.5984938 -38.60496724
OS 54.5984938 -38.59387252
OS 54.59941836 -38.58185324
OS 54.60034292 -38.56798484
OS 54.6031166 -38.53932348
OS 54.6077394 -38.508813
OS 54.61328676 -38.47830252
OS 54.616985 -38.46443412
OS 54.62068324 -38.45056572
OS 54.62068324 -38.44964116
OS 54.6216078 -38.44779204
OS 54.62345692 -38.4440938
OS 54.62530604 -38.439471
OS 54.62715516 -38.43299908
OS 54.6308534 -38.42652716
OS 54.63824988 -38.41080964
OS 54.64749548 -38.39416756
OS 54.65951476 -38.37660092
OS 54.67338316 -38.35903428
OS 54.69002524 -38.34424132
OS 54.6909498 -38.34424132
OS 54.69187436 -38.3423922
OS 54.69464804 -38.34054308
OS 54.69834628 -38.33869396
OS 54.70296908 -38.33499572
OS 54.70851644 -38.33222204
OS 54.72238484 -38.32482556
OS 54.73902692 -38.31835364
OS 54.75844268 -38.31188172
OS 54.78155668 -38.30818348
OS 54.8065198 -38.30633436
OS 54.81484084 -38.30633436
OS 54.825011 -38.30725892
OE
OB 49.95350436 -38.72331092 I
OS 50.040413 -38.72331092
OS 50.040413 -38.7954266
OS 49.95350436 -38.7954266
OS 49.95350436 -38.94890356
OS 49.87491676 -38.94890356
OS 49.87491676 -38.7954266
OS 49.5966242 -38.7954266
OS 49.5966242 -38.72331092
OS 49.88970972 -38.30910804
OS 49.95350436 -38.30910804
OS 49.95350436 -38.72331092
OE
OB 50.1467374 -38.95999828 I
OS 50.08386732 -38.95999828
OS 50.26970388 -38.29801332
OS 50.33257396 -38.29801332
OS 50.1467374 -38.95999828
OE
OB 50.59699812 -38.30725892 I
OS 50.6043946 -38.30818348
OS 50.6136402 -38.30910804
OS 50.62381036 -38.31095716
OS 50.63398052 -38.31280628
OS 50.65801908 -38.3192782
OS 50.68205764 -38.3285238
OS 50.69407692 -38.33407116
OS 50.7060962 -38.34054308
OS 50.71719092 -38.34886412
OS 50.72736108 -38.35810972
OS 50.72828564 -38.35903428
OS 50.73013476 -38.35995884
OS 50.73198388 -38.36365708
OS 50.73568212 -38.36735532
OS 50.74030492 -38.37197812
OS 50.74492772 -38.37845004
OS 50.74955052 -38.38492196
OS 50.75509788 -38.393243
OS 50.76434348 -38.41080964
OS 50.77358908 -38.43299908
OS 50.77728732 -38.4440938
OS 50.77913644 -38.45703764
OS 50.78098556 -38.46998148
OS 50.78191012 -38.48384988
OS 50.78191012 -38.485699
OS 50.78191012 -38.4903218
OS 50.78098556 -38.49771828
OS 50.780061 -38.50788844
OS 50.77821188 -38.51898316
OS 50.77451364 -38.531927
OS 50.7708154 -38.5457954
OS 50.76526804 -38.5596638
OS 50.76434348 -38.56151292
OS 50.76249436 -38.56613572
OS 50.75879612 -38.5735322
OS 50.75324876 -38.58370236
OS 50.74585228 -38.59479708
OS 50.73660668 -38.60866548
OS 50.72551196 -38.62253388
OS 50.71256812 -38.6382514
OS 50.710719 -38.64010052
OS 50.7060962 -38.64564788
OS 50.7014734 -38.65027068
OS 50.6968506 -38.65489348
OS 50.69130324 -38.66044084
OS 50.68390676 -38.66783732
OS 50.67651028 -38.6752338
OS 50.66726468 -38.68355484
OS 50.65801908 -38.69280044
OS 50.64692436 -38.7029706
OS 50.63490508 -38.71314076
OS 50.62196124 -38.72516004
OS 50.60716828 -38.73717932
OS 50.59237532 -38.75012316
OS 50.59145076 -38.75104772
OS 50.58960164 -38.75289684
OS 50.5859034 -38.75567052
OS 50.5812806 -38.75936876
OS 50.57573324 -38.76491612
OS 50.56926132 -38.77046348
OS 50.55446836 -38.78248276
OS 50.53875084 -38.79635116
OS 50.52395788 -38.81021956
OS 50.51101404 -38.82223884
OS 50.50546668 -38.82686164
OS 50.50084388 -38.83148444
OS 50.49991932 -38.832409
OS 50.49714564 -38.83518268
OS 50.4934474 -38.83888092
OS 50.4888246 -38.84442828
OS 50.4842018 -38.8509002
OS 50.47865444 -38.85737212
OS 50.46755972 -38.87308964
OS 50.78283468 -38.87308964
OS 50.78283468 -38.94890356
OS 50.35846164 -38.94890356
OS 50.35846164 -38.947979
OS 50.35846164 -38.94428076
OS 50.35846164 -38.9387334
OS 50.3593862 -38.93133692
OS 50.36031076 -38.92301588
OS 50.36215988 -38.91377028
OS 50.364009 -38.90452468
OS 50.36770724 -38.89435452
OS 50.36770724 -38.89342996
OS 50.3686318 -38.8925054
OS 50.37048092 -38.88695804
OS 50.37417916 -38.878637
OS 50.37972652 -38.86754228
OS 50.387123 -38.85459844
OS 50.3963686 -38.83980548
OS 50.40653876 -38.82501252
OS 50.4194826 -38.809295
OS 50.4194826 -38.80837044
OS 50.42133172 -38.80744588
OS 50.42595452 -38.80189852
OS 50.43427556 -38.79357748
OS 50.44629484 -38.7815582
OS 50.46016324 -38.7676898
OS 50.47772988 -38.75104772
OS 50.49899476 -38.73255652
OS 50.52210876 -38.71314076
OS 50.52303332 -38.7122162
OS 50.52673156 -38.70944252
OS 50.53227892 -38.70481972
OS 50.53875084 -38.69927236
OS 50.54707188 -38.69187588
OS 50.55724204 -38.68355484
OS 50.5674122 -38.67430924
OS 50.57943148 -38.66413908
OS 50.60254548 -38.64194964
OS 50.62565948 -38.6197602
OS 50.6367542 -38.60866548
OS 50.64692436 -38.59757076
OS 50.65616996 -38.5874006
OS 50.66356644 -38.57723044
OS 50.66356644 -38.57630588
OS 50.66541556 -38.57538132
OS 50.66726468 -38.57260764
OS 50.6691138 -38.5689094
OS 50.67558572 -38.55873924
OS 50.6829822 -38.54671996
OS 50.68945412 -38.531927
OS 50.69592604 -38.51620948
OS 50.69962428 -38.49864284
OS 50.7014734 -38.48200076
OS 50.7014734 -38.4810762
OS 50.7014734 -38.48015164
OS 50.70054884 -38.47460428
OS 50.69962428 -38.46535868
OS 50.6968506 -38.45518852
OS 50.69315236 -38.44224468
OS 50.68668044 -38.42930084
OS 50.6783594 -38.416357
OS 50.66726468 -38.40341316
OS 50.66541556 -38.40156404
OS 50.66079276 -38.3978658
OS 50.65432084 -38.393243
OS 50.64415068 -38.38677108
OS 50.63120684 -38.38122372
OS 50.61641388 -38.37567636
OS 50.59884724 -38.37197812
OS 50.57943148 -38.37105356
OS 50.57388412 -38.37105356
OS 50.57018588 -38.37197812
OS 50.55909116 -38.37290268
OS 50.54614732 -38.37567636
OS 50.53227892 -38.3793746
OS 50.5165614 -38.38584652
OS 50.50176844 -38.39416756
OS 50.48790004 -38.40526228
OS 50.48605092 -38.4071114
OS 50.48235268 -38.4117342
OS 50.47680532 -38.41913068
OS 50.47125796 -38.4302254
OS 50.46478604 -38.44316924
OS 50.45923868 -38.45981132
OS 50.45554044 -38.47830252
OS 50.45369132 -38.4995674
OS 50.3732546 -38.49124636
OS 50.3732546 -38.4903218
OS 50.37417916 -38.48754812
OS 50.37417916 -38.48292532
OS 50.37510372 -38.4764534
OS 50.37695284 -38.46905692
OS 50.37880196 -38.46073588
OS 50.38157564 -38.45056572
OS 50.38434932 -38.44039556
OS 50.3917458 -38.41820612
OS 50.40284052 -38.39601668
OS 50.40931244 -38.38492196
OS 50.41763348 -38.37382724
OS 50.42595452 -38.36365708
OS 50.43520012 -38.35441148
OS 50.43612468 -38.35348692
OS 50.4379738 -38.35256236
OS 50.44074748 -38.34978868
OS 50.44537028 -38.347015
OS 50.45091764 -38.34331676
OS 50.45738956 -38.33961852
OS 50.46478604 -38.33499572
OS 50.47403164 -38.33037292
OS 50.4842018 -38.32575012
OS 50.49529652 -38.32112732
OS 50.5073158 -38.31742908
OS 50.52025964 -38.31373084
OS 50.53412804 -38.31095716
OS 50.548921 -38.30818348
OS 50.56463852 -38.30725892
OS 50.5812806 -38.30633436
OS 50.5905262 -38.30633436
OS 50.59699812 -38.30725892
OE
OB 48.67576244 -38.94890356 I
OS 48.59717484 -38.94890356
OS 48.59717484 -38.4487166
OS 48.59625028 -38.44964116
OS 48.59162748 -38.4533394
OS 48.58608012 -38.45888676
OS 48.57683452 -38.46535868
OS 48.56666436 -38.47367972
OS 48.55372052 -38.48292532
OS 48.53892756 -38.49309548
OS 48.52228548 -38.50326564
OS 48.52136092 -38.50326564
OS 48.52043636 -38.5041902
OS 48.514889 -38.50788844
OS 48.5056434 -38.51251124
OS 48.49454868 -38.5180586
OS 48.48160484 -38.52453052
OS 48.46773644 -38.53100244
OS 48.45386804 -38.53747436
OS 48.43999964 -38.54302172
OS 48.43999964 -38.4672078
OS 48.4409242 -38.4672078
OS 48.44277332 -38.46535868
OS 48.44647156 -38.46443412
OS 48.45109436 -38.46166044
OS 48.45664172 -38.45888676
OS 48.46311364 -38.45518852
OS 48.47883116 -38.44594292
OS 48.49732236 -38.43577276
OS 48.51581356 -38.42282892
OS 48.53522932 -38.40803596
OS 48.55464508 -38.39231844
OS 48.55556964 -38.39139388
OS 48.5564942 -38.39046932
OS 48.55926788 -38.38769564
OS 48.56296612 -38.38492196
OS 48.57128716 -38.37567636
OS 48.58238188 -38.36458164
OS 48.5934766 -38.3516378
OS 48.60549588 -38.33684484
OS 48.61566604 -38.32205188
OS 48.62491164 -38.30633436
OS 48.67576244 -38.30633436
OS 48.67576244 -38.94890356
OE
OB 48.9032042 -38.95999828 I
OS 48.84033412 -38.95999828
OS 49.02617068 -38.29801332
OS 49.08904076 -38.29801332
OS 48.9032042 -38.95999828
OE
OB 49.35346492 -38.30725892 I
OS 49.3608614 -38.30818348
OS 49.370107 -38.30910804
OS 49.38027716 -38.31095716
OS 49.39044732 -38.31280628
OS 49.41448588 -38.3192782
OS 49.43852444 -38.3285238
OS 49.45054372 -38.33407116
OS 49.462563 -38.34054308
OS 49.47365772 -38.34886412
OS 49.48382788 -38.35810972
OS 49.48475244 -38.35903428
OS 49.48660156 -38.35995884
OS 49.48845068 -38.36365708
OS 49.49214892 -38.36735532
OS 49.49677172 -38.37197812
OS 49.50139452 -38.37845004
OS 49.50601732 -38.38492196
OS 49.51156468 -38.393243
OS 49.52081028 -38.41080964
OS 49.53005588 -38.43299908
OS 49.53375412 -38.4440938
OS 49.53560324 -38.45703764
OS 49.53745236 -38.46998148
OS 49.53837692 -38.48384988
OS 49.53837692 -38.485699
OS 49.53837692 -38.4903218
OS 49.53745236 -38.49771828
OS 49.5365278 -38.50788844
OS 49.53467868 -38.51898316
OS 49.53098044 -38.531927
OS 49.5272822 -38.5457954
OS 49.52173484 -38.5596638
OS 49.52081028 -38.56151292
OS 49.51896116 -38.56613572
OS 49.51526292 -38.5735322
OS 49.50971556 -38.58370236
OS 49.50231908 -38.59479708
OS 49.49307348 -38.60866548
OS 49.48197876 -38.62253388
OS 49.46903492 -38.6382514
OS 49.4671858 -38.64010052
OS 49.462563 -38.64564788
OS 49.4579402 -38.65027068
OS 49.4533174 -38.65489348
OS 49.44777004 -38.66044084
OS 49.44037356 -38.66783732
OS 49.43297708 -38.6752338
OS 49.42373148 -38.68355484
OS 49.41448588 -38.69280044
OS 49.40339116 -38.7029706
OS 49.39137188 -38.71314076
OS 49.37842804 -38.72516004
OS 49.36363508 -38.73717932
OS 49.34884212 -38.75012316
OS 49.34791756 -38.75104772
OS 49.34606844 -38.75289684
OS 49.3423702 -38.75567052
OS 49.3377474 -38.75936876
OS 49.33220004 -38.76491612
OS 49.32572812 -38.77046348
OS 49.31093516 -38.78248276
OS 49.29521764 -38.79635116
OS 49.28042468 -38.81021956
OS 49.26748084 -38.82223884
OS 49.26193348 -38.82686164
OS 49.25731068 -38.83148444
OS 49.25638612 -38.832409
OS 49.25361244 -38.83518268
OS 49.2499142 -38.83888092
OS 49.2452914 -38.84442828
OS 49.2406686 -38.8509002
OS 49.23512124 -38.85737212
OS 49.22402652 -38.87308964
OS 49.53930148 -38.87308964
OS 49.53930148 -38.94890356
OS 49.11492844 -38.94890356
OS 49.11492844 -38.947979
OS 49.11492844 -38.94428076
OS 49.11492844 -38.9387334
OS 49.115853 -38.93133692
OS 49.11677756 -38.92301588
OS 49.11862668 -38.91377028
OS 49.1204758 -38.90452468
OS 49.12417404 -38.89435452
OS 49.12417404 -38.89342996
OS 49.1250986 -38.8925054
OS 49.12694772 -38.88695804
OS 49.13064596 -38.878637
OS 49.13619332 -38.86754228
OS 49.1435898 -38.85459844
OS 49.1528354 -38.83980548
OS 49.16300556 -38.82501252
OS 49.1759494 -38.809295
OS 49.1759494 -38.80837044
OS 49.17779852 -38.80744588
OS 49.18242132 -38.80189852
OS 49.19074236 -38.79357748
OS 49.20276164 -38.7815582
OS 49.21663004 -38.7676898
OS 49.23419668 -38.75104772
OS 49.25546156 -38.73255652
OS 49.27857556 -38.71314076
OS 49.27950012 -38.7122162
OS 49.28319836 -38.70944252
OS 49.28874572 -38.70481972
OS 49.29521764 -38.69927236
OS 49.30353868 -38.69187588
OS 49.31370884 -38.68355484
OS 49.323879 -38.67430924
OS 49.33589828 -38.66413908
OS 49.35901228 -38.64194964
OS 49.38212628 -38.6197602
OS 49.393221 -38.60866548
OS 49.40339116 -38.59757076
OS 49.41263676 -38.5874006
OS 49.42003324 -38.57723044
OS 49.42003324 -38.57630588
OS 49.42188236 -38.57538132
OS 49.42373148 -38.57260764
OS 49.4255806 -38.5689094
OS 49.43205252 -38.55873924
OS 49.439449 -38.54671996
OS 49.44592092 -38.531927
OS 49.45239284 -38.51620948
OS 49.45609108 -38.49864284
OS 49.4579402 -38.48200076
OS 49.4579402 -38.4810762
OS 49.4579402 -38.48015164
OS 49.45701564 -38.47460428
OS 49.45609108 -38.46535868
OS 49.4533174 -38.45518852
OS 49.44961916 -38.44224468
OS 49.44314724 -38.42930084
OS 49.4348262 -38.416357
OS 49.42373148 -38.40341316
OS 49.42188236 -38.40156404
OS 49.41725956 -38.3978658
OS 49.41078764 -38.393243
OS 49.40061748 -38.38677108
OS 49.38767364 -38.38122372
OS 49.37288068 -38.37567636
OS 49.35531404 -38.37197812
OS 49.33589828 -38.37105356
OS 49.33035092 -38.37105356
OS 49.32665268 -38.37197812
OS 49.31555796 -38.37290268
OS 49.30261412 -38.37567636
OS 49.28874572 -38.3793746
OS 49.2730282 -38.38584652
OS 49.25823524 -38.39416756
OS 49.24436684 -38.40526228
OS 49.24251772 -38.4071114
OS 49.23881948 -38.4117342
OS 49.23327212 -38.41913068
OS 49.22772476 -38.4302254
OS 49.22125284 -38.44316924
OS 49.21570548 -38.45981132
OS 49.21200724 -38.47830252
OS 49.21015812 -38.4995674
OS 49.1297214 -38.49124636
OS 49.1297214 -38.4903218
OS 49.13064596 -38.48754812
OS 49.13064596 -38.48292532
OS 49.13157052 -38.4764534
OS 49.13341964 -38.46905692
OS 49.13526876 -38.46073588
OS 49.13804244 -38.45056572
OS 49.14081612 -38.44039556
OS 49.1482126 -38.41820612
OS 49.15930732 -38.39601668
OS 49.16577924 -38.38492196
OS 49.17410028 -38.37382724
OS 49.18242132 -38.36365708
OS 49.19166692 -38.35441148
OS 49.19259148 -38.35348692
OS 49.1944406 -38.35256236
OS 49.19721428 -38.34978868
OS 49.20183708 -38.347015
OS 49.20738444 -38.34331676
OS 49.21385636 -38.33961852
OS 49.22125284 -38.33499572
OS 49.23049844 -38.33037292
OS 49.2406686 -38.32575012
OS 49.25176332 -38.32112732
OS 49.2637826 -38.31742908
OS 49.27672644 -38.31373084
OS 49.29059484 -38.31095716
OS 49.3053878 -38.30818348
OS 49.32110532 -38.30725892
OS 49.3377474 -38.30633436
OS 49.346993 -38.30633436
OS 49.35346492 -38.30725892
OE
OB 51.0944114 -38.30725892 I
OS 51.10643068 -38.30910804
OS 51.12029908 -38.31188172
OS 51.13509204 -38.31557996
OS 51.15080956 -38.32020276
OS 51.16560252 -38.32759924
OS 51.16652708 -38.32759924
OS 51.16745164 -38.3285238
OS 51.17207444 -38.33129748
OS 51.17947092 -38.33592028
OS 51.18871652 -38.3423922
OS 51.19888668 -38.3516378
OS 51.2099814 -38.36180796
OS 51.22015156 -38.37382724
OS 51.23032172 -38.38769564
OS 51.23124628 -38.38954476
OS 51.23494452 -38.39416756
OS 51.23864276 -38.4024886
OS 51.24511468 -38.41450788
OS 51.25066204 -38.42837628
OS 51.25805852 -38.4440938
OS 51.26453044 -38.462585
OS 51.2700778 -38.48292532
OS 51.2700778 -38.48384988
OS 51.27100236 -38.485699
OS 51.27192692 -38.48847268
OS 51.27285148 -38.49309548
OS 51.27377604 -38.49864284
OS 51.2747006 -38.50511476
OS 51.27654972 -38.5134358
OS 51.27747428 -38.5226814
OS 51.2793234 -38.53285156
OS 51.28024796 -38.54394628
OS 51.28117252 -38.55689012
OS 51.28302164 -38.56983396
OS 51.2839462 -38.58462692
OS 51.2839462 -38.59941988
OS 51.28487076 -38.61606196
OS 51.28487076 -38.6336286
OS 51.28487076 -38.63455316
OS 51.28487076 -38.6382514
OS 51.28487076 -38.64472332
OS 51.28487076 -38.6521198
OS 51.2839462 -38.66228996
OS 51.2839462 -38.67338468
OS 51.28302164 -38.68540396
OS 51.28209708 -38.6983478
OS 51.2793234 -38.72793372
OS 51.2747006 -38.7584442
OS 51.26915324 -38.78803012
OS 51.265455 -38.80189852
OS 51.2608322 -38.81576692
OS 51.2608322 -38.81669148
OS 51.25990764 -38.8185406
OS 51.25805852 -38.82223884
OS 51.2562094 -38.82686164
OS 51.25436028 -38.83333356
OS 51.25066204 -38.83980548
OS 51.24326556 -38.855523
OS 51.23401996 -38.87216508
OS 51.22200068 -38.89065628
OS 51.20813228 -38.90729836
OS 51.1914902 -38.92301588
OS 51.19056564 -38.92301588
OS 51.18964108 -38.924865
OS 51.1868674 -38.92671412
OS 51.18316916 -38.92856324
OS 51.17854636 -38.93133692
OS 51.17392356 -38.93503516
OS 51.16005516 -38.94150708
OS 51.14341308 -38.947979
OS 51.12399732 -38.95445092
OS 51.10088332 -38.95814916
OS 51.0759202 -38.95999828
OS 51.0666746 -38.95999828
OS 51.06020268 -38.95907372
OS 51.0528062 -38.95814916
OS 51.0435606 -38.95630004
OS 51.03339044 -38.95445092
OS 51.02229572 -38.95167724
OS 51.011201 -38.947979
OS 50.99918172 -38.94428076
OS 50.98716244 -38.9387334
OS 50.97514316 -38.93226148
OS 50.96312388 -38.924865
OS 50.9511046 -38.9156194
OS 50.94000988 -38.90544924
OS 50.92983972 -38.89435452
OS 50.92891516 -38.89342996
OS 50.92706604 -38.89065628
OS 50.92429236 -38.88603348
OS 50.91966956 -38.878637
OS 50.91504676 -38.87031596
OS 50.91042396 -38.85922124
OS 50.90395204 -38.8462774
OS 50.89840468 -38.83148444
OS 50.89285732 -38.81484236
OS 50.88730996 -38.7954266
OS 50.8817626 -38.77416172
OS 50.8771398 -38.75012316
OS 50.872517 -38.72423548
OS 50.86974332 -38.69649868
OS 50.8678942 -38.6659882
OS 50.86696964 -38.6336286
OS 50.86696964 -38.63270404
OS 50.86696964 -38.6290058
OS 50.86696964 -38.62253388
OS 50.86696964 -38.6151374
OS 50.8678942 -38.60496724
OS 50.8678942 -38.59387252
OS 50.86881876 -38.58185324
OS 50.86974332 -38.56798484
OS 50.872517 -38.53932348
OS 50.8771398 -38.508813
OS 50.88268716 -38.47830252
OS 50.8863854 -38.46443412
OS 50.89008364 -38.45056572
OS 50.89008364 -38.44964116
OS 50.8910082 -38.44779204
OS 50.89285732 -38.4440938
OS 50.89470644 -38.439471
OS 50.89655556 -38.43299908
OS 50.9002538 -38.42652716
OS 50.90765028 -38.41080964
OS 50.91689588 -38.39416756
OS 50.92891516 -38.37660092
OS 50.94278356 -38.35903428
OS 50.95942564 -38.34424132
OS 50.9603502 -38.34424132
OS 50.96127476 -38.3423922
OS 50.96404844 -38.34054308
OS 50.96774668 -38.33869396
OS 50.97236948 -38.33499572
OS 50.97791684 -38.33222204
OS 50.99178524 -38.32482556
OS 51.00842732 -38.31835364
OS 51.02784308 -38.31188172
OS 51.05095708 -38.30818348
OS 51.0759202 -38.30633436
OS 51.08424124 -38.30633436
OS 51.0944114 -38.30725892
OE
OB 51.59182468 -38.30725892 I
OS 51.59922116 -38.30818348
OS 51.60846676 -38.30910804
OS 51.61863692 -38.31095716
OS 51.62880708 -38.31280628
OS 51.65284564 -38.3192782
OS 51.6768842 -38.3285238
OS 51.68890348 -38.33407116
OS 51.70092276 -38.34054308
OS 51.71201748 -38.34886412
OS 51.72218764 -38.35810972
OS 51.7231122 -38.35903428
OS 51.72496132 -38.35995884
OS 51.72681044 -38.36365708
OS 51.73050868 -38.36735532
OS 51.73513148 -38.37197812
OS 51.73975428 -38.37845004
OS 51.74437708 -38.38492196
OS 51.74992444 -38.393243
OS 51.75917004 -38.41080964
OS 51.76841564 -38.43299908
OS 51.77211388 -38.4440938
OS 51.773963 -38.45703764
OS 51.77581212 -38.46998148
OS 51.77673668 -38.48384988
OS 51.77673668 -38.485699
OS 51.77673668 -38.4903218
OS 51.77581212 -38.49771828
OS 51.77488756 -38.50788844
OS 51.77303844 -38.51898316
OS 51.7693402 -38.531927
OS 51.76564196 -38.5457954
OS 51.7600946 -38.5596638
OS 51.75917004 -38.56151292
OS 51.75732092 -38.56613572
OS 51.75362268 -38.5735322
OS 51.74807532 -38.58370236
OS 51.74067884 -38.59479708
OS 51.73143324 -38.60866548
OS 51.72033852 -38.62253388
OS 51.70739468 -38.6382514
OS 51.70554556 -38.64010052
OS 51.70092276 -38.64564788
OS 51.69629996 -38.65027068
OS 51.69167716 -38.65489348
OS 51.6861298 -38.66044084
OS 51.67873332 -38.66783732
OS 51.67133684 -38.6752338
OS 51.66209124 -38.68355484
OS 51.65284564 -38.69280044
OS 51.64175092 -38.7029706
OS 51.62973164 -38.71314076
OS 51.6167878 -38.72516004
OS 51.60199484 -38.73717932
OS 51.58720188 -38.75012316
OS 51.58627732 -38.75104772
OS 51.5844282 -38.75289684
OS 51.58072996 -38.75567052
OS 51.57610716 -38.75936876
OS 51.5705598 -38.76491612
OS 51.56408788 -38.77046348
OS 51.54929492 -38.78248276
OS 51.5335774 -38.79635116
OS 51.51878444 -38.81021956
OS 51.5058406 -38.82223884
OS 51.50029324 -38.82686164
OS 51.49567044 -38.83148444
OS 51.49474588 -38.832409
OS 51.4919722 -38.83518268
OS 51.48827396 -38.83888092
OS 51.48365116 -38.84442828
OS 51.47902836 -38.8509002
OS 51.473481 -38.85737212
OS 51.46238628 -38.87308964
OS 51.77766124 -38.87308964
OS 51.77766124 -38.94890356
OS 51.3532882 -38.94890356
OS 51.3532882 -38.947979
OS 51.3532882 -38.94428076
OS 51.3532882 -38.9387334
OS 51.35421276 -38.93133692
OS 51.35513732 -38.92301588
OS 51.35698644 -38.91377028
OS 51.35883556 -38.90452468
OS 51.3625338 -38.89435452
OS 51.3625338 -38.89342996
OS 51.36345836 -38.8925054
OS 51.36530748 -38.88695804
OS 51.36900572 -38.878637
OS 51.37455308 -38.86754228
OS 51.38194956 -38.85459844
OS 51.39119516 -38.83980548
OS 51.40136532 -38.82501252
OS 51.41430916 -38.809295
OS 51.41430916 -38.80837044
OS 51.41615828 -38.80744588
OS 51.42078108 -38.80189852
OS 51.42910212 -38.79357748
OS 51.4411214 -38.7815582
OS 51.4549898 -38.7676898
OS 51.47255644 -38.75104772
OS 51.49382132 -38.73255652
OS 51.51693532 -38.71314076
OS 51.51785988 -38.7122162
OS 51.52155812 -38.70944252
OS 51.52710548 -38.70481972
OS 51.5335774 -38.69927236
OS 51.54189844 -38.69187588
OS 51.5520686 -38.68355484
OS 51.56223876 -38.67430924
OS 51.57425804 -38.66413908
OS 51.59737204 -38.64194964
OS 51.62048604 -38.6197602
OS 51.63158076 -38.60866548
OS 51.64175092 -38.59757076
OS 51.65099652 -38.5874006
OS 51.658393 -38.57723044
OS 51.658393 -38.57630588
OS 51.66024212 -38.57538132
OS 51.66209124 -38.57260764
OS 51.66394036 -38.5689094
OS 51.67041228 -38.55873924
OS 51.67780876 -38.54671996
OS 51.68428068 -38.531927
OS 51.6907526 -38.51620948
OS 51.69445084 -38.49864284
OS 51.69629996 -38.48200076
OS 51.69629996 -38.4810762
OS 51.69629996 -38.48015164
OS 51.6953754 -38.47460428
OS 51.69445084 -38.46535868
OS 51.69167716 -38.45518852
OS 51.68797892 -38.44224468
OS 51.681507 -38.42930084
OS 51.67318596 -38.416357
OS 51.66209124 -38.40341316
OS 51.66024212 -38.40156404
OS 51.65561932 -38.3978658
OS 51.6491474 -38.393243
OS 51.63897724 -38.38677108
OS 51.6260334 -38.38122372
OS 51.61124044 -38.37567636
OS 51.5936738 -38.37197812
OS 51.57425804 -38.37105356
OS 51.56871068 -38.37105356
OS 51.56501244 -38.37197812
OS 51.55391772 -38.37290268
OS 51.54097388 -38.37567636
OS 51.52710548 -38.3793746
OS 51.51138796 -38.38584652
OS 51.496595 -38.39416756
OS 51.4827266 -38.40526228
OS 51.48087748 -38.4071114
OS 51.47717924 -38.4117342
OS 51.47163188 -38.41913068
OS 51.46608452 -38.4302254
OS 51.4596126 -38.44316924
OS 51.45406524 -38.45981132
OS 51.450367 -38.47830252
OS 51.44851788 -38.4995674
OS 51.36808116 -38.49124636
OS 51.36808116 -38.4903218
OS 51.36900572 -38.48754812
OS 51.36900572 -38.48292532
OS 51.36993028 -38.4764534
OS 51.3717794 -38.46905692
OS 51.37362852 -38.46073588
OS 51.3764022 -38.45056572
OS 51.37917588 -38.44039556
OS 51.38657236 -38.41820612
OS 51.39766708 -38.39601668
OS 51.404139 -38.38492196
OS 51.41246004 -38.37382724
OS 51.42078108 -38.36365708
OS 51.43002668 -38.35441148
OS 51.43095124 -38.35348692
OS 51.43280036 -38.35256236
OS 51.43557404 -38.34978868
OS 51.44019684 -38.347015
OS 51.4457442 -38.34331676
OS 51.45221612 -38.33961852
OS 51.4596126 -38.33499572
OS 51.4688582 -38.33037292
OS 51.47902836 -38.32575012
OS 51.49012308 -38.32112732
OS 51.50214236 -38.31742908
OS 51.5150862 -38.31373084
OS 51.5289546 -38.31095716
OS 51.54374756 -38.30818348
OS 51.55946508 -38.30725892
OS 51.57610716 -38.30633436
OS 51.58535276 -38.30633436
OS 51.59182468 -38.30725892
OE
OB 52.08184148 -38.30725892 I
OS 52.09386076 -38.30910804
OS 52.10865372 -38.31188172
OS 52.1252958 -38.31650452
OS 52.14193788 -38.32205188
OS 52.15857996 -38.32944836
OS 52.15950452 -38.32944836
OS 52.16042908 -38.33037292
OS 52.16597644 -38.3331466
OS 52.17429748 -38.33869396
OS 52.18354308 -38.34516588
OS 52.1946378 -38.35441148
OS 52.20573252 -38.36458164
OS 52.21682724 -38.37660092
OS 52.22607284 -38.39046932
OS 52.2269974 -38.39231844
OS 52.22977108 -38.39694124
OS 52.23346932 -38.40526228
OS 52.23809212 -38.41543244
OS 52.24271492 -38.42745172
OS 52.24641316 -38.44132012
OS 52.24918684 -38.45703764
OS 52.2501114 -38.47275516
OS 52.2501114 -38.47460428
OS 52.2501114 -38.48015164
OS 52.24918684 -38.48754812
OS 52.24733772 -38.49771828
OS 52.24456404 -38.50973756
OS 52.23994124 -38.5226814
OS 52.23439388 -38.53562524
OS 52.2269974 -38.54856908
OS 52.22607284 -38.5504182
OS 52.22329916 -38.55411644
OS 52.2177518 -38.56058836
OS 52.21035532 -38.56798484
OS 52.20110972 -38.57630588
OS 52.190015 -38.58555148
OS 52.17707116 -38.59387252
OS 52.16135364 -38.60219356
OS 52.1622782 -38.60219356
OS 52.16412732 -38.60311812
OS 52.166901 -38.60404268
OS 52.17059924 -38.60496724
OS 52.1807694 -38.60866548
OS 52.19371324 -38.61421284
OS 52.2085062 -38.62160932
OS 52.22329916 -38.63085492
OS 52.23716756 -38.6428742
OS 52.2501114 -38.6567426
OS 52.25103596 -38.65859172
OS 52.2547342 -38.66413908
OS 52.26028156 -38.67338468
OS 52.26582892 -38.68540396
OS 52.27137628 -38.70019692
OS 52.27692364 -38.71776356
OS 52.28062188 -38.73810388
OS 52.28154644 -38.76029332
OS 52.28154644 -38.76121788
OS 52.28154644 -38.76399156
OS 52.28154644 -38.76861436
OS 52.28062188 -38.77416172
OS 52.27969732 -38.7815582
OS 52.2778482 -38.78987924
OS 52.27599908 -38.79912484
OS 52.27414996 -38.809295
OS 52.26675348 -38.83148444
OS 52.26120612 -38.84350372
OS 52.25565876 -38.85459844
OS 52.24826228 -38.86661772
OS 52.23994124 -38.878637
OS 52.23069564 -38.89065628
OS 52.21960092 -38.901751
OS 52.21867636 -38.90267556
OS 52.21682724 -38.90452468
OS 52.213129 -38.90729836
OS 52.2085062 -38.9109966
OS 52.20295884 -38.9156194
OS 52.19556236 -38.9202422
OS 52.18724132 -38.92578956
OS 52.17707116 -38.93041236
OS 52.166901 -38.93595972
OS 52.15488172 -38.94150708
OS 52.14286244 -38.94612988
OS 52.12899404 -38.95075268
OS 52.11420108 -38.95445092
OS 52.09848356 -38.9572246
OS 52.08276604 -38.95907372
OS 52.0651994 -38.95999828
OS 52.05687836 -38.95999828
OS 52.051331 -38.95907372
OS 52.04393452 -38.95814916
OS 52.03561348 -38.9572246
OS 52.02636788 -38.95537548
OS 52.01619772 -38.95352636
OS 51.99400828 -38.947979
OS 51.97089428 -38.9387334
OS 51.958875 -38.93318604
OS 51.94778028 -38.92671412
OS 51.93668556 -38.91839308
OS 51.92559084 -38.91007204
OS 51.92466628 -38.90914748
OS 51.92281716 -38.90729836
OS 51.92004348 -38.90452468
OS 51.9172698 -38.90082644
OS 51.912647 -38.89620364
OS 51.9080242 -38.88973172
OS 51.90247684 -38.8832598
OS 51.89692948 -38.87493876
OS 51.89138212 -38.86569316
OS 51.88583476 -38.85644756
OS 51.8756646 -38.83425812
OS 51.86734356 -38.80837044
OS 51.86456988 -38.79450204
OS 51.86272076 -38.77970908
OS 51.94130836 -38.76953892
OS 51.94130836 -38.77046348
OS 51.94223292 -38.7723126
OS 51.94315748 -38.77601084
OS 51.94408204 -38.78063364
OS 51.9450066 -38.786181
OS 51.94685572 -38.79265292
OS 51.95147852 -38.80652132
OS 51.95795044 -38.8231634
OS 51.96627148 -38.83888092
OS 51.97551708 -38.85367388
OS 51.9866118 -38.86661772
OS 51.98846092 -38.86754228
OS 51.99215916 -38.87124052
OS 51.99955564 -38.87586332
OS 52.00880124 -38.88048612
OS 52.01989596 -38.88603348
OS 52.03376436 -38.89065628
OS 52.04948188 -38.89435452
OS 52.06612396 -38.89527908
OS 52.07167132 -38.89527908
OS 52.07536956 -38.89435452
OS 52.08553972 -38.89342996
OS 52.09848356 -38.89065628
OS 52.11327652 -38.88603348
OS 52.12899404 -38.87956156
OS 52.14471156 -38.87031596
OS 52.15950452 -38.85737212
OS 52.16135364 -38.855523
OS 52.16597644 -38.84997564
OS 52.1715238 -38.8416546
OS 52.17892028 -38.83055988
OS 52.18631676 -38.81669148
OS 52.19186412 -38.80097396
OS 52.19648692 -38.78248276
OS 52.19833604 -38.76214244
OS 52.19833604 -38.76121788
OS 52.19833604 -38.75936876
OS 52.19833604 -38.75659508
OS 52.19741148 -38.75289684
OS 52.19648692 -38.74272668
OS 52.19371324 -38.7307074
OS 52.190015 -38.71591444
OS 52.18354308 -38.70112148
OS 52.17429748 -38.68632852
OS 52.1622782 -38.67246012
OS 52.16042908 -38.670611
OS 52.15580628 -38.66691276
OS 52.1484098 -38.6613654
OS 52.13823964 -38.65489348
OS 52.1252958 -38.64842156
OS 52.10957828 -38.6428742
OS 52.09201164 -38.63917596
OS 52.07259588 -38.63732684
OS 52.06427484 -38.63732684
OS 52.05780292 -38.6382514
OS 52.04948188 -38.63917596
OS 52.04023628 -38.64102508
OS 52.02914156 -38.6428742
OS 52.01712228 -38.64564788
OS 52.02636788 -38.57630588
OS 52.03099068 -38.57630588
OS 52.03468892 -38.57723044
OS 52.0467082 -38.57723044
OS 52.05687836 -38.57538132
OS 52.06889764 -38.5735322
OS 52.08276604 -38.57075852
OS 52.09848356 -38.56613572
OS 52.11327652 -38.5596638
OS 52.12899404 -38.55134276
OS 52.1299186 -38.55134276
OS 52.13084316 -38.5504182
OS 52.13546596 -38.54671996
OS 52.14193788 -38.54024804
OS 52.14933436 -38.531927
OS 52.15673084 -38.51990772
OS 52.16320276 -38.50603932
OS 52.16782556 -38.4903218
OS 52.16967468 -38.4810762
OS 52.16967468 -38.47090604
OS 52.16967468 -38.46998148
OS 52.16967468 -38.46905692
OS 52.16967468 -38.46350956
OS 52.16782556 -38.45611308
OS 52.16597644 -38.44594292
OS 52.1622782 -38.4348482
OS 52.1576554 -38.42282892
OS 52.15025892 -38.41080964
OS 52.14008876 -38.39971492
OS 52.1391642 -38.39879036
OS 52.1345414 -38.39509212
OS 52.12806948 -38.39046932
OS 52.11974844 -38.38492196
OS 52.10865372 -38.38029916
OS 52.09570988 -38.37567636
OS 52.08091692 -38.37197812
OS 52.06427484 -38.37105356
OS 52.05687836 -38.37105356
OS 52.04855732 -38.37290268
OS 52.0374626 -38.3747518
OS 52.02544332 -38.37845004
OS 52.01342404 -38.38307284
OS 52.0004802 -38.39046932
OS 51.98846092 -38.39971492
OS 51.98753636 -38.40063948
OS 51.98383812 -38.40526228
OS 51.97829076 -38.4117342
OS 51.97181884 -38.4209798
OS 51.96534692 -38.43299908
OS 51.958875 -38.44779204
OS 51.95332764 -38.46535868
OS 51.9496294 -38.485699
OS 51.8710418 -38.4718306
OS 51.8710418 -38.47090604
OS 51.87196636 -38.46813236
OS 51.87289092 -38.46443412
OS 51.87381548 -38.45888676
OS 51.8756646 -38.45241484
OS 51.87843828 -38.44501836
OS 51.88398564 -38.42745172
OS 51.89323124 -38.4071114
OS 51.90432596 -38.38677108
OS 51.91819436 -38.36735532
OS 51.935761 -38.34978868
OS 51.93668556 -38.34886412
OS 51.93853468 -38.34793956
OS 51.94130836 -38.34609044
OS 51.9450066 -38.34331676
OS 51.9496294 -38.33961852
OS 51.95610132 -38.33592028
OS 51.96257324 -38.33222204
OS 51.97089428 -38.32759924
OS 51.98938548 -38.32020276
OS 52.01065036 -38.31280628
OS 52.03561348 -38.30818348
OS 52.04855732 -38.30633436
OS 52.07167132 -38.30633436
OS 52.08184148 -38.30725892
OE
OB 56.14158444 -38.38492196 H
OS 55.95852156 -38.38492196
OS 55.95852156 -38.61328828
OS 56.13048972 -38.61328828
OS 56.13696164 -38.61236372
OS 56.14343356 -38.61236372
OS 56.15083004 -38.61143916
OS 56.16839668 -38.60959004
OS 56.18781244 -38.6058918
OS 56.2072282 -38.60034444
OS 56.22479484 -38.59294796
OS 56.23311588 -38.58832516
OS 56.2395878 -38.5827778
OS 56.24143692 -38.58092868
OS 56.24513516 -38.57723044
OS 56.25068252 -38.56983396
OS 56.25715444 -38.56058836
OS 56.26362636 -38.54856908
OS 56.26917372 -38.53377612
OS 56.27287196 -38.51713404
OS 56.27472108 -38.49771828
OS 56.27472108 -38.49679372
OS 56.27472108 -38.49586916
OS 56.27472108 -38.49124636
OS 56.27379652 -38.48292532
OS 56.2719474 -38.47367972
OS 56.27009828 -38.46350956
OS 56.26640004 -38.45149028
OS 56.26085268 -38.44039556
OS 56.25438076 -38.42930084
OS 56.2534562 -38.42837628
OS 56.25068252 -38.42467804
OS 56.24605972 -38.42005524
OS 56.24051236 -38.41358332
OS 56.23219132 -38.4071114
OS 56.22294572 -38.40156404
OS 56.21277556 -38.39601668
OS 56.20075628 -38.39139388
OS 56.19983172 -38.39139388
OS 56.19613348 -38.39046932
OS 56.19058612 -38.38954476
OS 56.18318964 -38.38769564
OS 56.17209492 -38.38677108
OS 56.15822652 -38.38584652
OS 56.14158444 -38.38492196
OE
OB 49.87491676 -38.43669732 H
OS 49.67336268 -38.72331092
OS 49.87491676 -38.72331092
OS 49.87491676 -38.43669732
OE
OB 54.06132444 -38.37105356 H
OS 54.05392796 -38.37105356
OS 54.04560692 -38.37290268
OS 54.0345122 -38.3747518
OS 54.02249292 -38.37845004
OS 54.00954908 -38.38307284
OS 53.9975298 -38.39046932
OS 53.98551052 -38.40063948
OS 53.98458596 -38.40156404
OS 53.98088772 -38.40526228
OS 53.97626492 -38.4117342
OS 53.97164212 -38.42005524
OS 53.96609476 -38.4302254
OS 53.96147196 -38.44224468
OS 53.95777372 -38.45518852
OS 53.95684916 -38.46998148
OS 53.95684916 -38.47090604
OS 53.95684916 -38.4718306
OS 53.95777372 -38.47737796
OS 53.95869828 -38.485699
OS 53.9605474 -38.49586916
OS 53.96424564 -38.50788844
OS 53.96886844 -38.51990772
OS 53.97626492 -38.53285156
OS 53.98551052 -38.54394628
OS 53.98643508 -38.54487084
OS 53.99105788 -38.54856908
OS 53.9975298 -38.55319188
OS 54.00585084 -38.55781468
OS 54.01694556 -38.56336204
OS 54.0298894 -38.56798484
OS 54.04468236 -38.57168308
OS 54.06132444 -38.57260764
OS 54.06317356 -38.57260764
OS 54.06872092 -38.57168308
OS 54.07704196 -38.57075852
OS 54.08813668 -38.5689094
OS 54.10015596 -38.56521116
OS 54.11217524 -38.56058836
OS 54.12511908 -38.55319188
OS 54.1362138 -38.54394628
OS 54.13713836 -38.54302172
OS 54.1408366 -38.53839892
OS 54.1454594 -38.53285156
OS 54.15100676 -38.52453052
OS 54.15655412 -38.51436036
OS 54.16117692 -38.50234108
OS 54.16487516 -38.48847268
OS 54.16579972 -38.47367972
OS 54.16579972 -38.47275516
OS 54.16579972 -38.4718306
OS 54.16579972 -38.46628324
OS 54.1639506 -38.4579622
OS 54.16210148 -38.44779204
OS 54.15840324 -38.43669732
OS 54.15285588 -38.42467804
OS 54.1454594 -38.41265876
OS 54.13528924 -38.40063948
OS 54.13436468 -38.39971492
OS 54.12974188 -38.39601668
OS 54.12326996 -38.39139388
OS 54.11494892 -38.38584652
OS 54.1038542 -38.38029916
OS 54.09183492 -38.37567636
OS 54.07704196 -38.37197812
OS 54.06132444 -38.37105356
OE
OB 54.05855076 -38.63640228 H
OS 54.0530034 -38.63640228
OS 54.04930516 -38.63732684
OS 54.039135 -38.6382514
OS 54.02619116 -38.64102508
OS 54.0113982 -38.64564788
OS 53.99660524 -38.6521198
OS 53.98088772 -38.6613654
OS 53.96701932 -38.67338468
OS 53.9651702 -38.6752338
OS 53.96147196 -38.6798566
OS 53.9559246 -38.68817764
OS 53.94945268 -38.6983478
OS 53.9420562 -38.7122162
OS 53.93650884 -38.72793372
OS 53.9328106 -38.74550036
OS 53.93096148 -38.76491612
OS 53.93096148 -38.76676524
OS 53.93096148 -38.77046348
OS 53.93188604 -38.7769354
OS 53.9328106 -38.78525644
OS 53.93465972 -38.7954266
OS 53.9374334 -38.80652132
OS 53.94113164 -38.81761604
OS 53.94575444 -38.82963532
OS 53.946679 -38.83055988
OS 53.94852812 -38.83518268
OS 53.95222636 -38.84073004
OS 53.95777372 -38.84720196
OS 53.96424564 -38.855523
OS 53.97256668 -38.86384404
OS 53.98181228 -38.87124052
OS 53.992907 -38.878637
OS 53.99475612 -38.87956156
OS 53.99845436 -38.88141068
OS 54.00492628 -38.88418436
OS 54.01324732 -38.88695804
OS 54.02341748 -38.88973172
OS 54.03543676 -38.8925054
OS 54.0483806 -38.89435452
OS 54.06132444 -38.89527908
OS 54.0668718 -38.89527908
OS 54.07057004 -38.89435452
OS 54.08166476 -38.89342996
OS 54.0946086 -38.89065628
OS 54.10940156 -38.88603348
OS 54.12511908 -38.88048612
OS 54.13991204 -38.87124052
OS 54.154705 -38.85922124
OS 54.15655412 -38.85737212
OS 54.16025236 -38.85274932
OS 54.16672428 -38.84442828
OS 54.1731962 -38.83425812
OS 54.17966812 -38.82131428
OS 54.18614004 -38.80559676
OS 54.18983828 -38.78710556
OS 54.1916874 -38.7676898
OS 54.1916874 -38.76676524
OS 54.1916874 -38.76491612
OS 54.1916874 -38.76214244
OS 54.19076284 -38.7584442
OS 54.18983828 -38.74827404
OS 54.1870646 -38.73440564
OS 54.1824418 -38.72053724
OS 54.17596988 -38.70481972
OS 54.16672428 -38.6891022
OS 54.15378044 -38.67430924
OS 54.15193132 -38.67246012
OS 54.14730852 -38.66876188
OS 54.13898748 -38.66228996
OS 54.12789276 -38.65489348
OS 54.11402436 -38.64842156
OS 54.09738228 -38.64194964
OS 54.07889108 -38.6382514
OS 54.05855076 -38.63640228
OE
OB 54.80559524 -38.37105356 H
OS 54.80004788 -38.37105356
OS 54.79634964 -38.37197812
OS 54.78617948 -38.37382724
OS 54.7741602 -38.37660092
OS 54.7602918 -38.38214828
OS 54.74549884 -38.39046932
OS 54.73810236 -38.39601668
OS 54.73070588 -38.40156404
OS 54.72423396 -38.40896052
OS 54.71776204 -38.41728156
OS 54.71776204 -38.41820612
OS 54.71591292 -38.42005524
OS 54.7140638 -38.42375348
OS 54.71129012 -38.42837628
OS 54.70851644 -38.43577276
OS 54.7048182 -38.4440938
OS 54.70204452 -38.45426396
OS 54.69834628 -38.46628324
OS 54.69464804 -38.48015164
OS 54.6909498 -38.49586916
OS 54.68725156 -38.5134358
OS 54.68447788 -38.53285156
OS 54.6817042 -38.555041
OS 54.67985508 -38.57907956
OS 54.67893052 -38.60496724
OS 54.67800596 -38.6336286
OS 54.67800596 -38.63547772
OS 54.67800596 -38.64010052
OS 54.67800596 -38.64842156
OS 54.67893052 -38.65951628
OS 54.67893052 -38.67153556
OS 54.67985508 -38.68632852
OS 54.68077964 -38.70204604
OS 54.68262876 -38.71868812
OS 54.68725156 -38.75474596
OS 54.69002524 -38.7723126
OS 54.69372348 -38.78895468
OS 54.69742172 -38.8046722
OS 54.70296908 -38.81946516
OS 54.70851644 -38.832409
OS 54.71498836 -38.84350372
OS 54.71498836 -38.84442828
OS 54.71683748 -38.84535284
OS 54.72146028 -38.85182476
OS 54.72978132 -38.8601458
OS 54.73995148 -38.8693914
OS 54.75381988 -38.878637
OS 54.7695374 -38.88695804
OS 54.78710404 -38.89342996
OS 54.79634964 -38.89435452
OS 54.8065198 -38.89527908
OS 54.81206716 -38.89527908
OS 54.8157654 -38.89435452
OS 54.825011 -38.8925054
OS 54.83795484 -38.88880716
OS 54.85182324 -38.88233524
OS 54.86754076 -38.87308964
OS 54.87493724 -38.86754228
OS 54.88233372 -38.8601458
OS 54.8897302 -38.85274932
OS 54.89712668 -38.84350372
OS 54.89712668 -38.84257916
OS 54.8989758 -38.84073004
OS 54.90082492 -38.83795636
OS 54.90267404 -38.83333356
OS 54.90637228 -38.82686164
OS 54.90914596 -38.8185406
OS 54.9128442 -38.809295
OS 54.91654244 -38.79820028
OS 54.91931612 -38.78433188
OS 54.92301436 -38.76953892
OS 54.9267126 -38.75197228
OS 54.92948628 -38.73348108
OS 54.9313354 -38.71129164
OS 54.93318452 -38.68817764
OS 54.93503364 -38.66228996
OS 54.93503364 -38.6336286
OS 54.93503364 -38.63270404
OS 54.93503364 -38.63177948
OS 54.93503364 -38.62715668
OS 54.93503364 -38.61883564
OS 54.93410908 -38.60774092
OS 54.93410908 -38.59572164
OS 54.93318452 -38.58092868
OS 54.93225996 -38.56521116
OS 54.93041084 -38.54764452
OS 54.92578804 -38.51251124
OS 54.92301436 -38.4949446
OS 54.91931612 -38.47830252
OS 54.91561788 -38.462585
OS 54.91007052 -38.44779204
OS 54.90452316 -38.4348482
OS 54.89805124 -38.42375348
OS 54.89805124 -38.42282892
OS 54.89620212 -38.42190436
OS 54.894353 -38.41913068
OS 54.89157932 -38.41543244
OS 54.88325828 -38.4071114
OS 54.87308812 -38.39694124
OS 54.85921972 -38.38769564
OS 54.8435022 -38.3793746
OS 54.83518116 -38.37567636
OS 54.82593556 -38.37290268
OS 54.8157654 -38.37197812
OS 54.80559524 -38.37105356
OE
OB 51.07499564 -38.37105356 H
OS 51.06944828 -38.37105356
OS 51.06575004 -38.37197812
OS 51.05557988 -38.37382724
OS 51.0435606 -38.37660092
OS 51.0296922 -38.38214828
OS 51.01489924 -38.39046932
OS 51.00750276 -38.39601668
OS 51.00010628 -38.40156404
OS 50.99363436 -38.40896052
OS 50.98716244 -38.41728156
OS 50.98716244 -38.41820612
OS 50.98531332 -38.42005524
OS 50.9834642 -38.42375348
OS 50.98069052 -38.42837628
OS 50.97791684 -38.43577276
OS 50.9742186 -38.4440938
OS 50.97144492 -38.45426396
OS 50.96774668 -38.46628324
OS 50.96404844 -38.48015164
OS 50.9603502 -38.49586916
OS 50.95665196 -38.5134358
OS 50.95387828 -38.53285156
OS 50.9511046 -38.555041
OS 50.94925548 -38.57907956
OS 50.94833092 -38.60496724
OS 50.94740636 -38.6336286
OS 50.94740636 -38.63547772
OS 50.94740636 -38.64010052
OS 50.94740636 -38.64842156
OS 50.94833092 -38.65951628
OS 50.94833092 -38.67153556
OS 50.94925548 -38.68632852
OS 50.95018004 -38.70204604
OS 50.95202916 -38.71868812
OS 50.95665196 -38.75474596
OS 50.95942564 -38.7723126
OS 50.96312388 -38.78895468
OS 50.96682212 -38.8046722
OS 50.97236948 -38.81946516
OS 50.97791684 -38.832409
OS 50.98438876 -38.84350372
OS 50.98438876 -38.84442828
OS 50.98623788 -38.84535284
OS 50.99086068 -38.85182476
OS 50.99918172 -38.8601458
OS 51.00935188 -38.8693914
OS 51.02322028 -38.878637
OS 51.0389378 -38.88695804
OS 51.05650444 -38.89342996
OS 51.06575004 -38.89435452
OS 51.0759202 -38.89527908
OS 51.08146756 -38.89527908
OS 51.0851658 -38.89435452
OS 51.0944114 -38.8925054
OS 51.10735524 -38.88880716
OS 51.12122364 -38.88233524
OS 51.13694116 -38.87308964
OS 51.14433764 -38.86754228
OS 51.15173412 -38.8601458
OS 51.1591306 -38.85274932
OS 51.16652708 -38.84350372
OS 51.16652708 -38.84257916
OS 51.1683762 -38.84073004
OS 51.17022532 -38.83795636
OS 51.17207444 -38.83333356
OS 51.17577268 -38.82686164
OS 51.17854636 -38.8185406
OS 51.1822446 -38.809295
OS 51.18594284 -38.79820028
OS 51.18871652 -38.78433188
OS 51.19241476 -38.76953892
OS 51.196113 -38.75197228
OS 51.19888668 -38.73348108
OS 51.2007358 -38.71129164
OS 51.20258492 -38.68817764
OS 51.20443404 -38.66228996
OS 51.20443404 -38.6336286
OS 51.20443404 -38.63270404
OS 51.20443404 -38.63177948
OS 51.20443404 -38.62715668
OS 51.20443404 -38.61883564
OS 51.20350948 -38.60774092
OS 51.20350948 -38.59572164
OS 51.20258492 -38.58092868
OS 51.20166036 -38.56521116
OS 51.19981124 -38.54764452
OS 51.19518844 -38.51251124
OS 51.19241476 -38.4949446
OS 51.18871652 -38.47830252
OS 51.18501828 -38.462585
OS 51.17947092 -38.44779204
OS 51.17392356 -38.4348482
OS 51.16745164 -38.42375348
OS 51.16745164 -38.42282892
OS 51.16560252 -38.42190436
OS 51.1637534 -38.41913068
OS 51.16097972 -38.41543244
OS 51.15265868 -38.4071114
OS 51.14248852 -38.39694124
OS 51.12862012 -38.38769564
OS 51.1129026 -38.3793746
OS 51.10458156 -38.37567636
OS 51.09533596 -38.37290268
OS 51.0851658 -38.37197812
OS 51.07499564 -38.37105356
OE
SE

### steps/pcb/layers/bottom_solder/features
UNITS=MM
#Layer_Color=16711935
#
#Feature symbol names
#
$0 r99.9998
$1 rect700.00114x1399.99974
$2 rect700.00114x1402.87502
$3 rect1150.00024x1849.99884
$4 rect1150.00024x1000.00054
$5 rect669.99866x719.99856
$6 rect519.99896x539.99892
$7 r6300.0001
$8 rect2400.00028x3400.00082
$9 rect399.9992x1825.00016
$10 rect900.00074x1549.99944
$11 rect699.9986x399.9992
$12 rect1399.99974x1749.99904
$13 rect699.9986x719.99856
$14 rect559.99888x519.99896
$15 rect519.99896x559.99888
$16 rect719.99856x699.9986
$17 rect719.99856x669.99866
$18 r1999.99854
$19 r2190.0007
$20 r5699.99876
$21 r1623.9998
$22 r1662.00074
$23 r1899.99874

#
#Feature attribute names
#
@0 .nomenclature
@1 .string
@2 .string_angle
@3 .geometry
@4 .pad_usage

#
#Feature attribute text strings
#
&0 SMD_RectX1050.0004Y1749.9990
&1 SMD_RectX1050.0004Y900.0007
&2 SMD_RectX569.9989Y619.9988
&3 SMD_RectX419.9992Y439.9991
&4 SMD_RoundX6200.0003Y6200.0003
&5 SMD_RectX2300.0005Y3300.0010
&6 SMD_RectX299.9994Y1725.0004
&7 SMD_RectX800.0009Y1449.9996
&8 SMD_RectX599.9988Y299.9994
&9 SMD_RectX1299.9999Y1649.9992
&10 SMD_RectX599.9988Y619.9988
&11 SMD_RectX459.9991Y419.9992
&12 SMD_RectX419.9992Y459.9991
&13 SMD_RectX619.9988Y599.9988
&14 SMD_RectX619.9988Y569.9989
&15 SMD_RoundX1000.0005Y1000.0005
&16 Pad_Simple_X2090.0009Y2090.0009H1090.0004C2106.0004
&17 Pad_Simple_X5299.9996Y5299.9996H2999.9991C4015.9991
&18 Pad_Simple_X1524.0000Y1524.0000H762.0000C1778.0000
&19 Pad_Simple_X1562.0009Y1562.0009H961.9996C1977.9996
&20 Pad_Simple_X0.0000Y0.0000H3700.0002C4716.0002
&21 Pad_Simple_X1799.9989Y1799.9989H1200.0001C2216.0001

#
#Layer features
#
L -9.5600012 -24.45999934 40.4400004 -24.45999934 0 P 0
L -9.5600012 -35.9599992 -9.5600012 -24.45999934 0 P 0
L -9.5600012 -35.9599992 28.439999 -35.9599992 0 P 0
L -9.5600012 -39.45999982 -9.5600012 -35.9599992 0 P 0
L -9.5600012 -39.45999982 28.439999 -39.45999982 0 P 0
L -9.5600012 -42.96000044 -9.5600012 -39.45999982 0 P 0
L -9.5600012 -42.96000044 28.439999 -42.96000044 0 P 0
L -10.0600002 -23.96000034 62.93999858 -23.96000034 0 P 0
L -10.0600002 -43.45999944 -10.0600002 -23.96000034 0 P 0
L -10.0600002 -43.45999944 62.93999858 -43.45999944 0 P 0
L 28.439999 -35.96000174 45.44000056 -35.9599992 0 P 0
L 28.439999 -39.45999982 28.439999 -35.9599992 0 P 0
L 28.439999 -39.46000236 45.44000056 -39.45999982 0 P 0
L 28.439999 -42.96000044 28.439999 -39.45999982 0 P 0
L 28.439999 -42.96000298 45.44000056 -42.96000044 0 P 0
L 40.4400004 -24.45999934 62.43999958 -24.45999934 0 P 0
L 40.4400004 -35.9599992 40.4400004 -24.45999934 0 P 0
L 45.44000056 -35.9599992 62.43999958 -35.9599992 0 P 0
L 45.44000056 -39.45999982 62.43999958 -39.45999982 0 P 0
L 45.44000056 -42.96000044 45.44000056 -35.9599992 0 P 0
L 45.44000056 -42.96000044 62.43999958 -42.96000044 0 P 0
L 62.43999958 -35.9599992 62.43999958 -24.45999934 0 P 0
L 62.43999958 -42.96000044 62.43999958 -35.9599992 0 P 0
L 62.93999858 -43.45999944 62.93999858 -23.96000034 0 P 0
P -2.38499904 43.5150006 18 P 0 0 ;3=15,4=0
P 0 0 19 P 0 0 ;3=16,4=0
P 0 40.64 19 P 0 0 ;3=16,4=0
P 2.0779994 43.3299997 19 P 0 0 ;3=16,4=0
P 4.39999882 2.00000108 0 P 0 0 ;3=20,4=0
P 4.39999882 2.00000108 7 P 0 0 ;3=4,4=0
P 4.39999882 38.599999 0 P 0 0 ;3=20,4=0
P 4.39999882 38.599999 7 P 0 0 ;3=4,4=0
P 4.8300005 7.63999996 23 P 0 0 ;3=21,4=0
P 4.8300005 7.63999996 21 P 0 0 ;3=18,4=0
P 4.8300005 12.71999996 23 P 0 0 ;3=21,4=0
P 4.8300005 12.71999996 21 P 0 0 ;3=18,4=0
P 4.8300005 17.79999996 23 P 0 0 ;3=21,4=0
P 4.8300005 17.79999996 21 P 0 0 ;3=18,4=0
P 4.8300005 33.03999996 23 P 0 0 ;3=21,4=0
P 4.8300005 33.03999996 21 P 0 0 ;3=18,4=0
P 5.1259994 43.3299997 19 P 0 0 ;3=16,4=0
P 8.1739994 43.3299997 19 P 0 0 ;3=16,4=0
P 11.2219994 43.3299997 19 P 0 0 ;3=16,4=0
P 13.9050014 18.0150008 5 P 0 0 ;3=2,4=0
P 13.9050014 19.16500104 5 P 0 0 ;3=2,4=0
P 14.2699994 43.3299997 19 P 0 0 ;3=16,4=0
P 14.86499948 18.0150008 5 P 0 0 ;3=2,4=0
P 14.86499948 19.16500104 5 P 0 0 ;3=2,4=0
P 14.86499948 20.21500148 15 P 0 0 ;3=12,4=0
P 14.86499948 20.87500016 15 P 0 0 ;3=12,4=0
P 15.86500002 20.21500148 6 P 0 0 ;3=3,4=0
P 15.86500002 20.89500012 6 P 0 0 ;3=3,4=0
P 15.91499992 7.38999792 12 P 0 0 ;3=9,4=0
P 15.91499992 9.7899982 12 P 0 0 ;3=9,4=0
P 15.91499992 12.39000062 12 P 0 0 ;3=9,4=0
P 16.29499916 22.29000114 14 P 0 0 ;3=11,4=0
P 16.31500166 18.04000202 11 P 0 0 ;3=8,4=0
P 16.31500166 18.49000112 11 P 0 0 ;3=8,4=0
P 16.31500166 18.94000276 11 P 0 0 ;3=8,4=0
P 16.31503976 18.43856612 2 P 0 0
P 16.41500146 16.99000158 10 P 0 0 ;3=7,4=0
P 16.65500352 14.7900009 13 P 0 0 ;3=10,4=0
P 16.95499784 20.21500148 17 P 0 0 ;3=14,4=0
P 16.95499784 21.17499956 17 P 0 0 ;3=14,4=0
P 16.95499784 22.29000114 14 P 0 0 ;3=11,4=0
P 17.1650025 16.85250122 9 P 0 0 ;3=6,4=0
P 17.57500168 14.7900009 13 P 0 0 ;3=10,4=0
P 17.7150014 7.38999792 12 P 0 0 ;3=9,4=0
P 17.7150014 9.7899982 12 P 0 0 ;3=9,4=0
P 17.7150014 12.39000062 12 P 0 0 ;3=9,4=0
P 17.915001 16.99000158 10 P 0 0 ;3=7,4=0
P 18.01495762 18.44000376 1 P 0 0
P 18.0150008 18.04000202 11 P 0 0 ;3=8,4=0
P 18.0150008 18.49000112 11 P 0 0 ;3=8,4=0
P 18.0150008 18.94000276 11 P 0 0 ;3=8,4=0
P 18.22000166 21.17499956 13 P 0 0 ;3=10,4=0
P 19.13999982 21.17499956 13 P 0 0 ;3=10,4=0
P 20.24000016 42.13999954 20 P 0 0 ;3=17,4=0
P 20.43999976 -1.26000002 20 P 0 0 ;3=17,4=0
P 20.76500038 16.85250122 8 P 0 0 ;3=5,4=0
P 22.41500216 7.7900022 12 P 0 0 ;3=9,4=0
P 22.41500216 10.29000228 12 P 0 0 ;3=9,4=0
P 22.95500362 12.29000082 13 P 0 0 ;3=10,4=0
P 23.87500178 12.29000082 13 P 0 0 ;3=10,4=0
P 24.21500364 7.7900022 12 P 0 0 ;3=9,4=0
P 24.21500364 10.29000228 12 P 0 0 ;3=9,4=0
P 26.06499994 16.85250122 8 P 0 0 ;3=5,4=0
P 32.24000156 7.63999996 3 P 0 0 ;3=0,4=0
P 35.24000064 7.63999996 3 P 0 0 ;3=0,4=0
P 35.50000012 -1.00000054 0 P 0 0 ;3=20,4=0
P 35.50000012 -1.00000054 7 P 0 0 ;3=4,4=0
P 36.20000126 40.10000108 0 P 0 0 ;3=20,4=0
P 36.20000126 40.10000108 7 P 0 0 ;3=4,4=0
P 37.8500005 7.63999996 23 P 0 0 ;3=21,4=0
P 37.8500005 7.63999996 22 P 0 0 ;3=19,4=0
P 37.8500005 9.94000044 13 P 0 0 ;3=10,4=0
P 37.8500005 12.71999996 23 P 0 0 ;3=21,4=0
P 37.8500005 12.71999996 22 P 0 0 ;3=19,4=0
P 37.8500005 17.79999996 23 P 0 0 ;3=21,4=0
P 37.8500005 17.79999996 22 P 0 0 ;3=19,4=0
P 37.8500005 22.87999996 22 P 0 0 ;3=19,4=0
P 37.8500005 22.87999996 23 P 0 0 ;3=21,4=0
P 37.8500005 33.03999996 22 P 0 0 ;3=19,4=0
P 37.8500005 33.03999996 23 P 0 0 ;3=21,4=0
P 38.76999866 9.94000044 13 P 0 0 ;3=10,4=0
P 39.78999916 14.51500018 4 P 0 0 ;3=1,4=0
P 39.78999916 15.96499982 4 P 0 0 ;3=1,4=0
P 40.0900011 7.63999996 16 P 0 0 ;3=13,4=0
P 40.0900011 8.55999812 16 P 0 0 ;3=13,4=0
P 40.64 0 19 P 0 0 ;3=16,4=0
P 40.64 40.64 19 P 0 0 ;3=16,4=0
P 40.67999992 20.33999996 19 P 0 0 ;3=16,4=0
P 43.11499886 43.5150006 18 P 0 0 ;3=15,4=0
P 43.18999998 -2.80999946 18 P 0 0 ;3=15,4=0
S P 0
OB -2.46623586 -38.48662356 I
OS -2.45236746 -38.48754812
OS -2.4375745 -38.48939724
OS -2.42185698 -38.49309548
OS -2.4052149 -38.49679372
OS -2.38949738 -38.50234108
OS -2.38857282 -38.50234108
OS -2.38764826 -38.50326564
OS -2.38302546 -38.50511476
OS -2.37562898 -38.508813
OS -2.36638338 -38.5134358
OS -2.35621322 -38.51990772
OS -2.34604306 -38.5273042
OS -2.33679746 -38.53562524
OS -2.32847642 -38.54487084
OS -2.32755186 -38.5457954
OS -2.32570274 -38.54949364
OS -2.3220045 -38.55596556
OS -2.3173817 -38.56336204
OS -2.3127589 -38.57445676
OS -2.3081361 -38.58647604
OS -2.30443786 -38.60034444
OS -2.30073962 -38.61606196
OS -2.3774781 -38.62623212
OS -2.3774781 -38.624383
OS -2.37840266 -38.62068476
OS -2.38025178 -38.61421284
OS -2.38302546 -38.6058918
OS -2.38764826 -38.59757076
OS -2.39319562 -38.58832516
OS -2.39966754 -38.57907956
OS -2.40891314 -38.57075852
OS -2.4098377 -38.56983396
OS -2.41353594 -38.56798484
OS -2.4190833 -38.5642866
OS -2.42740434 -38.56058836
OS -2.43664994 -38.55689012
OS -2.44866922 -38.55319188
OS -2.46346218 -38.55134276
OS -2.4791797 -38.5504182
OS -2.4884253 -38.5504182
OS -2.4976709 -38.55134276
OS -2.50969018 -38.55226732
OS -2.52170946 -38.555041
OS -2.5346533 -38.55781468
OS -2.54667258 -38.56243748
OS -2.55684274 -38.5689094
OS -2.5577673 -38.56983396
OS -2.56054098 -38.57168308
OS -2.56423922 -38.57538132
OS -2.56793746 -38.58092868
OS -2.57256026 -38.58647604
OS -2.5762585 -38.59387252
OS -2.57903218 -38.60219356
OS -2.57995674 -38.6105146
OS -2.57995674 -38.61143916
OS -2.57995674 -38.61328828
OS -2.57903218 -38.61606196
OS -2.57903218 -38.6197602
OS -2.5762585 -38.6290058
OS -2.57071114 -38.6382514
OS -2.56978658 -38.63917596
OS -2.56886202 -38.64010052
OS -2.5670129 -38.6428742
OS -2.56331466 -38.64564788
OS -2.55961642 -38.64842156
OS -2.55406906 -38.6521198
OS -2.54759714 -38.65489348
OS -2.54020066 -38.65859172
OS -2.5392761 -38.65859172
OS -2.53742698 -38.65951628
OS -2.53372874 -38.66044084
OS -2.52725682 -38.66321452
OS -2.51801122 -38.6659882
OS -2.50599194 -38.66876188
OS -2.49859546 -38.67153556
OS -2.49027442 -38.67338468
OS -2.48102882 -38.67615836
OS -2.47085866 -38.67893204
OS -2.4699341 -38.67893204
OS -2.46716042 -38.6798566
OS -2.46253762 -38.68078116
OS -2.45699026 -38.68263028
OS -2.45051834 -38.6844794
OS -2.4421973 -38.68632852
OS -2.42463066 -38.69187588
OS -2.4052149 -38.69742324
OS -2.38579914 -38.70389516
OS -2.3682325 -38.71036708
OS -2.36083602 -38.71314076
OS -2.3543641 -38.71591444
OS -2.35251498 -38.716839
OS -2.34881674 -38.71868812
OS -2.34326938 -38.7214618
OS -2.33494834 -38.7260846
OS -2.3266273 -38.73163196
OS -2.31830626 -38.73902844
OS -2.30998522 -38.74734948
OS -2.30258874 -38.75659508
OS -2.30166418 -38.75751964
OS -2.29981506 -38.76121788
OS -2.29611682 -38.76676524
OS -2.29241858 -38.77508628
OS -2.2896449 -38.78525644
OS -2.28594666 -38.79635116
OS -2.28409754 -38.809295
OS -2.28317298 -38.82408796
OS -2.28317298 -38.82593708
OS -2.28317298 -38.83055988
OS -2.28409754 -38.83795636
OS -2.28594666 -38.84812652
OS -2.28872034 -38.85922124
OS -2.29334314 -38.87124052
OS -2.2988905 -38.88510892
OS -2.30628698 -38.89805276
OS -2.30721154 -38.89990188
OS -2.31090978 -38.90360012
OS -2.31553258 -38.91007204
OS -2.32292906 -38.91746852
OS -2.33309922 -38.92578956
OS -2.34419394 -38.93503516
OS -2.35713778 -38.9433562
OS -2.3728553 -38.95167724
OS -2.37377986 -38.95167724
OS -2.37470442 -38.9526018
OS -2.38025178 -38.95445092
OS -2.38949738 -38.9572246
OS -2.40151666 -38.96092284
OS -2.41630962 -38.96462108
OS -2.4329517 -38.96739476
OS -2.45051834 -38.96924388
OS -2.47085866 -38.97016844
OS -2.4791797 -38.97016844
OS -2.48565162 -38.96924388
OS -2.4930481 -38.96924388
OS -2.5022937 -38.96831932
OS -2.5115393 -38.96739476
OS -2.52170946 -38.96554564
OS -2.5438989 -38.96092284
OS -2.5670129 -38.95445092
OS -2.58920234 -38.94520532
OS -2.5993725 -38.93965796
OS -2.6086181 -38.93318604
OS -2.60954266 -38.93226148
OS -2.61046722 -38.93133692
OS -2.61601458 -38.92578956
OS -2.62433562 -38.91746852
OS -2.63358122 -38.90452468
OS -2.64375138 -38.88880716
OS -2.65392154 -38.87031596
OS -2.66224258 -38.84720196
OS -2.6687145 -38.82131428
OS -2.59105146 -38.809295
OS -2.59105146 -38.81021956
OS -2.59105146 -38.81114412
OS -2.58920234 -38.81669148
OS -2.58735322 -38.82593708
OS -2.58365498 -38.83610724
OS -2.57903218 -38.84720196
OS -2.57348482 -38.85922124
OS -2.56516378 -38.87124052
OS -2.55499362 -38.88141068
OS -2.5531445 -38.88233524
OS -2.54944626 -38.88510892
OS -2.54204978 -38.88880716
OS -2.53280418 -38.89342996
OS -2.5207849 -38.89805276
OS -2.5069165 -38.901751
OS -2.49027442 -38.90452468
OS -2.47085866 -38.90544924
OS -2.46161306 -38.90544924
OS -2.45236746 -38.90452468
OS -2.44034818 -38.90267556
OS -2.42740434 -38.89990188
OS -2.41353594 -38.89620364
OS -2.40151666 -38.89158084
OS -2.39042194 -38.88418436
OS -2.38949738 -38.8832598
OS -2.38579914 -38.88048612
OS -2.3821009 -38.87586332
OS -2.37655354 -38.8693914
OS -2.37193074 -38.86199492
OS -2.36730794 -38.85274932
OS -2.36453426 -38.84350372
OS -2.3636097 -38.832409
OS -2.3636097 -38.83148444
OS -2.3636097 -38.8277862
OS -2.36453426 -38.8231634
OS -2.36638338 -38.81669148
OS -2.36915706 -38.81021956
OS -2.37377986 -38.80374764
OS -2.37932722 -38.79635116
OS -2.38764826 -38.7908038
OS -2.38857282 -38.78987924
OS -2.3913465 -38.78895468
OS -2.3959693 -38.786181
OS -2.40336578 -38.78340732
OS -2.4144605 -38.77970908
OS -2.42093242 -38.7769354
OS -2.4283289 -38.77508628
OS -2.43664994 -38.7723126
OS -2.44589554 -38.76953892
OS -2.4560657 -38.76676524
OS -2.46808498 -38.76399156
OS -2.46900954 -38.76399156
OS -2.47178322 -38.763067
OS -2.47640602 -38.76214244
OS -2.48195338 -38.76029332
OS -2.48934986 -38.7584442
OS -2.4976709 -38.75567052
OS -2.51523754 -38.75104772
OS -2.53557786 -38.7445758
OS -2.55499362 -38.73902844
OS -2.57348482 -38.73255652
OS -2.58180586 -38.72885828
OS -2.58827778 -38.7260846
OS -2.5901269 -38.72516004
OS -2.59382514 -38.72331092
OS -2.5993725 -38.71961268
OS -2.60676898 -38.71498988
OS -2.61509002 -38.70851796
OS -2.62341106 -38.70112148
OS -2.6317321 -38.69280044
OS -2.63912858 -38.68263028
OS -2.64005314 -38.68170572
OS -2.64190226 -38.67800748
OS -2.64467594 -38.67153556
OS -2.64744962 -38.66413908
OS -2.6502233 -38.65489348
OS -2.65299698 -38.64379876
OS -2.6548461 -38.63270404
OS -2.65577066 -38.6197602
OS -2.65577066 -38.61791108
OS -2.65577066 -38.61421284
OS -2.6548461 -38.60866548
OS -2.65392154 -38.60034444
OS -2.65207242 -38.5920234
OS -2.6502233 -38.58185324
OS -2.64652506 -38.57260764
OS -2.64190226 -38.56243748
OS -2.6409777 -38.56151292
OS -2.63912858 -38.55781468
OS -2.6363549 -38.55319188
OS -2.6317321 -38.54671996
OS -2.62618474 -38.54024804
OS -2.61971282 -38.531927
OS -2.61231634 -38.52453052
OS -2.60307074 -38.5180586
OS -2.60214618 -38.51713404
OS -2.5993725 -38.51620948
OS -2.59567426 -38.5134358
OS -2.5901269 -38.51066212
OS -2.58273042 -38.50696388
OS -2.57440938 -38.50326564
OS -2.56423922 -38.4995674
OS -2.5531445 -38.49586916
OS -2.55129538 -38.4949446
OS -2.54759714 -38.49402004
OS -2.54112522 -38.49217092
OS -2.53280418 -38.4903218
OS -2.52263402 -38.48847268
OS -2.5115393 -38.48754812
OS -2.49859546 -38.485699
OS -2.47640602 -38.485699
OS -2.46623586 -38.48662356
OE
OB -1.98638922 -38.48662356 I
OS -1.97806818 -38.48754812
OS -1.96882258 -38.48939724
OS -1.95865242 -38.49124636
OS -1.94663314 -38.49309548
OS -1.92167002 -38.50141652
OS -1.90872618 -38.50603932
OS -1.89578234 -38.51251124
OS -1.8828385 -38.51898316
OS -1.86989466 -38.52822876
OS -1.85787538 -38.53747436
OS -1.8458561 -38.54856908
OS -1.84493154 -38.54949364
OS -1.84308242 -38.55134276
OS -1.84030874 -38.555041
OS -1.8366105 -38.5596638
OS -1.8319877 -38.56613572
OS -1.82644034 -38.57445676
OS -1.82089298 -38.58370236
OS -1.81534562 -38.59387252
OS -1.80979826 -38.60496724
OS -1.8042509 -38.61883564
OS -1.79870354 -38.63270404
OS -1.79408074 -38.64842156
OS -1.7903825 -38.66506364
OS -1.78760882 -38.68263028
OS -1.7857597 -38.70112148
OS -1.78483514 -38.7214618
OS -1.78483514 -38.72238636
OS -1.78483514 -38.72516004
OS -1.78483514 -38.72978284
OS -1.78483514 -38.73625476
OS -1.7857597 -38.74365124
OS -1.78668426 -38.75289684
OS -1.78668426 -38.76214244
OS -1.78853338 -38.7723126
OS -1.79130706 -38.7954266
OS -1.79685442 -38.8185406
OS -1.80332634 -38.8416546
OS -1.81257194 -38.86291948
OS -1.81257194 -38.86384404
OS -1.8134965 -38.8647686
OS -1.81534562 -38.86754228
OS -1.81719474 -38.87124052
OS -1.82366666 -38.88048612
OS -1.8319877 -38.89158084
OS -1.84308242 -38.90452468
OS -1.85695082 -38.91746852
OS -1.87266834 -38.93041236
OS -1.89115954 -38.94243164
OS -1.8920841 -38.94243164
OS -1.89300866 -38.9433562
OS -1.89578234 -38.94520532
OS -1.90040514 -38.94705444
OS -1.90502794 -38.94890356
OS -1.9105753 -38.95075268
OS -1.9244437 -38.95630004
OS -1.94016122 -38.96092284
OS -1.95957698 -38.96554564
OS -1.9799173 -38.96924388
OS -2.00210674 -38.97016844
OS -2.01135234 -38.97016844
OS -2.01874882 -38.96924388
OS -2.02706986 -38.96831932
OS -2.03631546 -38.9664702
OS -2.04741018 -38.96462108
OS -2.0585049 -38.96277196
OS -2.08346802 -38.95537548
OS -2.09733642 -38.94982812
OS -2.11028026 -38.94428076
OS -2.1232241 -38.93688428
OS -2.13616794 -38.92856324
OS -2.14818722 -38.91931764
OS -2.1602065 -38.90822292
OS -2.16113106 -38.90729836
OS -2.16298018 -38.90544924
OS -2.16575386 -38.901751
OS -2.1694521 -38.89620364
OS -2.1740749 -38.88973172
OS -2.1786977 -38.88233524
OS -2.18424506 -38.87308964
OS -2.18979242 -38.86199492
OS -2.19533978 -38.84997564
OS -2.20088714 -38.83610724
OS -2.20550994 -38.82131428
OS -2.21013274 -38.80559676
OS -2.21383098 -38.78803012
OS -2.21660466 -38.76953892
OS -2.21845378 -38.7491986
OS -2.21937834 -38.72793372
OS -2.21937834 -38.7260846
OS -2.21937834 -38.72238636
OS -2.21845378 -38.71591444
OS -2.21845378 -38.70666884
OS -2.21752922 -38.69649868
OS -2.2156801 -38.68355484
OS -2.21383098 -38.670611
OS -2.21013274 -38.65581804
OS -2.2064345 -38.64102508
OS -2.2018117 -38.62530756
OS -2.19626434 -38.60866548
OS -2.18886786 -38.59294796
OS -2.18147138 -38.578155
OS -2.17130122 -38.56336204
OS -2.16113106 -38.54949364
OS -2.14818722 -38.53747436
OS -2.14726266 -38.5365498
OS -2.14541354 -38.53562524
OS -2.1417153 -38.53285156
OS -2.1370925 -38.52915332
OS -2.13154514 -38.52545508
OS -2.12414866 -38.52083228
OS -2.11675218 -38.51620948
OS -2.10750658 -38.51158668
OS -2.09733642 -38.50696388
OS -2.0862417 -38.50234108
OS -2.06127858 -38.49402004
OS -2.03261722 -38.48754812
OS -2.01782426 -38.48662356
OS -2.00210674 -38.485699
OS -1.99286114 -38.485699
OS -1.98638922 -38.48662356
OE
OB -3.38339938 -38.48662356 I
OS -3.37692746 -38.48662356
OS -3.37045554 -38.48754812
OS -3.35473802 -38.4903218
OS -3.33809594 -38.4949446
OS -3.3205293 -38.50234108
OS -3.30296266 -38.51158668
OS -3.2881697 -38.52453052
OS -3.28632058 -38.52637964
OS -3.28262234 -38.531927
OS -3.27615042 -38.54024804
OS -3.27337674 -38.54671996
OS -3.2696785 -38.55319188
OS -3.26598026 -38.56151292
OS -3.26320658 -38.56983396
OS -3.25950834 -38.57907956
OS -3.25673466 -38.59017428
OS -3.25488554 -38.601269
OS -3.25303642 -38.61421284
OS -3.2511873 -38.62715668
OS -3.2511873 -38.64194964
OS -3.2511873 -38.95999828
OS -3.3297749 -38.95999828
OS -3.3297749 -38.66876188
OS -3.3297749 -38.66783732
OS -3.3297749 -38.66691276
OS -3.3297749 -38.6613654
OS -3.3297749 -38.65304436
OS -3.33069946 -38.6428742
OS -3.33162402 -38.63177948
OS -3.33254858 -38.62068476
OS -3.3343977 -38.60959004
OS -3.33717138 -38.601269
OS -3.33717138 -38.60034444
OS -3.3390205 -38.59757076
OS -3.34086962 -38.59387252
OS -3.3436433 -38.58924972
OS -3.34734154 -38.58370236
OS -3.35196434 -38.578155
OS -3.3575117 -38.57260764
OS -3.36490818 -38.56706028
OS -3.36583274 -38.56613572
OS -3.36860642 -38.56521116
OS -3.37230466 -38.56336204
OS -3.37877658 -38.56058836
OS -3.3852485 -38.55781468
OS -3.39356954 -38.55596556
OS -3.40189058 -38.555041
OS -3.41206074 -38.55411644
OS -3.41668354 -38.55411644
OS -3.42038178 -38.555041
OS -3.42962738 -38.55596556
OS -3.4407221 -38.55781468
OS -3.45366594 -38.56243748
OS -3.46753434 -38.56798484
OS -3.48140274 -38.57630588
OS -3.49434658 -38.5874006
OS -3.49527114 -38.58924972
OS -3.49896938 -38.59387252
OS -3.50451674 -38.601269
OS -3.5100641 -38.61236372
OS -3.51653602 -38.62715668
OS -3.52115882 -38.64472332
OS -3.52485706 -38.6659882
OS -3.52670618 -38.69095132
OS -3.52670618 -38.95999828
OS -3.60529378 -38.95999828
OS -3.60529378 -38.65951628
OS -3.60529378 -38.65859172
OS -3.60529378 -38.6567426
OS -3.60529378 -38.65489348
OS -3.60529378 -38.65119524
OS -3.60621834 -38.64102508
OS -3.60806746 -38.62993036
OS -3.60991658 -38.61698652
OS -3.61361482 -38.60404268
OS -3.61823762 -38.5920234
OS -3.62470954 -38.58092868
OS -3.6256341 -38.58000412
OS -3.62840778 -38.57630588
OS -3.63303058 -38.57260764
OS -3.6395025 -38.56706028
OS -3.64782354 -38.56243748
OS -3.65891826 -38.55781468
OS -3.6718621 -38.555041
OS -3.68757962 -38.55411644
OS -3.69312698 -38.55411644
OS -3.6995989 -38.555041
OS -3.70699538 -38.55596556
OS -3.71624098 -38.55873924
OS -3.7273357 -38.56151292
OS -3.73750586 -38.56613572
OS -3.74860058 -38.57168308
OS -3.74952514 -38.57260764
OS -3.75322338 -38.57538132
OS -3.75784618 -38.57907956
OS -3.7643181 -38.58462692
OS -3.77079002 -38.5920234
OS -3.77726194 -38.601269
OS -3.78373386 -38.61143916
OS -3.78928122 -38.62345844
OS -3.79020578 -38.62530756
OS -3.79113034 -38.62993036
OS -3.79297946 -38.63732684
OS -3.79575314 -38.647497
OS -3.79852682 -38.6613654
OS -3.80037594 -38.67800748
OS -3.8013005 -38.69742324
OS -3.80222506 -38.71961268
OS -3.80222506 -38.95999828
OS -3.88081266 -38.95999828
OS -3.88081266 -38.49586916
OS -3.8105461 -38.49586916
OS -3.8105461 -38.56243748
OS -3.80962154 -38.56058836
OS -3.80684786 -38.55689012
OS -3.8013005 -38.5504182
OS -3.79482858 -38.54302172
OS -3.78650754 -38.53377612
OS -3.77633738 -38.52453052
OS -3.76524266 -38.51528492
OS -3.75229882 -38.50696388
OS -3.7504497 -38.50603932
OS -3.7458269 -38.50326564
OS -3.73843042 -38.50049196
OS -3.72826026 -38.49586916
OS -3.71624098 -38.49217092
OS -3.70237258 -38.48939724
OS -3.68665506 -38.48662356
OS -3.67001298 -38.485699
OS -3.66169194 -38.485699
OS -3.65152178 -38.48662356
OS -3.64042706 -38.48847268
OS -3.62655866 -38.49124636
OS -3.61269026 -38.4949446
OS -3.59882186 -38.50049196
OS -3.58587802 -38.50788844
OS -3.5840289 -38.508813
OS -3.58033066 -38.51158668
OS -3.5747833 -38.51620948
OS -3.56738682 -38.52360596
OS -3.55999034 -38.531927
OS -3.5516693 -38.54209716
OS -3.54427282 -38.55411644
OS -3.53872546 -38.56798484
OS -3.5378009 -38.56706028
OS -3.53595178 -38.5642866
OS -3.5331781 -38.56058836
OS -3.5285553 -38.555041
OS -3.52300794 -38.54856908
OS -3.51653602 -38.54209716
OS -3.50913954 -38.53470068
OS -3.49989394 -38.52637964
OS -3.48972378 -38.51898316
OS -3.47955362 -38.51158668
OS -3.46753434 -38.50511476
OS -3.4545905 -38.49864284
OS -3.4407221 -38.49309548
OS -3.42592914 -38.48939724
OS -3.41113618 -38.48662356
OS -3.3944941 -38.485699
OS -3.38802218 -38.485699
OS -3.38339938 -38.48662356
OE
OB -2.6872057 -39.1375138 I
OS -3.20773298 -39.1375138
OS -3.20773298 -39.08111564
OS -2.6872057 -39.08111564
OS -2.6872057 -39.1375138
OE
OB -1.12100106 -38.95999828 I
OS -1.1940413 -38.95999828
OS -1.1940413 -38.901751
OS -1.19496586 -38.90267556
OS -1.19589042 -38.90452468
OS -1.1986641 -38.90822292
OS -1.20236234 -38.91284572
OS -1.20698514 -38.91746852
OS -1.2125325 -38.92301588
OS -1.21900442 -38.9294878
OS -1.22732546 -38.93595972
OS -1.2356465 -38.94243164
OS -1.2448921 -38.94890356
OS -1.25598682 -38.95445092
OS -1.2680061 -38.95907372
OS -1.28002538 -38.96369652
OS -1.29389378 -38.96739476
OS -1.30868674 -38.96924388
OS -1.32440426 -38.97016844
OS -1.32995162 -38.97016844
OS -1.33364986 -38.96924388
OS -1.34474458 -38.96831932
OS -1.35768842 -38.9664702
OS -1.37340594 -38.96277196
OS -1.39097258 -38.9572246
OS -1.40853922 -38.94982812
OS -1.42610586 -38.93965796
OS -1.42703042 -38.93965796
OS -1.42795498 -38.93780884
OS -1.43350234 -38.9341106
OS -1.44182338 -38.92671412
OS -1.45199354 -38.91746852
OS -1.46401282 -38.90544924
OS -1.4760321 -38.89065628
OS -1.48805138 -38.8740142
OS -1.49822154 -38.85459844
OS -1.49822154 -38.85367388
OS -1.4991461 -38.85182476
OS -1.50007066 -38.84905108
OS -1.50191978 -38.84535284
OS -1.5037689 -38.83980548
OS -1.50654258 -38.83333356
OS -1.5083917 -38.82686164
OS -1.51024082 -38.8185406
OS -1.51486362 -38.8000494
OS -1.51948642 -38.77878452
OS -1.5222601 -38.75474596
OS -1.52318466 -38.72885828
OS -1.52318466 -38.72793372
OS -1.52318466 -38.7260846
OS -1.52318466 -38.72238636
OS -1.52318466 -38.716839
OS -1.5222601 -38.71129164
OS -1.5222601 -38.70389516
OS -1.52041098 -38.68725308
OS -1.5176373 -38.66783732
OS -1.5130145 -38.64657244
OS -1.50746714 -38.624383
OS -1.50007066 -38.60311812
OS -1.50007066 -38.60219356
OS -1.4991461 -38.60034444
OS -1.49729698 -38.59757076
OS -1.49544786 -38.59387252
OS -1.4899005 -38.58370236
OS -1.48250402 -38.57075852
OS -1.47325842 -38.55689012
OS -1.46123914 -38.54302172
OS -1.44737074 -38.52822876
OS -1.43072866 -38.51620948
OS -1.4298041 -38.51620948
OS -1.42887954 -38.51528492
OS -1.42610586 -38.5134358
OS -1.42240762 -38.51158668
OS -1.41316202 -38.50696388
OS -1.40021818 -38.50049196
OS -1.38542522 -38.4949446
OS -1.36785858 -38.4903218
OS -1.34844282 -38.48662356
OS -1.3281025 -38.485699
OS -1.32070602 -38.485699
OS -1.31330954 -38.48662356
OS -1.30313938 -38.48754812
OS -1.2911201 -38.4903218
OS -1.27817626 -38.49309548
OS -1.26523242 -38.49771828
OS -1.25321314 -38.5041902
OS -1.25136402 -38.50511476
OS -1.24766578 -38.50696388
OS -1.24211842 -38.51158668
OS -1.23472194 -38.51620948
OS -1.22547634 -38.5226814
OS -1.2171553 -38.53100244
OS -1.2079097 -38.53932348
OS -1.19958866 -38.54949364
OS -1.19958866 -38.32020276
OS -1.12100106 -38.32020276
OS -1.12100106 -38.95999828
OE
OB -0.31386018 -38.48662356 I
OS -0.30369002 -38.48847268
OS -0.29167074 -38.49217092
OS -0.2787269 -38.49679372
OS -0.26393394 -38.50326564
OS -0.24821642 -38.51158668
OS -0.27687778 -38.58370236
OS -0.27780234 -38.5827778
OS -0.28150058 -38.58092868
OS -0.28704794 -38.578155
OS -0.29444442 -38.57538132
OS -0.30276546 -38.57260764
OS -0.31293562 -38.56983396
OS -0.32310578 -38.56798484
OS -0.33327594 -38.56706028
OS -0.33789874 -38.56706028
OS -0.34252154 -38.56798484
OS -0.34899346 -38.5689094
OS -0.35546538 -38.57075852
OS -0.36378642 -38.5735322
OS -0.37210746 -38.57723044
OS -0.37950394 -38.5827778
OS -0.3804285 -38.58370236
OS -0.38320218 -38.58555148
OS -0.38597586 -38.58924972
OS -0.39059866 -38.59387252
OS -0.39522146 -38.60034444
OS -0.39984426 -38.60774092
OS -0.40446706 -38.61606196
OS -0.4081653 -38.62623212
OS -0.40908986 -38.62808124
OS -0.41001442 -38.6336286
OS -0.41186354 -38.64194964
OS -0.41463722 -38.65304436
OS -0.4174109 -38.66691276
OS -0.41926002 -38.68263028
OS -0.42018458 -38.69927236
OS -0.42110914 -38.71776356
OS -0.42110914 -38.95999828
OS -0.49969674 -38.95999828
OS -0.49969674 -38.49586916
OS -0.42850562 -38.49586916
OS -0.42850562 -38.56613572
OS -0.42758106 -38.56521116
OS -0.42388282 -38.55873924
OS -0.41926002 -38.5504182
OS -0.41186354 -38.54024804
OS -0.40446706 -38.53007788
OS -0.39614602 -38.51898316
OS -0.38782498 -38.50973756
OS -0.37950394 -38.50234108
OS -0.37857938 -38.50141652
OS -0.3758057 -38.4995674
OS -0.37025834 -38.49679372
OS -0.36471098 -38.49402004
OS -0.3573145 -38.49124636
OS -0.3480689 -38.48847268
OS -0.3388233 -38.48662356
OS -0.32865314 -38.485699
OS -0.32218122 -38.485699
OS -0.31386018 -38.48662356
OE
OB -0.1307973 -38.42745172 I
OS -0.15206218 -38.54671996
OS -0.20106386 -38.54671996
OS -0.22047962 -38.42745172
OS -0.22047962 -38.32020276
OS -0.1307973 -38.32020276
OS -0.1307973 -38.42745172
OE
OB -1.61564066 -38.95999828 I
OS -1.69422826 -38.95999828
OS -1.69422826 -38.32020276
OS -1.61564066 -38.32020276
OS -1.61564066 -38.95999828
OE
OB -0.79093314 -38.48662356 I
OS -0.78353666 -38.48754812
OS -0.77429106 -38.48939724
OS -0.7641209 -38.49124636
OS -0.75210162 -38.49402004
OS -0.7410069 -38.49679372
OS -0.72806306 -38.50141652
OS -0.71604378 -38.50603932
OS -0.70309994 -38.51251124
OS -0.6901561 -38.51990772
OS -0.67721226 -38.52822876
OS -0.66519298 -38.53839892
OS -0.65409826 -38.54949364
OS -0.6531737 -38.5504182
OS -0.65132458 -38.55226732
OS -0.6485509 -38.55596556
OS -0.64485266 -38.56151292
OS -0.64022986 -38.56798484
OS -0.63560706 -38.57538132
OS -0.6300597 -38.58462692
OS -0.62451234 -38.59572164
OS -0.61896498 -38.60774092
OS -0.61341762 -38.62068476
OS -0.60879482 -38.63547772
OS -0.60417202 -38.65119524
OS -0.60047378 -38.66876188
OS -0.5977001 -38.68725308
OS -0.59585098 -38.70666884
OS -0.59492642 -38.72793372
OS -0.59492642 -38.72885828
OS -0.59492642 -38.73255652
OS -0.59492642 -38.73902844
OS -0.59585098 -38.74827404
OS -0.94256098 -38.74827404
OS -0.94256098 -38.7491986
OS -0.94256098 -38.75197228
OS -0.94163642 -38.75567052
OS -0.94163642 -38.76121788
OS -0.94071186 -38.7676898
OS -0.93886274 -38.77508628
OS -0.93608906 -38.79172836
OS -0.9305417 -38.81021956
OS -0.92314522 -38.83055988
OS -0.91297506 -38.84905108
OS -0.90003122 -38.86569316
OS -0.89910666 -38.86569316
OS -0.8981821 -38.86754228
OS -0.89263474 -38.87216508
OS -0.8843137 -38.878637
OS -0.87321898 -38.88510892
OS -0.85842602 -38.8925054
OS -0.84178394 -38.89897732
OS -0.82329274 -38.90360012
OS -0.81312258 -38.90452468
OS -0.80202786 -38.90544924
OS -0.79463138 -38.90544924
OS -0.78631034 -38.90452468
OS -0.77614018 -38.90267556
OS -0.76504546 -38.89990188
OS -0.75210162 -38.89620364
OS -0.74008234 -38.89065628
OS -0.72806306 -38.8832598
OS -0.7271385 -38.88233524
OS -0.7225157 -38.878637
OS -0.71696834 -38.87308964
OS -0.71049642 -38.86569316
OS -0.70309994 -38.855523
OS -0.6947789 -38.84257916
OS -0.68645786 -38.8277862
OS -0.67906138 -38.81021956
OS -0.5977001 -38.82038972
OS -0.5977001 -38.82131428
OS -0.59862466 -38.8231634
OS -0.59954922 -38.82686164
OS -0.60139834 -38.832409
OS -0.60417202 -38.83795636
OS -0.6069457 -38.84535284
OS -0.61434218 -38.86107036
OS -0.62358778 -38.878637
OS -0.63653162 -38.8971282
OS -0.65132458 -38.91469484
OS -0.66981578 -38.93133692
OS -0.67074034 -38.93133692
OS -0.67258946 -38.93318604
OS -0.67536314 -38.93503516
OS -0.67906138 -38.93780884
OS -0.68460874 -38.94058252
OS -0.6901561 -38.9433562
OS -0.69755258 -38.94705444
OS -0.70587362 -38.95075268
OS -0.71511922 -38.95445092
OS -0.72436482 -38.95814916
OS -0.74747882 -38.96369652
OS -0.7733665 -38.96831932
OS -0.80202786 -38.97016844
OS -0.81219802 -38.97016844
OS -0.81866994 -38.96924388
OS -0.82699098 -38.96831932
OS -0.83716114 -38.9664702
OS -0.84825586 -38.96462108
OS -0.86027514 -38.96277196
OS -0.88616282 -38.95537548
OS -0.90003122 -38.94982812
OS -0.91297506 -38.94428076
OS -0.92684346 -38.93688428
OS -0.9397873 -38.92856324
OS -0.95180658 -38.91931764
OS -0.96382586 -38.90822292
OS -0.96475042 -38.90729836
OS -0.96659954 -38.90544924
OS -0.96937322 -38.901751
OS -0.97307146 -38.89620364
OS -0.97769426 -38.88973172
OS -0.98231706 -38.88233524
OS -0.98786442 -38.87308964
OS -0.99341178 -38.86291948
OS -0.99895914 -38.8509002
OS -1.0045065 -38.83795636
OS -1.0091293 -38.8231634
OS -1.0137521 -38.80744588
OS -1.01745034 -38.7908038
OS -1.02022402 -38.7723126
OS -1.02207314 -38.75289684
OS -1.0229977 -38.73255652
OS -1.0229977 -38.73163196
OS -1.0229977 -38.72700916
OS -1.0229977 -38.7214618
OS -1.02207314 -38.71314076
OS -1.02114858 -38.7029706
OS -1.02022402 -38.69187588
OS -1.0183749 -38.67893204
OS -1.01560122 -38.6659882
OS -1.00820474 -38.63640228
OS -1.00358194 -38.62160932
OS -0.99803458 -38.6058918
OS -0.9906381 -38.59109884
OS -0.98231706 -38.57723044
OS -0.97307146 -38.56336204
OS -0.9629013 -38.5504182
OS -0.96197674 -38.54949364
OS -0.96012762 -38.54764452
OS -0.95642938 -38.54487084
OS -0.95180658 -38.54024804
OS -0.94625922 -38.53562524
OS -0.93886274 -38.53007788
OS -0.9305417 -38.52360596
OS -0.92037154 -38.5180586
OS -0.91020138 -38.51158668
OS -0.8981821 -38.50603932
OS -0.88523826 -38.50049196
OS -0.87136986 -38.49586916
OS -0.8565769 -38.49124636
OS -0.84085938 -38.48847268
OS -0.8242173 -38.48662356
OS -0.80665066 -38.485699
OS -0.79740506 -38.485699
OS -0.79093314 -38.48662356
OE
OB -5.16872474 -38.48662356 I
OS -5.1604037 -38.48754812
OS -5.1511581 -38.48939724
OS -5.14098794 -38.49124636
OS -5.12896866 -38.49309548
OS -5.10400554 -38.50141652
OS -5.0910617 -38.50603932
OS -5.07811786 -38.51251124
OS -5.06517402 -38.51898316
OS -5.05223018 -38.52822876
OS -5.0402109 -38.53747436
OS -5.02819162 -38.54856908
OS -5.02726706 -38.54949364
OS -5.02541794 -38.55134276
OS -5.02264426 -38.555041
OS -5.01894602 -38.5596638
OS -5.01432322 -38.56613572
OS -5.00877586 -38.57445676
OS -5.0032285 -38.58370236
OS -4.99768114 -38.59387252
OS -4.99213378 -38.60496724
OS -4.98658642 -38.61883564
OS -4.98103906 -38.63270404
OS -4.97641626 -38.64842156
OS -4.97271802 -38.66506364
OS -4.96994434 -38.68263028
OS -4.96809522 -38.70112148
OS -4.96717066 -38.7214618
OS -4.96717066 -38.72238636
OS -4.96717066 -38.72516004
OS -4.96717066 -38.72978284
OS -4.96717066 -38.73625476
OS -4.96809522 -38.74365124
OS -4.96901978 -38.75289684
OS -4.96901978 -38.76214244
OS -4.9708689 -38.7723126
OS -4.97364258 -38.7954266
OS -4.97918994 -38.8185406
OS -4.98566186 -38.8416546
OS -4.99490746 -38.86291948
OS -4.99490746 -38.86384404
OS -4.99583202 -38.8647686
OS -4.99768114 -38.86754228
OS -4.99953026 -38.87124052
OS -5.00600218 -38.88048612
OS -5.01432322 -38.89158084
OS -5.02541794 -38.90452468
OS -5.03928634 -38.91746852
OS -5.05500386 -38.93041236
OS -5.07349506 -38.94243164
OS -5.07441962 -38.94243164
OS -5.07534418 -38.9433562
OS -5.07811786 -38.94520532
OS -5.08274066 -38.94705444
OS -5.08736346 -38.94890356
OS -5.09291082 -38.95075268
OS -5.10677922 -38.95630004
OS -5.12249674 -38.96092284
OS -5.1419125 -38.96554564
OS -5.16225282 -38.96924388
OS -5.18444226 -38.97016844
OS -5.19368786 -38.97016844
OS -5.20108434 -38.96924388
OS -5.20940538 -38.96831932
OS -5.21865098 -38.9664702
OS -5.2297457 -38.96462108
OS -5.24084042 -38.96277196
OS -5.26580354 -38.95537548
OS -5.27967194 -38.94982812
OS -5.29261578 -38.94428076
OS -5.30555962 -38.93688428
OS -5.31850346 -38.92856324
OS -5.33052274 -38.91931764
OS -5.34254202 -38.90822292
OS -5.34346658 -38.90729836
OS -5.3453157 -38.90544924
OS -5.34808938 -38.901751
OS -5.35178762 -38.89620364
OS -5.35641042 -38.88973172
OS -5.36103322 -38.88233524
OS -5.36658058 -38.87308964
OS -5.37212794 -38.86199492
OS -5.3776753 -38.84997564
OS -5.38322266 -38.83610724
OS -5.38784546 -38.82131428
OS -5.39246826 -38.80559676
OS -5.3961665 -38.78803012
OS -5.39894018 -38.76953892
OS -5.4007893 -38.7491986
OS -5.40171386 -38.72793372
OS -5.40171386 -38.7260846
OS -5.40171386 -38.72238636
OS -5.4007893 -38.71591444
OS -5.4007893 -38.70666884
OS -5.39986474 -38.69649868
OS -5.39801562 -38.68355484
OS -5.3961665 -38.670611
OS -5.39246826 -38.65581804
OS -5.38877002 -38.64102508
OS -5.38414722 -38.62530756
OS -5.37859986 -38.60866548
OS -5.37120338 -38.59294796
OS -5.3638069 -38.578155
OS -5.35363674 -38.56336204
OS -5.34346658 -38.54949364
OS -5.33052274 -38.53747436
OS -5.32959818 -38.5365498
OS -5.32774906 -38.53562524
OS -5.32405082 -38.53285156
OS -5.31942802 -38.52915332
OS -5.31388066 -38.52545508
OS -5.30648418 -38.52083228
OS -5.2990877 -38.51620948
OS -5.2898421 -38.51158668
OS -5.27967194 -38.50696388
OS -5.26857722 -38.50234108
OS -5.2436141 -38.49402004
OS -5.21495274 -38.48754812
OS -5.20015978 -38.48662356
OS -5.18444226 -38.485699
OS -5.17519666 -38.485699
OS -5.16872474 -38.48662356
OE
OB -4.78318322 -38.49586916 I
OS -4.70367106 -38.49586916
OS -4.70367106 -38.55689012
OS -4.78318322 -38.55689012
OS -4.78318322 -38.82963532
OS -4.78318322 -38.83148444
OS -4.78318322 -38.83518268
OS -4.78318322 -38.84073004
OS -4.78225866 -38.84720196
OS -4.7813341 -38.86199492
OS -4.78040954 -38.86846684
OS -4.77948498 -38.87308964
OS -4.77856042 -38.87493876
OS -4.77578674 -38.878637
OS -4.7720885 -38.8832598
OS -4.76561658 -38.8878826
OS -4.76376746 -38.88880716
OS -4.75914466 -38.89065628
OS -4.75082362 -38.8925054
OS -4.73880434 -38.89342996
OS -4.72955874 -38.89342996
OS -4.72493594 -38.8925054
OS -4.71846402 -38.8925054
OS -4.71106754 -38.89158084
OS -4.70367106 -38.89065628
OS -4.6935009 -38.95999828
OS -4.69535002 -38.95999828
OS -4.69904826 -38.96092284
OS -4.70552018 -38.9618474
OS -4.71384122 -38.96277196
OS -4.72308682 -38.96462108
OS -4.73325698 -38.96554564
OS -4.7535973 -38.9664702
OS -4.76099378 -38.9664702
OS -4.76839026 -38.96554564
OS -4.77763586 -38.96462108
OS -4.78873058 -38.96369652
OS -4.7998253 -38.96092284
OS -4.80999546 -38.95814916
OS -4.82016562 -38.95352636
OS -4.82109018 -38.9526018
OS -4.82386386 -38.95075268
OS -4.8275621 -38.947979
OS -4.83310946 -38.9433562
OS -4.83773226 -38.9387334
OS -4.84327962 -38.93226148
OS -4.84882698 -38.92578956
OS -4.85252522 -38.91746852
OS -4.85252522 -38.91654396
OS -4.85437434 -38.91284572
OS -4.8552989 -38.9063738
OS -4.85714802 -38.8971282
OS -4.85899714 -38.88510892
OS -4.8599217 -38.87771244
OS -4.8599217 -38.8693914
OS -4.86084626 -38.85922124
OS -4.86177082 -38.84905108
OS -4.86177082 -38.83795636
OS -4.86177082 -38.82501252
OS -4.86177082 -38.55689012
OS -4.9200181 -38.55689012
OS -4.9200181 -38.49586916
OS -4.86177082 -38.49586916
OS -4.86177082 -38.38122372
OS -4.78318322 -38.33407116
OS -4.78318322 -38.49586916
OE
OB -5.79280274 -38.54856908 I
OS -5.79187818 -38.54764452
OS -5.79095362 -38.5457954
OS -5.78817994 -38.54302172
OS -5.78355714 -38.53839892
OS -5.77893434 -38.53377612
OS -5.77338698 -38.52822876
OS -5.7659905 -38.5226814
OS -5.75859402 -38.51713404
OS -5.74010282 -38.50511476
OS -5.71883794 -38.49586916
OS -5.70681866 -38.49124636
OS -5.69387482 -38.48847268
OS -5.68000642 -38.48662356
OS -5.66613802 -38.485699
OS -5.65874154 -38.485699
OS -5.6504205 -38.48662356
OS -5.64025034 -38.48754812
OS -5.62823106 -38.4903218
OS -5.61436266 -38.49309548
OS -5.5995697 -38.49771828
OS -5.5857013 -38.50326564
OS -5.58385218 -38.5041902
OS -5.57922938 -38.50603932
OS -5.5718329 -38.51066212
OS -5.56351186 -38.51620948
OS -5.5533417 -38.5226814
OS -5.54317154 -38.53100244
OS -5.53207682 -38.5411726
OS -5.52283122 -38.55226732
OS -5.52190666 -38.55319188
OS -5.51913298 -38.55781468
OS -5.51451018 -38.5642866
OS -5.50896282 -38.57260764
OS -5.5024909 -38.58370236
OS -5.49601898 -38.5966462
OS -5.48954706 -38.61143916
OS -5.4839997 -38.62715668
OS -5.4839997 -38.62808124
OS -5.48307514 -38.6290058
OS -5.48215058 -38.63177948
OS -5.48122602 -38.63455316
OS -5.4793769 -38.64379876
OS -5.47660322 -38.65581804
OS -5.47382954 -38.66968644
OS -5.47105586 -38.68540396
OS -5.4701313 -38.7029706
OS -5.46920674 -38.7214618
OS -5.46920674 -38.72238636
OS -5.46920674 -38.72700916
OS -5.46920674 -38.73255652
OS -5.4701313 -38.74087756
OS -5.47105586 -38.75104772
OS -5.47198042 -38.76214244
OS -5.47382954 -38.77508628
OS -5.47660322 -38.78895468
OS -5.4839997 -38.8185406
OS -5.4886225 -38.83425812
OS -5.49416986 -38.84905108
OS -5.50064178 -38.8647686
OS -5.50896282 -38.878637
OS -5.51820842 -38.8925054
OS -5.52837858 -38.90544924
OS -5.52930314 -38.9063738
OS -5.53115226 -38.90822292
OS -5.53392594 -38.9109966
OS -5.53854874 -38.9156194
OS -5.54502066 -38.9202422
OS -5.55149258 -38.92578956
OS -5.55888906 -38.93133692
OS -5.56813466 -38.93780884
OS -5.57830482 -38.9433562
OS -5.58847498 -38.94982812
OS -5.6134381 -38.95999828
OS -5.62638194 -38.96462108
OS -5.64025034 -38.96739476
OS -5.6550433 -38.96924388
OS -5.66983626 -38.97016844
OS -5.6735345 -38.97016844
OS -5.6781573 -38.96924388
OS -5.68370466 -38.96924388
OS -5.69017658 -38.96831932
OS -5.69849762 -38.9664702
OS -5.71698882 -38.9618474
OS -5.72715898 -38.95814916
OS -5.73732914 -38.95352636
OS -5.74842386 -38.947979
OS -5.75859402 -38.94150708
OS -5.76968874 -38.93318604
OS -5.7798589 -38.92394044
OS -5.7891045 -38.91377028
OS -5.7983501 -38.901751
OS -5.7983501 -38.95999828
OS -5.87139034 -38.95999828
OS -5.87139034 -38.32020276
OS -5.79280274 -38.32020276
OS -5.79280274 -38.54856908
OE
OB -5.97031826 -38.42745172 I
OS -5.99158314 -38.54671996
OS -6.04058482 -38.54671996
OS -6.06000058 -38.42745172
OS -6.06000058 -38.32020276
OS -5.97031826 -38.32020276
OS -5.97031826 -38.42745172
OE
OB -4.17389818 -38.48662356 I
OS -4.16557714 -38.48754812
OS -4.15633154 -38.48939724
OS -4.14616138 -38.49124636
OS -4.1341421 -38.49309548
OS -4.10917898 -38.50141652
OS -4.09623514 -38.50603932
OS -4.0832913 -38.51251124
OS -4.07034746 -38.51898316
OS -4.05740362 -38.52822876
OS -4.04538434 -38.53747436
OS -4.03336506 -38.54856908
OS -4.0324405 -38.54949364
OS -4.03059138 -38.55134276
OS -4.0278177 -38.555041
OS -4.02411946 -38.5596638
OS -4.01949666 -38.56613572
OS -4.0139493 -38.57445676
OS -4.00840194 -38.58370236
OS -4.00285458 -38.59387252
OS -3.99730722 -38.60496724
OS -3.99175986 -38.61883564
OS -3.9862125 -38.63270404
OS -3.9815897 -38.64842156
OS -3.97789146 -38.66506364
OS -3.97511778 -38.68263028
OS -3.97326866 -38.70112148
OS -3.9723441 -38.7214618
OS -3.9723441 -38.72238636
OS -3.9723441 -38.72516004
OS -3.9723441 -38.72978284
OS -3.9723441 -38.73625476
OS -3.97326866 -38.74365124
OS -3.97419322 -38.75289684
OS -3.97419322 -38.76214244
OS -3.97604234 -38.7723126
OS -3.97881602 -38.7954266
OS -3.98436338 -38.8185406
OS -3.9908353 -38.8416546
OS -4.0000809 -38.86291948
OS -4.0000809 -38.86384404
OS -4.00100546 -38.8647686
OS -4.00285458 -38.86754228
OS -4.0047037 -38.87124052
OS -4.01117562 -38.88048612
OS -4.01949666 -38.89158084
OS -4.03059138 -38.90452468
OS -4.04445978 -38.91746852
OS -4.0601773 -38.93041236
OS -4.0786685 -38.94243164
OS -4.07959306 -38.94243164
OS -4.08051762 -38.9433562
OS -4.0832913 -38.94520532
OS -4.0879141 -38.94705444
OS -4.0925369 -38.94890356
OS -4.09808426 -38.95075268
OS -4.11195266 -38.95630004
OS -4.12767018 -38.96092284
OS -4.14708594 -38.96554564
OS -4.16742626 -38.96924388
OS -4.1896157 -38.97016844
OS -4.1988613 -38.97016844
OS -4.20625778 -38.96924388
OS -4.21457882 -38.96831932
OS -4.22382442 -38.9664702
OS -4.23491914 -38.96462108
OS -4.24601386 -38.96277196
OS -4.27097698 -38.95537548
OS -4.28484538 -38.94982812
OS -4.29778922 -38.94428076
OS -4.31073306 -38.93688428
OS -4.3236769 -38.92856324
OS -4.33569618 -38.91931764
OS -4.34771546 -38.90822292
OS -4.34864002 -38.90729836
OS -4.35048914 -38.90544924
OS -4.35326282 -38.901751
OS -4.35696106 -38.89620364
OS -4.36158386 -38.88973172
OS -4.36620666 -38.88233524
OS -4.37175402 -38.87308964
OS -4.37730138 -38.86199492
OS -4.38284874 -38.84997564
OS -4.3883961 -38.83610724
OS -4.3930189 -38.82131428
OS -4.3976417 -38.80559676
OS -4.40133994 -38.78803012
OS -4.40411362 -38.76953892
OS -4.40596274 -38.7491986
OS -4.4068873 -38.72793372
OS -4.4068873 -38.7260846
OS -4.4068873 -38.72238636
OS -4.40596274 -38.71591444
OS -4.40596274 -38.70666884
OS -4.40503818 -38.69649868
OS -4.40318906 -38.68355484
OS -4.40133994 -38.670611
OS -4.3976417 -38.65581804
OS -4.39394346 -38.64102508
OS -4.38932066 -38.62530756
OS -4.3837733 -38.60866548
OS -4.37637682 -38.59294796
OS -4.36898034 -38.578155
OS -4.35881018 -38.56336204
OS -4.34864002 -38.54949364
OS -4.33569618 -38.53747436
OS -4.33477162 -38.5365498
OS -4.3329225 -38.53562524
OS -4.32922426 -38.53285156
OS -4.32460146 -38.52915332
OS -4.3190541 -38.52545508
OS -4.31165762 -38.52083228
OS -4.30426114 -38.51620948
OS -4.29501554 -38.51158668
OS -4.28484538 -38.50696388
OS -4.27375066 -38.50234108
OS -4.24878754 -38.49402004
OS -4.22012618 -38.48754812
OS -4.20533322 -38.48662356
OS -4.1896157 -38.485699
OS -4.1803701 -38.485699
OS -4.17389818 -38.48662356
OE
OB -4.53447658 -38.49586916 I
OS -4.45496442 -38.49586916
OS -4.45496442 -38.55689012
OS -4.53447658 -38.55689012
OS -4.53447658 -38.82963532
OS -4.53447658 -38.83148444
OS -4.53447658 -38.83518268
OS -4.53447658 -38.84073004
OS -4.53355202 -38.84720196
OS -4.53262746 -38.86199492
OS -4.5317029 -38.86846684
OS -4.53077834 -38.87308964
OS -4.52985378 -38.87493876
OS -4.5270801 -38.878637
OS -4.52338186 -38.8832598
OS -4.51690994 -38.8878826
OS -4.51506082 -38.88880716
OS -4.51043802 -38.89065628
OS -4.50211698 -38.8925054
OS -4.4900977 -38.89342996
OS -4.4808521 -38.89342996
OS -4.4762293 -38.8925054
OS -4.46975738 -38.8925054
OS -4.4623609 -38.89158084
OS -4.45496442 -38.89065628
OS -4.44479426 -38.95999828
OS -4.44664338 -38.95999828
OS -4.45034162 -38.96092284
OS -4.45681354 -38.9618474
OS -4.46513458 -38.96277196
OS -4.47438018 -38.96462108
OS -4.48455034 -38.96554564
OS -4.50489066 -38.9664702
OS -4.51228714 -38.9664702
OS -4.51968362 -38.96554564
OS -4.52892922 -38.96462108
OS -4.54002394 -38.96369652
OS -4.55111866 -38.96092284
OS -4.56128882 -38.95814916
OS -4.57145898 -38.95352636
OS -4.57238354 -38.9526018
OS -4.57515722 -38.95075268
OS -4.57885546 -38.947979
OS -4.58440282 -38.9433562
OS -4.58902562 -38.9387334
OS -4.59457298 -38.93226148
OS -4.60012034 -38.92578956
OS -4.60381858 -38.91746852
OS -4.60381858 -38.91654396
OS -4.6056677 -38.91284572
OS -4.60659226 -38.9063738
OS -4.60844138 -38.8971282
OS -4.6102905 -38.88510892
OS -4.61121506 -38.87771244
OS -4.61121506 -38.8693914
OS -4.61213962 -38.85922124
OS -4.61306418 -38.84905108
OS -4.61306418 -38.83795636
OS -4.61306418 -38.82501252
OS -4.61306418 -38.55689012
OS -4.67131146 -38.55689012
OS -4.67131146 -38.49586916
OS -4.61306418 -38.49586916
OS -4.61306418 -38.38122372
OS -4.53447658 -38.33407116
OS -4.53447658 -38.49586916
OE
OB -4.1896157 -38.5504182 H
OS -4.19516306 -38.5504182
OS -4.19978586 -38.55134276
OS -4.20995602 -38.55226732
OS -4.22382442 -38.55596556
OS -4.23954194 -38.56151292
OS -4.25618402 -38.5689094
OS -4.27190154 -38.58000412
OS -4.28022258 -38.5874006
OS -4.28761906 -38.59479708
OS -4.28761906 -38.59572164
OS -4.28946818 -38.5966462
OS -4.2913173 -38.59941988
OS -4.29409098 -38.60311812
OS -4.29686466 -38.60774092
OS -4.29963834 -38.61328828
OS -4.30333658 -38.62068476
OS -4.30703482 -38.62808124
OS -4.31073306 -38.63732684
OS -4.3144313 -38.64657244
OS -4.31720498 -38.65766716
OS -4.31997866 -38.66968644
OS -4.32275234 -38.68263028
OS -4.32460146 -38.69649868
OS -4.32552602 -38.7122162
OS -4.32645058 -38.72793372
OS -4.32645058 -38.72885828
OS -4.32645058 -38.73163196
OS -4.32645058 -38.73625476
OS -4.32552602 -38.74272668
OS -4.32552602 -38.75012316
OS -4.32460146 -38.7584442
OS -4.32182778 -38.77785996
OS -4.31720498 -38.8000494
OS -4.3098085 -38.82223884
OS -4.3005629 -38.84350372
OS -4.29409098 -38.85274932
OS -4.28761906 -38.86199492
OS -4.2866945 -38.86199492
OS -4.28576994 -38.86384404
OS -4.28022258 -38.86846684
OS -4.27190154 -38.87586332
OS -4.26080682 -38.8832598
OS -4.24693842 -38.89158084
OS -4.23029634 -38.89897732
OS -4.21088058 -38.90360012
OS -4.20071042 -38.90452468
OS -4.1896157 -38.90544924
OS -4.18406834 -38.90544924
OS -4.17944554 -38.90452468
OS -4.16927538 -38.90267556
OS -4.15540698 -38.89990188
OS -4.14061402 -38.89435452
OS -4.12397194 -38.88695804
OS -4.10825442 -38.87586332
OS -4.09993338 -38.86846684
OS -4.0925369 -38.86107036
OS -4.09161234 -38.8601458
OS -4.09068778 -38.85922124
OS -4.08883866 -38.85644756
OS -4.08606498 -38.85274932
OS -4.0832913 -38.84812652
OS -4.07959306 -38.84257916
OS -4.07589482 -38.83518268
OS -4.07219658 -38.8277862
OS -4.06849834 -38.8185406
OS -4.06572466 -38.80837044
OS -4.06202642 -38.79727572
OS -4.05925274 -38.78525644
OS -4.05647906 -38.77138804
OS -4.05462994 -38.75751964
OS -4.05278082 -38.74180212
OS -4.05278082 -38.72516004
OS -4.05278082 -38.72423548
OS -4.05278082 -38.7214618
OS -4.05278082 -38.716839
OS -4.05370538 -38.71129164
OS -4.05370538 -38.70389516
OS -4.05462994 -38.69557412
OS -4.05740362 -38.67615836
OS -4.06202642 -38.65581804
OS -4.0694229 -38.6336286
OS -4.07959306 -38.61328828
OS -4.08514042 -38.60311812
OS -4.0925369 -38.59479708
OS -4.0925369 -38.59387252
OS -4.09438602 -38.59294796
OS -4.09993338 -38.5874006
OS -4.10825442 -38.58092868
OS -4.11934914 -38.57260764
OS -4.13321754 -38.5642866
OS -4.14985962 -38.55689012
OS -4.16835082 -38.55226732
OS -4.17852098 -38.55134276
OS -4.1896157 -38.5504182
OE
OB -5.6642889 -38.5504182 H
OS -5.6781573 -38.5504182
OS -5.68185554 -38.55134276
OS -5.6920257 -38.55319188
OS -5.70404498 -38.55596556
OS -5.71791338 -38.56151292
OS -5.73270634 -38.56983396
OS -5.74010282 -38.57445676
OS -5.7474993 -38.58092868
OS -5.75489578 -38.5874006
OS -5.76229226 -38.59572164
OS -5.76229226 -38.5966462
OS -5.76414138 -38.59757076
OS -5.7659905 -38.60034444
OS -5.76783962 -38.60404268
OS -5.7706133 -38.60866548
OS -5.77431154 -38.61421284
OS -5.77708522 -38.62068476
OS -5.78078346 -38.62808124
OS -5.7844817 -38.63732684
OS -5.78725538 -38.64657244
OS -5.79095362 -38.65766716
OS -5.7937273 -38.66876188
OS -5.79557642 -38.68170572
OS -5.79742554 -38.69557412
OS -5.79927466 -38.70944252
OS -5.79927466 -38.72516004
OS -5.79927466 -38.7260846
OS -5.79927466 -38.72885828
OS -5.79927466 -38.73348108
OS -5.79927466 -38.73902844
OS -5.7983501 -38.74550036
OS -5.7983501 -38.7538214
OS -5.79650098 -38.77138804
OS -5.7937273 -38.7908038
OS -5.79002906 -38.81114412
OS -5.7844817 -38.82963532
OS -5.78078346 -38.83795636
OS -5.77708522 -38.84535284
OS -5.77708522 -38.8462774
OS -5.7752361 -38.84812652
OS -5.77338698 -38.8509002
OS -5.7706133 -38.85459844
OS -5.76229226 -38.8647686
OS -5.75027298 -38.87493876
OS -5.73640458 -38.88603348
OS -5.71883794 -38.89620364
OS -5.70959234 -38.89990188
OS -5.69849762 -38.90267556
OS -5.68832746 -38.90452468
OS -5.67630818 -38.90544924
OS -5.67168538 -38.90544924
OS -5.66798714 -38.90452468
OS -5.65781698 -38.90267556
OS -5.6457977 -38.89990188
OS -5.6319293 -38.89435452
OS -5.61713634 -38.88695804
OS -5.60234338 -38.87586332
OS -5.5949469 -38.86846684
OS -5.58755042 -38.86107036
OS -5.58755042 -38.8601458
OS -5.5857013 -38.85922124
OS -5.58385218 -38.85644756
OS -5.58200306 -38.85274932
OS -5.57830482 -38.84812652
OS -5.57553114 -38.84257916
OS -5.5718329 -38.83518268
OS -5.56813466 -38.8277862
OS -5.56536098 -38.8185406
OS -5.56166274 -38.809295
OS -5.5579645 -38.79820028
OS -5.55519082 -38.786181
OS -5.5533417 -38.77323716
OS -5.55149258 -38.75936876
OS -5.54964346 -38.74365124
OS -5.54964346 -38.72793372
OS -5.54964346 -38.72700916
OS -5.54964346 -38.72423548
OS -5.54964346 -38.71961268
OS -5.55056802 -38.71314076
OS -5.55056802 -38.70574428
OS -5.55149258 -38.69649868
OS -5.55426626 -38.67708292
OS -5.5579645 -38.65581804
OS -5.56443642 -38.63270404
OS -5.57368202 -38.61236372
OS -5.57922938 -38.60219356
OS -5.5857013 -38.59387252
OS -5.5857013 -38.59294796
OS -5.58755042 -38.5920234
OS -5.59217322 -38.5874006
OS -5.5995697 -38.58000412
OS -5.60973986 -38.57168308
OS -5.6226837 -38.5642866
OS -5.63747666 -38.55689012
OS -5.6550433 -38.55226732
OS -5.6642889 -38.5504182
OE
OB -0.8057261 -38.5504182 H
OS -0.81127346 -38.5504182
OS -0.8149717 -38.55134276
OS -0.82514186 -38.55226732
OS -0.83716114 -38.555041
OS -0.8519541 -38.5596638
OS -0.86767162 -38.56613572
OS -0.88246458 -38.57538132
OS -0.89725754 -38.5874006
OS -0.89910666 -38.58924972
OS -0.9028049 -38.59387252
OS -0.90927682 -38.60219356
OS -0.91574874 -38.61328828
OS -0.92314522 -38.62623212
OS -0.92961714 -38.6428742
OS -0.9351645 -38.66228996
OS -0.93793818 -38.68355484
OS -0.67813682 -38.68355484
OS -0.67813682 -38.68263028
OS -0.67813682 -38.68078116
OS -0.67906138 -38.67800748
OS -0.67906138 -38.67430924
OS -0.6809105 -38.66321452
OS -0.68368418 -38.65119524
OS -0.68830698 -38.63640228
OS -0.69292978 -38.62253388
OS -0.70032626 -38.60866548
OS -0.7086473 -38.5966462
OS -0.7086473 -38.59572164
OS -0.71049642 -38.59479708
OS -0.71511922 -38.58924972
OS -0.72344026 -38.58185324
OS -0.73453498 -38.5735322
OS -0.74840338 -38.56521116
OS -0.76504546 -38.55781468
OS -0.78446122 -38.55226732
OS -0.79463138 -38.55134276
OS -0.8057261 -38.5504182
OE
OB -2.00210674 -38.5504182 H
OS -2.0076541 -38.5504182
OS -2.0122769 -38.55134276
OS -2.02244706 -38.55226732
OS -2.03631546 -38.55596556
OS -2.05203298 -38.56151292
OS -2.06867506 -38.5689094
OS -2.08439258 -38.58000412
OS -2.09271362 -38.5874006
OS -2.1001101 -38.59479708
OS -2.1001101 -38.59572164
OS -2.10195922 -38.5966462
OS -2.10380834 -38.59941988
OS -2.10658202 -38.60311812
OS -2.1093557 -38.60774092
OS -2.11212938 -38.61328828
OS -2.11582762 -38.62068476
OS -2.11952586 -38.62808124
OS -2.1232241 -38.63732684
OS -2.12692234 -38.64657244
OS -2.12969602 -38.65766716
OS -2.1324697 -38.66968644
OS -2.13524338 -38.68263028
OS -2.1370925 -38.69649868
OS -2.13801706 -38.7122162
OS -2.13894162 -38.72793372
OS -2.13894162 -38.72885828
OS -2.13894162 -38.73163196
OS -2.13894162 -38.73625476
OS -2.13801706 -38.74272668
OS -2.13801706 -38.75012316
OS -2.1370925 -38.7584442
OS -2.13431882 -38.77785996
OS -2.12969602 -38.8000494
OS -2.12229954 -38.82223884
OS -2.11305394 -38.84350372
OS -2.10658202 -38.85274932
OS -2.1001101 -38.86199492
OS -2.09918554 -38.86199492
OS -2.09826098 -38.86384404
OS -2.09271362 -38.86846684
OS -2.08439258 -38.87586332
OS -2.07329786 -38.8832598
OS -2.05942946 -38.89158084
OS -2.04278738 -38.89897732
OS -2.02337162 -38.90360012
OS -2.01320146 -38.90452468
OS -2.00210674 -38.90544924
OS -1.99655938 -38.90544924
OS -1.99193658 -38.90452468
OS -1.98176642 -38.90267556
OS -1.96789802 -38.89990188
OS -1.95310506 -38.89435452
OS -1.93646298 -38.88695804
OS -1.92074546 -38.87586332
OS -1.91242442 -38.86846684
OS -1.90502794 -38.86107036
OS -1.90410338 -38.8601458
OS -1.90317882 -38.85922124
OS -1.9013297 -38.85644756
OS -1.89855602 -38.85274932
OS -1.89578234 -38.84812652
OS -1.8920841 -38.84257916
OS -1.88838586 -38.83518268
OS -1.88468762 -38.8277862
OS -1.88098938 -38.8185406
OS -1.8782157 -38.80837044
OS -1.87451746 -38.79727572
OS -1.87174378 -38.78525644
OS -1.8689701 -38.77138804
OS -1.86712098 -38.75751964
OS -1.86527186 -38.74180212
OS -1.86527186 -38.72516004
OS -1.86527186 -38.72423548
OS -1.86527186 -38.7214618
OS -1.86527186 -38.716839
OS -1.86619642 -38.71129164
OS -1.86619642 -38.70389516
OS -1.86712098 -38.69557412
OS -1.86989466 -38.67615836
OS -1.87451746 -38.65581804
OS -1.88191394 -38.6336286
OS -1.8920841 -38.61328828
OS -1.89763146 -38.60311812
OS -1.90502794 -38.59479708
OS -1.90502794 -38.59387252
OS -1.90687706 -38.59294796
OS -1.91242442 -38.5874006
OS -1.92074546 -38.58092868
OS -1.93184018 -38.57260764
OS -1.94570858 -38.5642866
OS -1.96235066 -38.55689012
OS -1.98084186 -38.55226732
OS -1.99101202 -38.55134276
OS -2.00210674 -38.5504182
OE
OB -1.31978146 -38.5504182 H
OS -1.32440426 -38.5504182
OS -1.3281025 -38.55134276
OS -1.33827266 -38.55226732
OS -1.35029194 -38.55596556
OS -1.36416034 -38.56058836
OS -1.3789533 -38.5689094
OS -1.39374626 -38.57907956
OS -1.40114274 -38.58647604
OS -1.40761466 -38.59387252
OS -1.40761466 -38.59479708
OS -1.40946378 -38.59572164
OS -1.41038834 -38.59849532
OS -1.41316202 -38.60219356
OS -1.4159357 -38.60681636
OS -1.41870938 -38.61236372
OS -1.42148306 -38.61883564
OS -1.4251813 -38.62623212
OS -1.42887954 -38.63547772
OS -1.43165322 -38.64564788
OS -1.4344269 -38.6567426
OS -1.43720058 -38.66876188
OS -1.4390497 -38.68170572
OS -1.44089882 -38.69649868
OS -1.44274794 -38.7122162
OS -1.44274794 -38.72885828
OS -1.44274794 -38.72978284
OS -1.44274794 -38.73255652
OS -1.44274794 -38.73717932
OS -1.44182338 -38.74365124
OS -1.44182338 -38.75104772
OS -1.44089882 -38.75936876
OS -1.43812514 -38.77878452
OS -1.43350234 -38.8000494
OS -1.42703042 -38.82223884
OS -1.41778482 -38.84350372
OS -1.41223746 -38.85274932
OS -1.40576554 -38.86199492
OS -1.40484098 -38.86199492
OS -1.40391642 -38.86384404
OS -1.39929362 -38.86846684
OS -1.39097258 -38.87586332
OS -1.38080242 -38.8832598
OS -1.36785858 -38.89158084
OS -1.35214106 -38.89897732
OS -1.33549898 -38.90360012
OS -1.32625338 -38.90452468
OS -1.31700778 -38.90544924
OS -1.31238498 -38.90544924
OS -1.30868674 -38.90452468
OS -1.29851658 -38.90360012
OS -1.2864973 -38.89990188
OS -1.2726289 -38.89527908
OS -1.25783594 -38.8878826
OS -1.24304298 -38.87771244
OS -1.2356465 -38.87124052
OS -1.22917458 -38.86384404
OS -1.22917458 -38.86291948
OS -1.22732546 -38.86199492
OS -1.22547634 -38.85922124
OS -1.22362722 -38.855523
OS -1.22085354 -38.8509002
OS -1.2171553 -38.8462774
OS -1.21438162 -38.83888092
OS -1.21068338 -38.83148444
OS -1.20698514 -38.8231634
OS -1.20421146 -38.8139178
OS -1.20051322 -38.80282308
OS -1.19773954 -38.79172836
OS -1.19589042 -38.77878452
OS -1.1940413 -38.76584068
OS -1.19219218 -38.75104772
OS -1.19219218 -38.7353302
OS -1.19219218 -38.73440564
OS -1.19219218 -38.7307074
OS -1.19219218 -38.7260846
OS -1.19311674 -38.71961268
OS -1.19311674 -38.7122162
OS -1.1940413 -38.7029706
OS -1.19496586 -38.69280044
OS -1.19681498 -38.68170572
OS -1.20143778 -38.65951628
OS -1.2079097 -38.63640228
OS -1.2171553 -38.61421284
OS -1.22270266 -38.60496724
OS -1.22917458 -38.59572164
OS -1.22917458 -38.59479708
OS -1.2310237 -38.59387252
OS -1.2356465 -38.58832516
OS -1.24396754 -38.58092868
OS -1.2541377 -38.57260764
OS -1.26708154 -38.5642866
OS -1.28279906 -38.55781468
OS -1.3003657 -38.55226732
OS -1.3096113 -38.55134276
OS -1.31978146 -38.5504182
OE
OB -5.18444226 -38.5504182 H
OS -5.18998962 -38.5504182
OS -5.19461242 -38.55134276
OS -5.20478258 -38.55226732
OS -5.21865098 -38.55596556
OS -5.2343685 -38.56151292
OS -5.25101058 -38.5689094
OS -5.2667281 -38.58000412
OS -5.27504914 -38.5874006
OS -5.28244562 -38.59479708
OS -5.28244562 -38.59572164
OS -5.28429474 -38.5966462
OS -5.28614386 -38.59941988
OS -5.28891754 -38.60311812
OS -5.29169122 -38.60774092
OS -5.2944649 -38.61328828
OS -5.29816314 -38.62068476
OS -5.30186138 -38.62808124
OS -5.30555962 -38.63732684
OS -5.30925786 -38.64657244
OS -5.31203154 -38.65766716
OS -5.31480522 -38.66968644
OS -5.3175789 -38.68263028
OS -5.31942802 -38.69649868
OS -5.32035258 -38.7122162
OS -5.32127714 -38.72793372
OS -5.32127714 -38.72885828
OS -5.32127714 -38.73163196
OS -5.32127714 -38.73625476
OS -5.32035258 -38.74272668
OS -5.32035258 -38.75012316
OS -5.31942802 -38.7584442
OS -5.31665434 -38.77785996
OS -5.31203154 -38.8000494
OS -5.30463506 -38.82223884
OS -5.29538946 -38.84350372
OS -5.28891754 -38.85274932
OS -5.28244562 -38.86199492
OS -5.28152106 -38.86199492
OS -5.2805965 -38.86384404
OS -5.27504914 -38.86846684
OS -5.2667281 -38.87586332
OS -5.25563338 -38.8832598
OS -5.24176498 -38.89158084
OS -5.2251229 -38.89897732
OS -5.20570714 -38.90360012
OS -5.19553698 -38.90452468
OS -5.18444226 -38.90544924
OS -5.1788949 -38.90544924
OS -5.1742721 -38.90452468
OS -5.16410194 -38.90267556
OS -5.15023354 -38.89990188
OS -5.13544058 -38.89435452
OS -5.1187985 -38.88695804
OS -5.10308098 -38.87586332
OS -5.09475994 -38.86846684
OS -5.08736346 -38.86107036
OS -5.0864389 -38.8601458
OS -5.08551434 -38.85922124
OS -5.08366522 -38.85644756
OS -5.08089154 -38.85274932
OS -5.07811786 -38.84812652
OS -5.07441962 -38.84257916
OS -5.07072138 -38.83518268
OS -5.06702314 -38.8277862
OS -5.0633249 -38.8185406
OS -5.06055122 -38.80837044
OS -5.05685298 -38.79727572
OS -5.0540793 -38.78525644
OS -5.05130562 -38.77138804
OS -5.0494565 -38.75751964
OS -5.04760738 -38.74180212
OS -5.04760738 -38.72516004
OS -5.04760738 -38.72423548
OS -5.04760738 -38.7214618
OS -5.04760738 -38.716839
OS -5.04853194 -38.71129164
OS -5.04853194 -38.70389516
OS -5.0494565 -38.69557412
OS -5.05223018 -38.67615836
OS -5.05685298 -38.65581804
OS -5.06424946 -38.6336286
OS -5.07441962 -38.61328828
OS -5.07996698 -38.60311812
OS -5.08736346 -38.59479708
OS -5.08736346 -38.59387252
OS -5.08921258 -38.59294796
OS -5.09475994 -38.5874006
OS -5.10308098 -38.58092868
OS -5.1141757 -38.57260764
OS -5.1280441 -38.5642866
OS -5.14468618 -38.55689012
OS -5.16317738 -38.55226732
OS -5.17334754 -38.55134276
OS -5.18444226 -38.5504182
OE
SE
S P 0
OB -4.66714078 -36.5016923 I
OS -4.65465922 -36.5016923
OS -4.62553558 -36.50307914
OS -4.5950251 -36.50723966
OS -4.56174094 -36.51140018
OS -4.53123046 -36.51833438
OS -4.51597522 -36.5224949
OS -4.50349366 -36.52665542
OS -4.50210682 -36.52665542
OS -4.50071998 -36.52804226
OS -4.49239894 -36.53220278
OS -4.47991738 -36.53775014
OS -4.46466214 -36.54745802
OS -4.44802006 -36.55993958
OS -4.42999114 -36.57658166
OS -4.41334906 -36.59599742
OS -4.39670698 -36.61818686
OS -4.39670698 -36.6195737
OS -4.39532014 -36.62096054
OS -4.38977278 -36.62928158
OS -4.38422542 -36.64314998
OS -4.37590438 -36.6611789
OS -4.36897018 -36.6819815
OS -4.36203598 -36.70694462
OS -4.35787546 -36.73329458
OS -4.35648862 -36.76241822
OS -4.35648862 -36.76380506
OS -4.35648862 -36.76657874
OS -4.35648862 -36.7721261
OS -4.35787546 -36.7790603
OS -4.35787546 -36.78876818
OS -4.3592623 -36.79847606
OS -4.36480966 -36.82205234
OS -4.3731307 -36.84978914
OS -4.38422542 -36.87891278
OS -4.4008675 -36.90803642
OS -4.41196222 -36.92190482
OS -4.42305694 -36.93577322
OS -4.42444378 -36.93716006
OS -4.42583062 -36.9385469
OS -4.42999114 -36.94270742
OS -4.4355385 -36.94686794
OS -4.4424727 -36.9524153
OS -4.45079374 -36.95796266
OS -4.46188846 -36.96489686
OS -4.47298318 -36.9732179
OS -4.48685158 -36.9801521
OS -4.50210682 -36.9870863
OS -4.5187489 -36.99540734
OS -4.53677782 -37.00234154
OS -4.55758042 -37.0078889
OS -4.57838302 -37.0148231
OS -4.6019593 -37.01898362
OS -4.62692242 -37.02314414
OS -4.62414874 -37.02453098
OS -4.61860138 -37.02730466
OS -4.61028034 -37.03285202
OS -4.59918562 -37.03839938
OS -4.5742225 -37.05365462
OS -4.56174094 -37.0633625
OS -4.55064622 -37.07168354
OS -4.54787254 -37.07445722
OS -4.54093834 -37.08139142
OS -4.52984362 -37.09248614
OS -4.51597522 -37.10635454
OS -4.50071998 -37.1257703
OS -4.48269106 -37.1465729
OS -4.46466214 -37.17153602
OS -4.44524638 -37.19927282
OS -4.28021242 -37.45999874
OS -4.43831218 -37.45999874
OS -4.56451462 -37.26029378
OS -4.56451462 -37.25890694
OS -4.5672883 -37.25613326
OS -4.57006198 -37.25197274
OS -4.5742225 -37.24642538
OS -4.58393038 -37.23117014
OS -4.59641194 -37.21175438
OS -4.61166718 -37.19095178
OS -4.62692242 -37.16876234
OS -4.64217766 -37.14795974
OS -4.65604606 -37.12854398
OS -4.6574329 -37.12715714
OS -4.66159342 -37.12160978
OS -4.66852762 -37.11328874
OS -4.6782355 -37.10358086
OS -4.6990381 -37.08277826
OS -4.71013282 -37.07307038
OS -4.72122754 -37.06474934
OS -4.72261438 -37.0633625
OS -4.72538806 -37.06197566
OS -4.73093542 -37.05920198
OS -4.73925646 -37.05504146
OS -4.7475775 -37.05088094
OS -4.75728538 -37.04672042
OS -4.77947482 -37.03978622
OS -4.78086166 -37.03978622
OS -4.78363534 -37.03839938
OS -4.7891827 -37.03839938
OS -4.7961169 -37.03701254
OS -4.80582478 -37.0356257
OS -4.8169195 -37.0356257
OS -4.83217474 -37.03423886
OS -4.99582186 -37.03423886
OS -4.99582186 -37.45999874
OS -5.12341114 -37.45999874
OS -5.12341114 -36.50030546
OS -4.6782355 -36.50030546
OS -4.66714078 -36.5016923
OE
OB -1.0100437 -37.45999874 I
OS -1.13208562 -37.45999874
OS -1.13208562 -36.65701838
OS -1.4122273 -37.45999874
OS -1.52594818 -37.45999874
OS -1.80331618 -36.64314998
OS -1.80331618 -37.45999874
OS -1.9253581 -37.45999874
OS -1.9253581 -36.50030546
OS -1.73536102 -36.50030546
OS -1.50791926 -37.1812439
OS -1.50791926 -37.18263074
OS -1.50653242 -37.18540442
OS -1.50514558 -37.18956494
OS -1.5023719 -37.19649914
OS -1.49682454 -37.21314122
OS -1.48989034 -37.23394382
OS -1.48295614 -37.2575201
OS -1.4746351 -37.28109638
OS -1.4677009 -37.30328582
OS -1.46215354 -37.32270158
OS -1.4607667 -37.3199279
OS -1.45937986 -37.3129937
OS -1.45521934 -37.30051214
OS -1.44967198 -37.28387006
OS -1.44273778 -37.26168062
OS -1.4330299 -37.23533066
OS -1.42332202 -37.20482018
OS -1.41084046 -37.16876234
OS -1.18062502 -36.50030546
OS -1.0100437 -36.50030546
OS -1.0100437 -37.45999874
OE
OB -2.02382374 -37.45999874 I
OS -2.1680551 -37.45999874
OS -2.28038914 -37.16876234
OS -2.68257274 -37.16876234
OS -2.78658574 -37.45999874
OS -2.92110922 -37.45999874
OS -2.55498346 -36.50030546
OS -2.41629946 -36.50030546
OS -2.02382374 -37.45999874
OE
OB -3.02928274 -37.45999874 I
OS -3.16103254 -37.45999874
OS -3.66306862 -36.70694462
OS -3.66306862 -37.45999874
OS -3.78511054 -37.45999874
OS -3.78511054 -36.50030546
OS -3.65474758 -36.50030546
OS -3.15132466 -37.25474642
OS -3.15132466 -36.50030546
OS -3.02928274 -36.50030546
OS -3.02928274 -37.45999874
OE
OB -5.3231161 -36.61402634 I
OS -5.89033366 -36.61402634
OS -5.89033366 -36.90664958
OS -5.35917394 -36.90664958
OS -5.35917394 -37.02037046
OS -5.89033366 -37.02037046
OS -5.89033366 -37.34627786
OS -5.30092666 -37.34627786
OS -5.30092666 -37.45999874
OS -6.01792294 -37.45999874
OS -6.01792294 -36.50030546
OS -5.3231161 -36.50030546
OS -5.3231161 -36.61402634
OE
OB -0.10721086 -36.61402634 I
OS -0.67442842 -36.61402634
OS -0.67442842 -36.90664958
OS -0.1432687 -36.90664958
OS -0.1432687 -37.02037046
OS -0.67442842 -37.02037046
OS -0.67442842 -37.34627786
OS -0.08502142 -37.34627786
OS -0.08502142 -37.45999874
OS -0.8020177 -37.45999874
OS -0.8020177 -36.50030546
OS -0.10721086 -36.50030546
OS -0.10721086 -36.61402634
OE
OB -8.43241138 -37.34627786 I
OS -7.95949894 -37.34627786
OS -7.95949894 -37.45999874
OS -8.56000066 -37.45999874
OS -8.56000066 -36.50030546
OS -8.43241138 -36.50030546
OS -8.43241138 -37.34627786
OE
OB -6.51718534 -37.05365462 I
OS -6.51718534 -37.45999874
OS -6.64477462 -37.45999874
OS -6.64477462 -37.05365462
OS -7.0150609 -36.50030546
OS -6.86112166 -36.50030546
OS -6.67251142 -36.79154186
OS -6.67251142 -36.7929287
OS -6.66973774 -36.79570238
OS -6.66696406 -36.7998629
OS -6.66419038 -36.80541026
OS -6.65864302 -36.81234446
OS -6.65309566 -36.8206655
OS -6.6406141 -36.8414681
OS -6.62535886 -36.86643122
OS -6.60871678 -36.89416802
OS -6.59068786 -36.92329166
OS -6.57404578 -36.95380214
OS -6.57404578 -36.9524153
OS -6.57265894 -36.94964162
OS -6.56988526 -36.9454811
OS -6.56572474 -36.93993374
OS -6.56156422 -36.93299954
OS -6.55601686 -36.9246785
OS -6.5435353 -36.9038759
OS -6.52828006 -36.87891278
OS -6.51025114 -36.84978914
OS -6.48944854 -36.81789182
OS -6.4672591 -36.78322082
OS -6.28280938 -36.50030546
OS -6.1344175 -36.50030546
OS -6.51718534 -37.05365462
OE
OB -7.01644774 -37.45999874 I
OS -7.1606791 -37.45999874
OS -7.27301314 -37.16876234
OS -7.67519674 -37.16876234
OS -7.77920974 -37.45999874
OS -7.91373322 -37.45999874
OS -7.54760746 -36.50030546
OS -7.40892346 -36.50030546
OS -7.01644774 -37.45999874
OE
OB -7.48103914 -36.60015794 H
OS -7.48103914 -36.60154478
OS -7.48242598 -36.60431846
OS -7.48242598 -36.60986582
OS -7.48519966 -36.61541318
OS -7.4865865 -36.62512106
OS -7.48936018 -36.63482894
OS -7.49490754 -36.65840522
OS -7.50184174 -36.68614202
OS -7.51154962 -36.7166525
OS -7.5212575 -36.74993666
OS -7.53373906 -36.78460766
OS -7.63775206 -37.06474934
OS -7.3132315 -37.06474934
OS -7.41308398 -36.80124974
OS -7.41308398 -36.7998629
OS -7.41447082 -36.79570238
OS -7.4172445 -36.78876818
OS -7.42001818 -36.78044714
OS -7.4241787 -36.77073926
OS -7.42833922 -36.7582577
OS -7.43249974 -36.7443893
OS -7.4380471 -36.7305209
OS -7.44914182 -36.69862358
OS -7.46023654 -36.66533942
OS -7.47133126 -36.63205526
OS -7.48103914 -36.60015794
OE
OB -4.69349074 -36.60709214 H
OS -4.99582186 -36.60709214
OS -4.99582186 -36.9246785
OS -4.71013282 -36.9246785
OS -4.69349074 -36.92329166
OS -4.67407498 -36.92190482
OS -4.65188554 -36.92051798
OS -4.6296961 -36.9177443
OS -4.60750666 -36.91358378
OS -4.5880909 -36.90803642
OS -4.58531722 -36.90664958
OS -4.57976986 -36.9038759
OS -4.57144882 -36.89971538
OS -4.5603541 -36.89416802
OS -4.54787254 -36.88584698
OS -4.53539098 -36.8761391
OS -4.52290942 -36.86365754
OS -4.51320154 -36.84978914
OS -4.5118147 -36.8484023
OS -4.50904102 -36.84285494
OS -4.5048805 -36.8345339
OS -4.49933314 -36.82343918
OS -4.49517262 -36.81095762
OS -4.4910121 -36.79708922
OS -4.48823842 -36.78044714
OS -4.48685158 -36.76380506
OS -4.48685158 -36.76241822
OS -4.48685158 -36.76103138
OS -4.48823842 -36.75271034
OS -4.48962526 -36.74022878
OS -4.49239894 -36.7235867
OS -4.49933314 -36.70694462
OS -4.50765418 -36.68752886
OS -4.52013574 -36.66949994
OS -4.53677782 -36.65147102
OS -4.5395515 -36.65008418
OS -4.5464857 -36.64453682
OS -4.55758042 -36.63760262
OS -4.57560934 -36.62928158
OS -4.59641194 -36.62096054
OS -4.62414874 -36.61402634
OS -4.65604606 -36.60847898
OS -4.69349074 -36.60709214
OE
OB -2.48841514 -36.60015794 H
OS -2.48841514 -36.60154478
OS -2.48980198 -36.60431846
OS -2.48980198 -36.60986582
OS -2.49257566 -36.61541318
OS -2.4939625 -36.62512106
OS -2.49673618 -36.63482894
OS -2.50228354 -36.65840522
OS -2.50921774 -36.68614202
OS -2.51892562 -36.7166525
OS -2.5286335 -36.74993666
OS -2.54111506 -36.78460766
OS -2.64512806 -37.06474934
OS -2.3206075 -37.06474934
OS -2.42045998 -36.80124974
OS -2.42045998 -36.7998629
OS -2.42184682 -36.79570238
OS -2.4246205 -36.78876818
OS -2.42739418 -36.78044714
OS -2.4315547 -36.77073926
OS -2.43571522 -36.7582577
OS -2.43987574 -36.7443893
OS -2.4454231 -36.7305209
OS -2.45651782 -36.69862358
OS -2.46761254 -36.66533942
OS -2.47870726 -36.63205526
OS -2.48841514 -36.60015794
OE
SE
S P 0
OB 35.73690338 -37.45999874 I
OS 35.61486146 -37.45999874
OS 35.61486146 -36.65701838
OS 35.33471978 -37.45999874
OS 35.2209989 -37.45999874
OS 34.9436309 -36.64314998
OS 34.9436309 -37.45999874
OS 34.82158898 -37.45999874
OS 34.82158898 -36.50030546
OS 35.01158606 -36.50030546
OS 35.23902782 -37.1812439
OS 35.23902782 -37.18263074
OS 35.24041466 -37.18540442
OS 35.2418015 -37.18956494
OS 35.24457518 -37.19649914
OS 35.25012254 -37.21314122
OS 35.25705674 -37.23394382
OS 35.26399094 -37.2575201
OS 35.27231198 -37.28109638
OS 35.27924618 -37.30328582
OS 35.28479354 -37.32270158
OS 35.28618038 -37.3199279
OS 35.28756722 -37.3129937
OS 35.29172774 -37.30051214
OS 35.2972751 -37.28387006
OS 35.3042093 -37.26168062
OS 35.31391718 -37.23533066
OS 35.32362506 -37.20482018
OS 35.33610662 -37.16876234
OS 35.56632206 -36.50030546
OS 35.73690338 -36.50030546
OS 35.73690338 -37.45999874
OE
OB 34.61356298 -37.05504146 I
OS 34.61356298 -37.0564283
OS 34.61356298 -37.06197566
OS 34.61356298 -37.06890986
OS 34.61356298 -37.07861774
OS 34.61217614 -37.0910993
OS 34.61217614 -37.1049677
OS 34.6107893 -37.12160978
OS 34.60940246 -37.13825186
OS 34.60524194 -37.17569654
OS 34.59969458 -37.21452806
OS 34.59137354 -37.25197274
OS 34.58582618 -37.27000166
OS 34.58027882 -37.28664374
OS 34.58027882 -37.28803058
OS 34.57889198 -37.29080426
OS 34.5761183 -37.29496478
OS 34.57334462 -37.30051214
OS 34.56502358 -37.31576738
OS 34.55254202 -37.33518314
OS 34.53589994 -37.35737258
OS 34.51648418 -37.37956202
OS 34.49152106 -37.4031383
OS 34.46101058 -37.4239409
OS 34.45962374 -37.4239409
OS 34.45685006 -37.42671458
OS 34.45268954 -37.42810142
OS 34.44575534 -37.43226194
OS 34.4374343 -37.43642246
OS 34.42633958 -37.44058298
OS 34.41524486 -37.4447435
OS 34.40137646 -37.45029086
OS 34.38612122 -37.45583822
OS 34.36947914 -37.45999874
OS 34.35145022 -37.46415926
OS 34.33064762 -37.46831978
OS 34.30984502 -37.47109346
OS 34.28765558 -37.47386714
OS 34.23772934 -37.47664082
OS 34.22524778 -37.47664082
OS 34.2155399 -37.47525398
OS 34.20444518 -37.47525398
OS 34.19057678 -37.47386714
OS 34.17532154 -37.4724803
OS 34.1600663 -37.47109346
OS 34.1253953 -37.4655461
OS 34.08795062 -37.45722506
OS 34.05189278 -37.44613034
OS 34.01722178 -37.4308751
OS 34.01583494 -37.4308751
OS 34.01306126 -37.42810142
OS 34.00890074 -37.42532774
OS 34.00335338 -37.42255406
OS 33.98809814 -37.41145934
OS 33.97006922 -37.3962041
OS 33.94926662 -37.37678834
OS 33.92985086 -37.3545989
OS 33.9104351 -37.3268621
OS 33.89517986 -37.29635162
OS 33.89517986 -37.29496478
OS 33.89379302 -37.2921911
OS 33.89240618 -37.28664374
OS 33.8896325 -37.27970954
OS 33.88685882 -37.2713885
OS 33.88408514 -37.26029378
OS 33.87992462 -37.24781222
OS 33.87715094 -37.23255698
OS 33.87437726 -37.2159149
OS 33.87021674 -37.19788598
OS 33.86744306 -37.17847022
OS 33.86466938 -37.15766762
OS 33.8618957 -37.13409134
OS 33.86050886 -37.10912822
OS 33.85912202 -37.08277826
OS 33.85912202 -37.05504146
OS 33.85912202 -36.50030546
OS 33.9867113 -36.50030546
OS 33.9867113 -37.05504146
OS 33.9867113 -37.0564283
OS 33.9867113 -37.06058882
OS 33.9867113 -37.06752302
OS 33.9867113 -37.07584406
OS 33.98809814 -37.08555194
OS 33.98809814 -37.0980335
OS 33.98948498 -37.12438346
OS 33.99225866 -37.15489394
OS 33.99641918 -37.18540442
OS 34.00196654 -37.21452806
OS 34.00474022 -37.22700962
OS 34.00890074 -37.23949118
OS 34.01028758 -37.24226486
OS 34.01306126 -37.24919906
OS 34.01999546 -37.25890694
OS 34.0283165 -37.27277534
OS 34.03802438 -37.28664374
OS 34.05189278 -37.30189898
OS 34.06853486 -37.31715422
OS 34.08795062 -37.32963578
OS 34.0907243 -37.33102262
OS 34.0976585 -37.33518314
OS 34.11014006 -37.33934366
OS 34.12678214 -37.34489102
OS 34.1461979 -37.35182522
OS 34.17116102 -37.35598574
OS 34.19751098 -37.36014626
OS 34.22663462 -37.3615331
OS 34.24050302 -37.3615331
OS 34.24882406 -37.36014626
OS 34.26130562 -37.36014626
OS 34.27378718 -37.35875942
OS 34.30429766 -37.35321206
OS 34.33758182 -37.34627786
OS 34.36947914 -37.33518314
OS 34.39998962 -37.3199279
OS 34.41385802 -37.31022002
OS 34.42633958 -37.2991253
OS 34.42772642 -37.29773846
OS 34.42911326 -37.29635162
OS 34.43188694 -37.2921911
OS 34.43604746 -37.28664374
OS 34.44020798 -37.2783227
OS 34.44575534 -37.27000166
OS 34.4513027 -37.2575201
OS 34.45685006 -37.24503854
OS 34.46239742 -37.2297833
OS 34.46655794 -37.21175438
OS 34.4721053 -37.19095178
OS 34.47626582 -37.16876234
OS 34.48042634 -37.14379922
OS 34.48320002 -37.11744926
OS 34.4859737 -37.08693878
OS 34.4859737 -37.05504146
OS 34.4859737 -36.50030546
OS 34.61356298 -36.50030546
OS 34.61356298 -37.05504146
OE
OB 33.64416182 -37.45999874 I
OS 33.51241202 -37.45999874
OS 33.01037594 -36.70694462
OS 33.01037594 -37.45999874
OS 32.88833402 -37.45999874
OS 32.88833402 -36.50030546
OS 33.01869698 -36.50030546
OS 33.5221199 -37.25474642
OS 33.5221199 -36.50030546
OS 33.64416182 -36.50030546
OS 33.64416182 -37.45999874
OE
OB 38.19022334 -36.5016923 I
OS 38.2027049 -36.5016923
OS 38.23182854 -36.50307914
OS 38.26233902 -36.50723966
OS 38.29562318 -36.51140018
OS 38.32613366 -36.51833438
OS 38.3413889 -36.5224949
OS 38.35387046 -36.52665542
OS 38.3552573 -36.52665542
OS 38.35664414 -36.52804226
OS 38.36496518 -36.53220278
OS 38.37744674 -36.53775014
OS 38.39270198 -36.54745802
OS 38.40934406 -36.55993958
OS 38.42737298 -36.57658166
OS 38.44401506 -36.59599742
OS 38.46065714 -36.61818686
OS 38.46065714 -36.6195737
OS 38.46204398 -36.62096054
OS 38.46759134 -36.62928158
OS 38.4731387 -36.64314998
OS 38.48145974 -36.6611789
OS 38.48839394 -36.6819815
OS 38.49532814 -36.70694462
OS 38.49948866 -36.73329458
OS 38.5008755 -36.76241822
OS 38.5008755 -36.76380506
OS 38.5008755 -36.76657874
OS 38.5008755 -36.7721261
OS 38.49948866 -36.7790603
OS 38.49948866 -36.78876818
OS 38.49810182 -36.79847606
OS 38.49255446 -36.82205234
OS 38.48423342 -36.84978914
OS 38.4731387 -36.87891278
OS 38.45649662 -36.90803642
OS 38.4454019 -36.92190482
OS 38.43430718 -36.93577322
OS 38.43292034 -36.93716006
OS 38.4315335 -36.9385469
OS 38.42737298 -36.94270742
OS 38.42182562 -36.94686794
OS 38.41489142 -36.9524153
OS 38.40657038 -36.95796266
OS 38.39547566 -36.96489686
OS 38.38438094 -36.9732179
OS 38.37051254 -36.9801521
OS 38.3552573 -36.9870863
OS 38.33861522 -36.99540734
OS 38.3205863 -37.00234154
OS 38.2997837 -37.0078889
OS 38.2789811 -37.0148231
OS 38.25540482 -37.01898362
OS 38.2304417 -37.02314414
OS 38.23321538 -37.02453098
OS 38.23876274 -37.02730466
OS 38.24708378 -37.03285202
OS 38.2581785 -37.03839938
OS 38.28314162 -37.05365462
OS 38.29562318 -37.0633625
OS 38.3067179 -37.07168354
OS 38.30949158 -37.07445722
OS 38.31642578 -37.08139142
OS 38.3275205 -37.09248614
OS 38.3413889 -37.10635454
OS 38.35664414 -37.1257703
OS 38.37467306 -37.1465729
OS 38.39270198 -37.17153602
OS 38.41211774 -37.19927282
OS 38.5771517 -37.45999874
OS 38.41905194 -37.45999874
OS 38.2928495 -37.26029378
OS 38.2928495 -37.25890694
OS 38.29007582 -37.25613326
OS 38.28730214 -37.25197274
OS 38.28314162 -37.24642538
OS 38.27343374 -37.23117014
OS 38.26095218 -37.21175438
OS 38.24569694 -37.19095178
OS 38.2304417 -37.16876234
OS 38.21518646 -37.14795974
OS 38.20131806 -37.12854398
OS 38.19993122 -37.12715714
OS 38.1957707 -37.12160978
OS 38.1888365 -37.11328874
OS 38.17912862 -37.10358086
OS 38.15832602 -37.08277826
OS 38.1472313 -37.07307038
OS 38.13613658 -37.06474934
OS 38.13474974 -37.0633625
OS 38.13197606 -37.06197566
OS 38.1264287 -37.05920198
OS 38.11810766 -37.05504146
OS 38.10978662 -37.05088094
OS 38.10007874 -37.04672042
OS 38.0778893 -37.03978622
OS 38.07650246 -37.03978622
OS 38.07372878 -37.03839938
OS 38.06818142 -37.03839938
OS 38.06124722 -37.03701254
OS 38.05153934 -37.0356257
OS 38.04044462 -37.0356257
OS 38.02518938 -37.03423886
OS 37.86154226 -37.03423886
OS 37.86154226 -37.45999874
OS 37.73395298 -37.45999874
OS 37.73395298 -36.50030546
OS 38.17912862 -36.50030546
OS 38.19022334 -36.5016923
OE
OB 37.53424802 -36.61402634 I
OS 36.96703046 -36.61402634
OS 36.96703046 -36.90664958
OS 37.49819018 -36.90664958
OS 37.49819018 -37.02037046
OS 36.96703046 -37.02037046
OS 36.96703046 -37.34627786
OS 37.55643746 -37.34627786
OS 37.55643746 -37.45999874
OS 36.83944118 -37.45999874
OS 36.83944118 -36.50030546
OS 37.53424802 -36.50030546
OS 37.53424802 -36.61402634
OE
OB 36.32492354 -36.5016923 I
OS 36.33601826 -36.5016923
OS 36.36098138 -36.50446598
OS 36.38871818 -36.50723966
OS 36.41784182 -36.51278702
OS 36.44696546 -36.51972122
OS 36.47331542 -36.5294291
OS 36.47470226 -36.5294291
OS 36.4760891 -36.53081594
OS 36.48441014 -36.53497646
OS 36.4968917 -36.54191066
OS 36.5107601 -36.55161854
OS 36.52740218 -36.5641001
OS 36.5454311 -36.57935534
OS 36.56207318 -36.5987711
OS 36.57732842 -36.6195737
OS 36.57871526 -36.62234738
OS 36.58287578 -36.63066842
OS 36.58980998 -36.64176314
OS 36.59674418 -36.65840522
OS 36.60367838 -36.67782098
OS 36.61061258 -36.69862358
OS 36.6147731 -36.72219986
OS 36.61615994 -36.74577614
OS 36.61615994 -36.74854982
OS 36.61615994 -36.75548402
OS 36.6147731 -36.76796558
OS 36.61199942 -36.78322082
OS 36.6078389 -36.80124974
OS 36.6009047 -36.8206655
OS 36.59258366 -36.84008126
OS 36.58148894 -36.86088386
OS 36.5801021 -36.86365754
OS 36.57594158 -36.8692049
OS 36.56762054 -36.88029962
OS 36.55652582 -36.89139434
OS 36.54265742 -36.90526274
OS 36.52601534 -36.92051798
OS 36.50521274 -36.93438638
OS 36.48163646 -36.94825478
OS 36.4830233 -36.94825478
OS 36.48579698 -36.94964162
OS 36.4899575 -36.95102846
OS 36.49550486 -36.95380214
OS 36.51214694 -36.9593495
OS 36.5315627 -36.96905738
OS 36.5523653 -36.98153894
OS 36.57594158 -36.99679418
OS 36.59674418 -37.0148231
OS 36.61615994 -37.03701254
OS 36.61754678 -37.03978622
OS 36.62309414 -37.04810726
OS 36.63141518 -37.06058882
OS 36.63973622 -37.0772309
OS 36.64805726 -37.09942034
OS 36.6563783 -37.12299662
OS 36.66192566 -37.15073342
OS 36.6633125 -37.1812439
OS 36.6633125 -37.18263074
OS 36.6633125 -37.18401758
OS 36.6633125 -37.19233862
OS 36.66192566 -37.20620702
OS 36.65915198 -37.2228491
OS 36.6563783 -37.24226486
OS 36.65083094 -37.26306746
OS 36.64389674 -37.2852569
OS 36.63418886 -37.30744634
OS 36.63280202 -37.31022002
OS 36.6286415 -37.31715422
OS 36.62309414 -37.3268621
OS 36.6147731 -37.3407305
OS 36.60367838 -37.3545989
OS 36.59258366 -37.36985414
OS 36.57871526 -37.38510938
OS 36.56346002 -37.39759094
OS 36.56207318 -37.39897778
OS 36.55652582 -37.4031383
OS 36.54681794 -37.40868566
OS 36.53433638 -37.41423302
OS 36.51908114 -37.42255406
OS 36.50105222 -37.4308751
OS 36.48163646 -37.4378093
OS 36.45806018 -37.4447435
OS 36.4552865 -37.4447435
OS 36.44696546 -37.44751718
OS 36.43309706 -37.44890402
OS 36.41506814 -37.4516777
OS 36.3928787 -37.45445138
OS 36.36652874 -37.45722506
OS 36.3374051 -37.4586119
OS 36.30412094 -37.45999874
OS 35.93799518 -37.45999874
OS 35.93799518 -36.50030546
OS 36.31521566 -36.50030546
OS 36.32492354 -36.5016923
OE
OB 32.3849111 -36.61402634 I
OS 32.06871158 -36.61402634
OS 32.06871158 -37.45999874
OS 31.9411223 -37.45999874
OS 31.9411223 -36.61402634
OS 31.62492278 -36.61402634
OS 31.62492278 -36.50030546
OS 32.3849111 -36.50030546
OS 32.3849111 -36.61402634
OE
OB 30.62639798 -37.45999874 I
OS 30.48216662 -37.45999874
OS 30.36983258 -37.16876234
OS 29.96764898 -37.16876234
OS 29.86363598 -37.45999874
OS 29.7291125 -37.45999874
OS 30.09523826 -36.50030546
OS 30.23392226 -36.50030546
OS 30.62639798 -37.45999874
OE
OB 29.3546657 -36.5016923 I
OS 29.37824198 -36.50307914
OS 29.4032051 -36.50446598
OS 29.42678138 -36.50723966
OS 29.44758398 -36.51001334
OS 29.45035766 -36.51001334
OS 29.46006554 -36.51278702
OS 29.4725471 -36.5155607
OS 29.48918918 -36.51972122
OS 29.5072181 -36.52665542
OS 29.52663386 -36.53497646
OS 29.54743646 -36.54468434
OS 29.56546538 -36.55577906
OS 29.56823906 -36.5571659
OS 29.57378642 -36.56132642
OS 29.58210746 -36.56964746
OS 29.59320218 -36.57935534
OS 29.60568374 -36.5918369
OS 29.6181653 -36.60847898
OS 29.6320337 -36.6265079
OS 29.64312842 -36.6473105
OS 29.64451526 -36.65008418
OS 29.64728894 -36.65701838
OS 29.6528363 -36.66949994
OS 29.65838366 -36.68614202
OS 29.66254418 -36.70555778
OS 29.66809154 -36.72774722
OS 29.67086522 -36.75271034
OS 29.67225206 -36.7790603
OS 29.67225206 -36.78044714
OS 29.67225206 -36.78460766
OS 29.67225206 -36.79015502
OS 29.67086522 -36.7998629
OS 29.66947838 -36.80957078
OS 29.66809154 -36.82205234
OS 29.66531786 -36.83592074
OS 29.66254418 -36.85117598
OS 29.6528363 -36.8830733
OS 29.64728894 -36.89971538
OS 29.6389679 -36.9177443
OS 29.62926002 -36.93577322
OS 29.61955214 -36.9524153
OS 29.60707058 -36.96905738
OS 29.59320218 -36.98569946
OS 29.59181534 -36.9870863
OS 29.58904166 -36.98985998
OS 29.58488114 -36.9940205
OS 29.57794694 -36.99818102
OS 29.5696259 -37.00511522
OS 29.55853118 -37.01204942
OS 29.54466278 -37.02037046
OS 29.52940754 -37.02730466
OS 29.51137862 -37.0356257
OS 29.49057602 -37.04394674
OS 29.46838658 -37.05088094
OS 29.44203662 -37.0564283
OS 29.41429982 -37.06197566
OS 29.38378934 -37.06613618
OS 29.34911834 -37.06890986
OS 29.3130605 -37.0702967
OS 29.06758982 -37.0702967
OS 29.06758982 -37.45999874
OS 28.94000054 -37.45999874
OS 28.94000054 -36.50030546
OS 29.3338631 -36.50030546
OS 29.3546657 -36.5016923
OE
OB 31.18668134 -36.5016923 I
OS 31.1991629 -36.5016923
OS 31.22828654 -36.50307914
OS 31.25879702 -36.50723966
OS 31.29208118 -36.51140018
OS 31.32259166 -36.51833438
OS 31.3378469 -36.5224949
OS 31.35032846 -36.52665542
OS 31.3517153 -36.52665542
OS 31.35310214 -36.52804226
OS 31.36142318 -36.53220278
OS 31.37390474 -36.53775014
OS 31.38915998 -36.54745802
OS 31.40580206 -36.55993958
OS 31.42383098 -36.57658166
OS 31.44047306 -36.59599742
OS 31.45711514 -36.61818686
OS 31.45711514 -36.6195737
OS 31.45850198 -36.62096054
OS 31.46404934 -36.62928158
OS 31.4695967 -36.64314998
OS 31.47791774 -36.6611789
OS 31.48485194 -36.6819815
OS 31.49178614 -36.70694462
OS 31.49594666 -36.73329458
OS 31.4973335 -36.76241822
OS 31.4973335 -36.76380506
OS 31.4973335 -36.76657874
OS 31.4973335 -36.7721261
OS 31.49594666 -36.7790603
OS 31.49594666 -36.78876818
OS 31.49455982 -36.79847606
OS 31.48901246 -36.82205234
OS 31.48069142 -36.84978914
OS 31.4695967 -36.87891278
OS 31.45295462 -36.90803642
OS 31.4418599 -36.92190482
OS 31.43076518 -36.93577322
OS 31.42937834 -36.93716006
OS 31.4279915 -36.9385469
OS 31.42383098 -36.94270742
OS 31.41828362 -36.94686794
OS 31.41134942 -36.9524153
OS 31.40302838 -36.95796266
OS 31.39193366 -36.96489686
OS 31.38083894 -36.9732179
OS 31.36697054 -36.9801521
OS 31.3517153 -36.9870863
OS 31.33507322 -36.99540734
OS 31.3170443 -37.00234154
OS 31.2962417 -37.0078889
OS 31.2754391 -37.0148231
OS 31.25186282 -37.01898362
OS 31.2268997 -37.02314414
OS 31.22967338 -37.02453098
OS 31.23522074 -37.02730466
OS 31.24354178 -37.03285202
OS 31.2546365 -37.03839938
OS 31.27959962 -37.05365462
OS 31.29208118 -37.0633625
OS 31.3031759 -37.07168354
OS 31.30594958 -37.07445722
OS 31.31288378 -37.08139142
OS 31.3239785 -37.09248614
OS 31.3378469 -37.10635454
OS 31.35310214 -37.1257703
OS 31.37113106 -37.1465729
OS 31.38915998 -37.17153602
OS 31.40857574 -37.19927282
OS 31.5736097 -37.45999874
OS 31.41550994 -37.45999874
OS 31.2893075 -37.26029378
OS 31.2893075 -37.25890694
OS 31.28653382 -37.25613326
OS 31.28376014 -37.25197274
OS 31.27959962 -37.24642538
OS 31.26989174 -37.23117014
OS 31.25741018 -37.21175438
OS 31.24215494 -37.19095178
OS 31.2268997 -37.16876234
OS 31.21164446 -37.14795974
OS 31.19777606 -37.12854398
OS 31.19638922 -37.12715714
OS 31.1922287 -37.12160978
OS 31.1852945 -37.11328874
OS 31.17558662 -37.10358086
OS 31.15478402 -37.08277826
OS 31.1436893 -37.07307038
OS 31.13259458 -37.06474934
OS 31.13120774 -37.0633625
OS 31.12843406 -37.06197566
OS 31.1228867 -37.05920198
OS 31.11456566 -37.05504146
OS 31.10624462 -37.05088094
OS 31.09653674 -37.04672042
OS 31.0743473 -37.03978622
OS 31.07296046 -37.03978622
OS 31.07018678 -37.03839938
OS 31.06463942 -37.03839938
OS 31.05770522 -37.03701254
OS 31.04799734 -37.0356257
OS 31.03690262 -37.0356257
OS 31.02164738 -37.03423886
OS 30.85800026 -37.03423886
OS 30.85800026 -37.45999874
OS 30.73041098 -37.45999874
OS 30.73041098 -36.50030546
OS 31.17558662 -36.50030546
OS 31.18668134 -36.5016923
OE
OB 38.16387338 -36.60709214 H
OS 37.86154226 -36.60709214
OS 37.86154226 -36.9246785
OS 38.1472313 -36.9246785
OS 38.16387338 -36.92329166
OS 38.18328914 -36.92190482
OS 38.20547858 -36.92051798
OS 38.22766802 -36.9177443
OS 38.24985746 -36.91358378
OS 38.26927322 -36.90803642
OS 38.2720469 -36.90664958
OS 38.27759426 -36.9038759
OS 38.2859153 -36.89971538
OS 38.29701002 -36.89416802
OS 38.30949158 -36.88584698
OS 38.32197314 -36.8761391
OS 38.3344547 -36.86365754
OS 38.34416258 -36.84978914
OS 38.34554942 -36.8484023
OS 38.3483231 -36.84285494
OS 38.35248362 -36.8345339
OS 38.35803098 -36.82343918
OS 38.3621915 -36.81095762
OS 38.36635202 -36.79708922
OS 38.3691257 -36.78044714
OS 38.37051254 -36.76380506
OS 38.37051254 -36.76241822
OS 38.37051254 -36.76103138
OS 38.3691257 -36.75271034
OS 38.36773886 -36.74022878
OS 38.36496518 -36.7235867
OS 38.35803098 -36.70694462
OS 38.34970994 -36.68752886
OS 38.33722838 -36.66949994
OS 38.3205863 -36.65147102
OS 38.31781262 -36.65008418
OS 38.31087842 -36.64453682
OS 38.2997837 -36.63760262
OS 38.28175478 -36.62928158
OS 38.26095218 -36.62096054
OS 38.23321538 -36.61402634
OS 38.20131806 -36.60847898
OS 38.16387338 -36.60709214
OE
OB 29.34218414 -36.61402634 H
OS 29.06758982 -36.61402634
OS 29.06758982 -36.95657582
OS 29.32554206 -36.95657582
OS 29.33524994 -36.95518898
OS 29.34495782 -36.95518898
OS 29.35605254 -36.95380214
OS 29.3824025 -36.95102846
OS 29.41152614 -36.9454811
OS 29.44064978 -36.93716006
OS 29.46699974 -36.92606534
OS 29.4794813 -36.91913114
OS 29.48918918 -36.9108101
OS 29.49196286 -36.90803642
OS 29.49751022 -36.90248906
OS 29.50583126 -36.89139434
OS 29.51553914 -36.87752594
OS 29.52524702 -36.85949702
OS 29.53356806 -36.83730758
OS 29.53911542 -36.81234446
OS 29.5418891 -36.78322082
OS 29.5418891 -36.78183398
OS 29.5418891 -36.78044714
OS 29.5418891 -36.77351294
OS 29.54050226 -36.76103138
OS 29.53772858 -36.74716298
OS 29.5349549 -36.73190774
OS 29.52940754 -36.71387882
OS 29.5210865 -36.69723674
OS 29.51137862 -36.68059466
OS 29.50999178 -36.67920782
OS 29.50583126 -36.67366046
OS 29.49889706 -36.66672626
OS 29.49057602 -36.65701838
OS 29.47809446 -36.6473105
OS 29.46422606 -36.63898946
OS 29.44897082 -36.63066842
OS 29.4309419 -36.62373422
OS 29.42955506 -36.62373422
OS 29.4240077 -36.62234738
OS 29.41568666 -36.62096054
OS 29.40459194 -36.61818686
OS 29.38794986 -36.61680002
OS 29.36714726 -36.61541318
OS 29.34218414 -36.61402634
OE
OB 30.16180658 -36.60015794 H
OS 30.16180658 -36.60154478
OS 30.16041974 -36.60431846
OS 30.16041974 -36.60986582
OS 30.15764606 -36.61541318
OS 30.15625922 -36.62512106
OS 30.15348554 -36.63482894
OS 30.14793818 -36.65840522
OS 30.14100398 -36.68614202
OS 30.1312961 -36.7166525
OS 30.12158822 -36.74993666
OS 30.10910666 -36.78460766
OS 30.00509366 -37.06474934
OS 30.32961422 -37.06474934
OS 30.22976174 -36.80124974
OS 30.22976174 -36.7998629
OS 30.2283749 -36.79570238
OS 30.22560122 -36.78876818
OS 30.22282754 -36.78044714
OS 30.21866702 -36.77073926
OS 30.2145065 -36.7582577
OS 30.21034598 -36.7443893
OS 30.20479862 -36.7305209
OS 30.1937039 -36.69862358
OS 30.18260918 -36.66533942
OS 30.17151446 -36.63205526
OS 30.16180658 -36.60015794
OE
OB 31.16033138 -36.60709214 H
OS 30.85800026 -36.60709214
OS 30.85800026 -36.9246785
OS 31.1436893 -36.9246785
OS 31.16033138 -36.92329166
OS 31.17974714 -36.92190482
OS 31.20193658 -36.92051798
OS 31.22412602 -36.9177443
OS 31.24631546 -36.91358378
OS 31.26573122 -36.90803642
OS 31.2685049 -36.90664958
OS 31.27405226 -36.9038759
OS 31.2823733 -36.89971538
OS 31.29346802 -36.89416802
OS 31.30594958 -36.88584698
OS 31.31843114 -36.8761391
OS 31.3309127 -36.86365754
OS 31.34062058 -36.84978914
OS 31.34200742 -36.8484023
OS 31.3447811 -36.84285494
OS 31.34894162 -36.8345339
OS 31.35448898 -36.82343918
OS 31.3586495 -36.81095762
OS 31.36281002 -36.79708922
OS 31.3655837 -36.78044714
OS 31.36697054 -36.76380506
OS 31.36697054 -36.76241822
OS 31.36697054 -36.76103138
OS 31.3655837 -36.75271034
OS 31.36419686 -36.74022878
OS 31.36142318 -36.7235867
OS 31.35448898 -36.70694462
OS 31.34616794 -36.68752886
OS 31.33368638 -36.66949994
OS 31.3170443 -36.65147102
OS 31.31427062 -36.65008418
OS 31.30733642 -36.64453682
OS 31.2962417 -36.63760262
OS 31.27821278 -36.62928158
OS 31.25741018 -36.62096054
OS 31.22967338 -36.61402634
OS 31.19777606 -36.60847898
OS 31.16033138 -36.60709214
OE
OB 36.29302622 -36.61402634 H
OS 36.06558446 -36.61402634
OS 36.06558446 -36.90248906
OS 36.30134726 -36.90248906
OS 36.31937618 -36.90110222
OS 36.33879194 -36.89971538
OS 36.3582077 -36.89832854
OS 36.37762346 -36.89555486
OS 36.3928787 -36.89278118
OS 36.39565238 -36.89139434
OS 36.40119974 -36.8900075
OS 36.40952078 -36.88584698
OS 36.4206155 -36.88029962
OS 36.43171022 -36.87475226
OS 36.44419178 -36.86643122
OS 36.45667334 -36.8553365
OS 36.46638122 -36.84424178
OS 36.46776806 -36.84285494
OS 36.47054174 -36.83869442
OS 36.47470226 -36.83037338
OS 36.47886278 -36.8206655
OS 36.4830233 -36.80957078
OS 36.48718382 -36.79570238
OS 36.4899575 -36.7790603
OS 36.49134434 -36.76103138
OS 36.49134434 -36.7582577
OS 36.49134434 -36.75271034
OS 36.4899575 -36.7443893
OS 36.48857066 -36.73329458
OS 36.48579698 -36.71942618
OS 36.48163646 -36.70555778
OS 36.4760891 -36.69168938
OS 36.46776806 -36.67782098
OS 36.46638122 -36.67643414
OS 36.46360754 -36.67227362
OS 36.45806018 -36.66533942
OS 36.45112598 -36.65840522
OS 36.4414181 -36.65008418
OS 36.43032338 -36.64176314
OS 36.41645498 -36.6334421
OS 36.40119974 -36.62789474
OS 36.3998129 -36.62789474
OS 36.3928787 -36.62512106
OS 36.38317082 -36.62373422
OS 36.36791558 -36.62096054
OS 36.34711298 -36.61818686
OS 36.3235367 -36.61680002
OS 36.29302622 -36.61402634
OE
OB 36.31798934 -37.01620994 H
OS 36.06558446 -37.01620994
OS 36.06558446 -37.34627786
OS 36.33879194 -37.34627786
OS 36.36791558 -37.34489102
OS 36.38039714 -37.34350418
OS 36.39149186 -37.34211734
OS 36.3928787 -37.34211734
OS 36.39842606 -37.3407305
OS 36.4067471 -37.33934366
OS 36.41645498 -37.33656998
OS 36.44003126 -37.32824894
OS 36.46360754 -37.31715422
OS 36.46499438 -37.31576738
OS 36.4691549 -37.3129937
OS 36.47470226 -37.30883318
OS 36.48163646 -37.30328582
OS 36.48857066 -37.29496478
OS 36.49827854 -37.28664374
OS 36.50521274 -37.27554902
OS 36.51353378 -37.26306746
OS 36.51492062 -37.26168062
OS 36.51630746 -37.2575201
OS 36.51908114 -37.24919906
OS 36.52324166 -37.23949118
OS 36.52740218 -37.22839646
OS 36.53017586 -37.21452806
OS 36.5315627 -37.19788598
OS 36.53294954 -37.1812439
OS 36.53294954 -37.17847022
OS 36.53294954 -37.17292286
OS 36.5315627 -37.16182814
OS 36.52878902 -37.14934658
OS 36.52601534 -37.13547818
OS 36.52046798 -37.12022294
OS 36.51353378 -37.1049677
OS 36.5038259 -37.08971246
OS 36.50243906 -37.08832562
OS 36.49827854 -37.08277826
OS 36.49273118 -37.07584406
OS 36.48441014 -37.06752302
OS 36.47331542 -37.05781514
OS 36.45944702 -37.04810726
OS 36.44419178 -37.03978622
OS 36.42616286 -37.03285202
OS 36.42338918 -37.03146518
OS 36.41784182 -37.03007834
OS 36.40536026 -37.02730466
OS 36.39010502 -37.02453098
OS 36.37068926 -37.0217573
OS 36.34711298 -37.01898362
OS 36.31798934 -37.01620994
OE
SE
S P 0
OB 40.9056459 -38.32112732 I
OS 40.92136342 -38.32205188
OS 40.9380055 -38.32297644
OS 40.95372302 -38.32482556
OS 40.96759142 -38.32667468
OS 40.96944054 -38.32667468
OS 40.97591246 -38.3285238
OS 40.9842335 -38.33037292
OS 40.99532822 -38.3331466
OS 41.0073475 -38.3377694
OS 41.02029134 -38.34331676
OS 41.03415974 -38.34978868
OS 41.04617902 -38.35718516
OS 41.04802814 -38.35810972
OS 41.05172638 -38.3608834
OS 41.05727374 -38.36643076
OS 41.06467022 -38.37290268
OS 41.07299126 -38.38122372
OS 41.0813123 -38.39231844
OS 41.0905579 -38.40433772
OS 41.09795438 -38.41820612
OS 41.09887894 -38.42005524
OS 41.10072806 -38.42467804
OS 41.1044263 -38.43299908
OS 41.10812454 -38.4440938
OS 41.11089822 -38.45703764
OS 41.11459646 -38.4718306
OS 41.11644558 -38.48847268
OS 41.11737014 -38.50603932
OS 41.11737014 -38.50696388
OS 41.11737014 -38.50973756
OS 41.11737014 -38.5134358
OS 41.11644558 -38.51990772
OS 41.11552102 -38.52637964
OS 41.11459646 -38.53470068
OS 41.11274734 -38.54394628
OS 41.11089822 -38.55411644
OS 41.1044263 -38.57538132
OS 41.10072806 -38.58647604
OS 41.0951807 -38.59849532
OS 41.08870878 -38.6105146
OS 41.08223686 -38.62160932
OS 41.07391582 -38.63270404
OS 41.06467022 -38.64379876
OS 41.06374566 -38.64472332
OS 41.06189654 -38.64657244
OS 41.05912286 -38.64934612
OS 41.05450006 -38.6521198
OS 41.0489527 -38.6567426
OS 41.04155622 -38.6613654
OS 41.03231062 -38.66691276
OS 41.02214046 -38.67153556
OS 41.01012118 -38.67708292
OS 40.99625278 -38.68263028
OS 40.98145982 -38.68725308
OS 40.96389318 -38.69095132
OS 40.94540198 -38.69464956
OS 40.92506166 -38.69742324
OS 40.90194766 -38.69927236
OS 40.8779091 -38.70019692
OS 40.71426198 -38.70019692
OS 40.71426198 -38.95999828
OS 40.62920246 -38.95999828
OS 40.62920246 -38.32020276
OS 40.8917775 -38.32020276
OS 40.9056459 -38.32112732
OE
OB 40.49791494 -38.98403684 I
OS 40.49791494 -38.9849614
OS 40.49791494 -38.98773508
OS 40.49791494 -38.99235788
OS 40.49791494 -38.99790524
OS 40.49699038 -39.00530172
OS 40.49699038 -39.0126982
OS 40.49514126 -39.0311894
OS 40.49236758 -39.05060516
OS 40.48866934 -39.07094548
OS 40.48312198 -39.08851212
OS 40.47942374 -39.09683316
OS 40.4757255 -39.10330508
OS 40.4757255 -39.10422964
OS 40.47480094 -39.1051542
OS 40.47017814 -39.109777
OS 40.46278166 -39.11717348
OS 40.45353606 -39.12549452
OS 40.44059222 -39.13381556
OS 40.42395014 -39.14028748
OS 40.40453438 -39.14583484
OS 40.39343966 -39.1467594
OS 40.38142038 -39.14768396
OS 40.37587302 -39.14768396
OS 40.37032566 -39.1467594
OS 40.36200462 -39.1467594
OS 40.35275902 -39.14583484
OS 40.34258886 -39.14398572
OS 40.32039942 -39.13843836
OS 40.33519238 -39.07187004
OS 40.33611694 -39.07187004
OS 40.33889062 -39.0727946
OS 40.34351342 -39.07371916
OS 40.34813622 -39.07464372
OS 40.3601555 -39.0774174
OS 40.36570286 -39.07834196
OS 40.37494846 -39.07834196
OS 40.37957126 -39.0774174
OS 40.38511862 -39.07649284
OS 40.39066598 -39.07464372
OS 40.39621334 -39.07094548
OS 40.40268526 -39.06724724
OS 40.40730806 -39.06169988
OS 40.40823262 -39.06077532
OS 40.40915718 -39.05800164
OS 40.4110063 -39.05337884
OS 40.41377998 -39.04598236
OS 40.4156291 -39.0358122
OS 40.41655366 -39.02841572
OS 40.41747822 -39.0219438
OS 40.41840278 -39.01362276
OS 40.41840278 -39.0034526
OS 40.41932734 -38.99328244
OS 40.41932734 -38.98218772
OS 40.41932734 -38.49586916
OS 40.49791494 -38.49586916
OS 40.49791494 -38.98403684
OE
OB 41.51770462 -38.3100326 I
OS 41.52602566 -38.31095716
OS 41.53619582 -38.31188172
OS 41.54636598 -38.31280628
OS 41.55838526 -38.31557996
OS 41.58334838 -38.32112732
OS 41.61108518 -38.32944836
OS 41.62495358 -38.33499572
OS 41.63789742 -38.34146764
OS 41.65084126 -38.34978868
OS 41.6637851 -38.35810972
OS 41.66470966 -38.35903428
OS 41.66655878 -38.35995884
OS 41.67025702 -38.36273252
OS 41.67487982 -38.36735532
OS 41.67950262 -38.37197812
OS 41.68597454 -38.37845004
OS 41.69244646 -38.38584652
OS 41.69984294 -38.393243
OS 41.70723942 -38.4024886
OS 41.7146359 -38.41358332
OS 41.72295694 -38.42467804
OS 41.73035342 -38.43669732
OS 41.73682534 -38.45056572
OS 41.74422182 -38.46443412
OS 41.74976918 -38.47922708
OS 41.75531654 -38.49586916
OS 41.67210614 -38.51528492
OS 41.67210614 -38.51436036
OS 41.67118158 -38.51251124
OS 41.66933246 -38.508813
OS 41.66748334 -38.5041902
OS 41.66563422 -38.49864284
OS 41.66286054 -38.49124636
OS 41.65546406 -38.4764534
OS 41.64621846 -38.45981132
OS 41.63512374 -38.44316924
OS 41.62125534 -38.42745172
OS 41.60646238 -38.41358332
OS 41.60461326 -38.4117342
OS 41.5990659 -38.40803596
OS 41.5898203 -38.40341316
OS 41.57780102 -38.39694124
OS 41.5620835 -38.39139388
OS 41.54451686 -38.38584652
OS 41.52325198 -38.38214828
OS 41.50013798 -38.38122372
OS 41.4927415 -38.38122372
OS 41.4881187 -38.38214828
OS 41.48164678 -38.38214828
OS 41.4742503 -38.38307284
OS 41.45668366 -38.38584652
OS 41.4372679 -38.38954476
OS 41.41692758 -38.39601668
OS 41.3956627 -38.40526228
OS 41.37624694 -38.41728156
OS 41.37532238 -38.41728156
OS 41.37439782 -38.41913068
OS 41.3679259 -38.42375348
OS 41.35960486 -38.43114996
OS 41.3494347 -38.44224468
OS 41.33741542 -38.45611308
OS 41.3263207 -38.4718306
OS 41.31615054 -38.49124636
OS 41.30690494 -38.51251124
OS 41.30690494 -38.5134358
OS 41.30598038 -38.51528492
OS 41.30505582 -38.5180586
OS 41.30413126 -38.5226814
OS 41.30228214 -38.52822876
OS 41.30043302 -38.53470068
OS 41.29765934 -38.5504182
OS 41.2939611 -38.5689094
OS 41.29026286 -38.58924972
OS 41.28841374 -38.61143916
OS 41.28748918 -38.63547772
OS 41.28748918 -38.63640228
OS 41.28748918 -38.63917596
OS 41.28748918 -38.64379876
OS 41.28748918 -38.64934612
OS 41.28841374 -38.65581804
OS 41.28841374 -38.66413908
OS 41.2893383 -38.67338468
OS 41.29026286 -38.68355484
OS 41.29303654 -38.70574428
OS 41.29765934 -38.72978284
OS 41.3032067 -38.7538214
OS 41.31060318 -38.77785996
OS 41.31060318 -38.77878452
OS 41.31152774 -38.78063364
OS 41.31337686 -38.78340732
OS 41.31522598 -38.78803012
OS 41.32077334 -38.79912484
OS 41.32909438 -38.81206868
OS 41.33926454 -38.82686164
OS 41.35220838 -38.84257916
OS 41.36700134 -38.85644756
OS 41.38456798 -38.8693914
OS 41.38549254 -38.8693914
OS 41.38734166 -38.87031596
OS 41.39011534 -38.87216508
OS 41.39381358 -38.8740142
OS 41.39843638 -38.87586332
OS 41.40398374 -38.878637
OS 41.41692758 -38.88418436
OS 41.43356966 -38.88973172
OS 41.45206086 -38.89435452
OS 41.47240118 -38.89805276
OS 41.49366606 -38.89897732
OS 41.50013798 -38.89897732
OS 41.50568534 -38.89805276
OS 41.51215726 -38.89805276
OS 41.51862918 -38.8971282
OS 41.53527126 -38.89342996
OS 41.55468702 -38.88880716
OS 41.57410278 -38.88141068
OS 41.5944431 -38.87124052
OS 41.60461326 -38.86569316
OS 41.61385886 -38.85829668
OS 41.61478342 -38.85737212
OS 41.61570798 -38.85644756
OS 41.61848166 -38.85367388
OS 41.6221799 -38.8509002
OS 41.62587814 -38.8462774
OS 41.63050094 -38.84073004
OS 41.6360483 -38.83518268
OS 41.6406711 -38.8277862
OS 41.64621846 -38.81946516
OS 41.65269038 -38.81021956
OS 41.65823774 -38.80097396
OS 41.6637851 -38.78987924
OS 41.6684079 -38.77785996
OS 41.6730307 -38.76491612
OS 41.6776535 -38.75104772
OS 41.68135174 -38.73625476
OS 41.76641126 -38.75751964
OS 41.76641126 -38.7584442
OS 41.7654867 -38.76214244
OS 41.76363758 -38.7676898
OS 41.7608639 -38.77508628
OS 41.75809022 -38.78340732
OS 41.75439198 -38.79357748
OS 41.74976918 -38.8046722
OS 41.74422182 -38.81669148
OS 41.73127798 -38.84257916
OS 41.7146359 -38.86846684
OS 41.70446574 -38.88141068
OS 41.69429558 -38.89435452
OS 41.68320086 -38.90544924
OS 41.67025702 -38.91654396
OS 41.66933246 -38.91746852
OS 41.66748334 -38.91931764
OS 41.66286054 -38.92116676
OS 41.65823774 -38.924865
OS 41.65084126 -38.9294878
OS 41.64344478 -38.9341106
OS 41.63327462 -38.9387334
OS 41.62310446 -38.9433562
OS 41.61108518 -38.94890356
OS 41.59814134 -38.95352636
OS 41.58427294 -38.95814916
OS 41.56947998 -38.96277196
OS 41.55376246 -38.9664702
OS 41.53712038 -38.96831932
OS 41.51955374 -38.97016844
OS 41.50106254 -38.971093
OS 41.49089238 -38.971093
OS 41.4834959 -38.97016844
OS 41.47517486 -38.97016844
OS 41.4650047 -38.96924388
OS 41.45390998 -38.96739476
OS 41.44096614 -38.96554564
OS 41.4141539 -38.96092284
OS 41.3864171 -38.95352636
OS 41.3586803 -38.9433562
OS 41.34573646 -38.93688428
OS 41.33279262 -38.9294878
OS 41.33186806 -38.92856324
OS 41.33001894 -38.92763868
OS 41.3263207 -38.924865
OS 41.32262246 -38.92116676
OS 41.3170751 -38.91746852
OS 41.31060318 -38.91192116
OS 41.3032067 -38.90544924
OS 41.29581022 -38.89805276
OS 41.28841374 -38.88973172
OS 41.2800927 -38.88141068
OS 41.26345062 -38.8601458
OS 41.2477331 -38.83518268
OS 41.2338647 -38.80744588
OS 41.2338647 -38.80652132
OS 41.23201558 -38.80374764
OS 41.23109102 -38.79912484
OS 41.22831734 -38.79357748
OS 41.22646822 -38.786181
OS 41.22369454 -38.7769354
OS 41.2199963 -38.76676524
OS 41.21722262 -38.75567052
OS 41.21444894 -38.74365124
OS 41.2107507 -38.72978284
OS 41.2061279 -38.70112148
OS 41.20242966 -38.66876188
OS 41.20058054 -38.63547772
OS 41.20058054 -38.63455316
OS 41.20058054 -38.63085492
OS 41.20058054 -38.62530756
OS 41.2015051 -38.61883564
OS 41.2015051 -38.60959004
OS 41.20242966 -38.60034444
OS 41.20335422 -38.58832516
OS 41.20520334 -38.57630588
OS 41.20982614 -38.54949364
OS 41.21629806 -38.51990772
OS 41.22554366 -38.4903218
OS 41.2384875 -38.46166044
OS 41.23941206 -38.46073588
OS 41.24033662 -38.4579622
OS 41.24218574 -38.45426396
OS 41.24588398 -38.44964116
OS 41.24958222 -38.44316924
OS 41.25420502 -38.43577276
OS 41.2662243 -38.41913068
OS 41.28194182 -38.40063948
OS 41.30043302 -38.38214828
OS 41.3216979 -38.36365708
OS 41.34666102 -38.34793956
OS 41.34758558 -38.347015
OS 41.35035926 -38.34609044
OS 41.3540575 -38.34424132
OS 41.3586803 -38.34146764
OS 41.36607678 -38.33869396
OS 41.37347326 -38.33592028
OS 41.38271886 -38.33222204
OS 41.39288902 -38.3285238
OS 41.40398374 -38.32482556
OS 41.41600302 -38.32112732
OS 41.4418907 -38.31557996
OS 41.47147662 -38.31095716
OS 41.5019871 -38.30910804
OS 41.5112327 -38.30910804
OS 41.51770462 -38.3100326
OE
OB 42.90454462 -39.1375138 I
OS 42.38401734 -39.1375138
OS 42.38401734 -39.08111564
OS 42.90454462 -39.08111564
OS 42.90454462 -39.1375138
OE
OB 42.12514054 -38.32112732 I
OS 42.13253702 -38.32112732
OS 42.1491791 -38.32297644
OS 42.1676703 -38.32482556
OS 42.18708606 -38.3285238
OS 42.20650182 -38.3331466
OS 42.22406846 -38.33961852
OS 42.22499302 -38.33961852
OS 42.22591758 -38.34054308
OS 42.23146494 -38.34331676
OS 42.23978598 -38.34793956
OS 42.24903158 -38.35441148
OS 42.2601263 -38.36273252
OS 42.27214558 -38.37290268
OS 42.2832403 -38.38584652
OS 42.29341046 -38.39971492
OS 42.29433502 -38.40156404
OS 42.2971087 -38.4071114
OS 42.3017315 -38.41450788
OS 42.3063543 -38.4256026
OS 42.3109771 -38.43854644
OS 42.3155999 -38.45241484
OS 42.31837358 -38.46813236
OS 42.31929814 -38.48384988
OS 42.31929814 -38.485699
OS 42.31929814 -38.4903218
OS 42.31837358 -38.49864284
OS 42.31652446 -38.508813
OS 42.31375078 -38.52083228
OS 42.30912798 -38.53377612
OS 42.30358062 -38.54671996
OS 42.29618414 -38.56058836
OS 42.29525958 -38.56243748
OS 42.2924859 -38.56613572
OS 42.28693854 -38.5735322
OS 42.27954206 -38.58092868
OS 42.27029646 -38.59017428
OS 42.25920174 -38.60034444
OS 42.24533334 -38.60959004
OS 42.22961582 -38.61883564
OS 42.23054038 -38.61883564
OS 42.2323895 -38.6197602
OS 42.23516318 -38.62068476
OS 42.23886142 -38.62253388
OS 42.24995614 -38.62623212
OS 42.26289998 -38.63270404
OS 42.27676838 -38.64102508
OS 42.2924859 -38.65119524
OS 42.3063543 -38.66321452
OS 42.31929814 -38.67800748
OS 42.3202227 -38.6798566
OS 42.32392094 -38.68540396
OS 42.3294683 -38.693725
OS 42.33501566 -38.70481972
OS 42.34056302 -38.71961268
OS 42.34611038 -38.7353302
OS 42.34980862 -38.7538214
OS 42.35073318 -38.77416172
OS 42.35073318 -38.77508628
OS 42.35073318 -38.77601084
OS 42.35073318 -38.7815582
OS 42.34980862 -38.7908038
OS 42.3479595 -38.80189852
OS 42.34611038 -38.81484236
OS 42.34241214 -38.82871076
OS 42.33778934 -38.84350372
OS 42.33131742 -38.85829668
OS 42.33039286 -38.8601458
OS 42.32761918 -38.8647686
OS 42.32392094 -38.87124052
OS 42.31837358 -38.88048612
OS 42.3109771 -38.88973172
OS 42.30358062 -38.89990188
OS 42.29433502 -38.91007204
OS 42.28416486 -38.91839308
OS 42.2832403 -38.91931764
OS 42.27954206 -38.92209132
OS 42.27307014 -38.92578956
OS 42.2647491 -38.9294878
OS 42.25457894 -38.93503516
OS 42.24255966 -38.94058252
OS 42.22961582 -38.94520532
OS 42.2138983 -38.94982812
OS 42.21204918 -38.94982812
OS 42.20650182 -38.95167724
OS 42.19725622 -38.9526018
OS 42.18523694 -38.95445092
OS 42.17044398 -38.95630004
OS 42.15287734 -38.95814916
OS 42.13346158 -38.95907372
OS 42.11127214 -38.95999828
OS 41.8671883 -38.95999828
OS 41.8671883 -38.32020276
OS 42.11866862 -38.32020276
OS 42.12514054 -38.32112732
OE
OB 40.30745558 -38.48662356 I
OS 40.31762574 -38.48847268
OS 40.32964502 -38.49217092
OS 40.34258886 -38.49679372
OS 40.35738182 -38.50326564
OS 40.37309934 -38.51158668
OS 40.34443798 -38.58370236
OS 40.34351342 -38.5827778
OS 40.33981518 -38.58092868
OS 40.33426782 -38.578155
OS 40.32687134 -38.57538132
OS 40.3185503 -38.57260764
OS 40.30838014 -38.56983396
OS 40.29820998 -38.56798484
OS 40.28803982 -38.56706028
OS 40.28341702 -38.56706028
OS 40.27879422 -38.56798484
OS 40.2723223 -38.5689094
OS 40.26585038 -38.57075852
OS 40.25752934 -38.5735322
OS 40.2492083 -38.57723044
OS 40.24181182 -38.5827778
OS 40.24088726 -38.58370236
OS 40.23811358 -38.58555148
OS 40.2353399 -38.58924972
OS 40.2307171 -38.59387252
OS 40.2260943 -38.60034444
OS 40.2214715 -38.60774092
OS 40.2168487 -38.61606196
OS 40.21315046 -38.62623212
OS 40.2122259 -38.62808124
OS 40.21130134 -38.6336286
OS 40.20945222 -38.64194964
OS 40.20667854 -38.65304436
OS 40.20390486 -38.66691276
OS 40.20205574 -38.68263028
OS 40.20113118 -38.69927236
OS 40.20020662 -38.71776356
OS 40.20020662 -38.95999828
OS 40.12161902 -38.95999828
OS 40.12161902 -38.49586916
OS 40.19281014 -38.49586916
OS 40.19281014 -38.56613572
OS 40.1937347 -38.56521116
OS 40.19743294 -38.55873924
OS 40.20205574 -38.5504182
OS 40.20945222 -38.54024804
OS 40.2168487 -38.53007788
OS 40.22516974 -38.51898316
OS 40.23349078 -38.50973756
OS 40.24181182 -38.50234108
OS 40.24273638 -38.50141652
OS 40.24551006 -38.4995674
OS 40.25105742 -38.49679372
OS 40.25660478 -38.49402004
OS 40.26400126 -38.49124636
OS 40.27324686 -38.48847268
OS 40.28249246 -38.48662356
OS 40.29266262 -38.485699
OS 40.29913454 -38.485699
OS 40.30745558 -38.48662356
OE
OB 39.48829542 -38.95999828 I
OS 39.3986131 -38.95999828
OS 39.3986131 -38.87031596
OS 39.48829542 -38.87031596
OS 39.48829542 -38.95999828
OE
OB 38.6404739 -38.95999828 I
OS 38.55171614 -38.95999828
OS 38.30393406 -38.32020276
OS 38.39639006 -38.32020276
OS 38.56281086 -38.78525644
OS 38.56281086 -38.786181
OS 38.56373542 -38.78803012
OS 38.56465998 -38.7908038
OS 38.5665091 -38.79450204
OS 38.56743366 -38.8000494
OS 38.56928278 -38.80559676
OS 38.57390558 -38.81946516
OS 38.57945294 -38.83518268
OS 38.5850003 -38.85274932
OS 38.59609502 -38.88973172
OS 38.59609502 -38.88880716
OS 38.59701958 -38.88695804
OS 38.59794414 -38.88418436
OS 38.5988687 -38.88048612
OS 38.60164238 -38.87031596
OS 38.60626518 -38.85644756
OS 38.61088798 -38.84073004
OS 38.61643534 -38.8231634
OS 38.62290726 -38.8046722
OS 38.63030374 -38.78525644
OS 38.80412102 -38.32020276
OS 38.8901051 -38.32020276
OS 38.6404739 -38.95999828
OE
OB 39.27564662 -38.42745172 I
OS 39.25438174 -38.54671996
OS 39.20538006 -38.54671996
OS 39.1859643 -38.42745172
OS 39.1859643 -38.32020276
OS 39.27564662 -38.32020276
OS 39.27564662 -38.42745172
OE
OB 40.49791494 -38.4117342 I
OS 40.41932734 -38.4117342
OS 40.41932734 -38.32020276
OS 40.49791494 -38.32020276
OS 40.49791494 -38.4117342
OE
OB 39.84517558 -38.48662356 I
OS 39.8516475 -38.48754812
OS 39.8655159 -38.48939724
OS 39.88215798 -38.49309548
OS 39.89972462 -38.49864284
OS 39.91729126 -38.50696388
OS 39.9348579 -38.51713404
OS 39.93578246 -38.51713404
OS 39.93670702 -38.51898316
OS 39.94225438 -38.5226814
OS 39.95057542 -38.53007788
OS 39.96074558 -38.53932348
OS 39.9718403 -38.55134276
OS 39.98293502 -38.56613572
OS 39.99402974 -38.58370236
OS 40.00327534 -38.60311812
OS 40.00327534 -38.60404268
OS 40.0041999 -38.6058918
OS 40.00512446 -38.60866548
OS 40.00697358 -38.61236372
OS 40.0088227 -38.61791108
OS 40.01067182 -38.624383
OS 40.01529462 -38.63917596
OS 40.01991742 -38.65766716
OS 40.02361566 -38.67800748
OS 40.02638934 -38.70112148
OS 40.0273139 -38.72516004
OS 40.0273139 -38.7260846
OS 40.0273139 -38.72793372
OS 40.0273139 -38.73163196
OS 40.0273139 -38.73717932
OS 40.02638934 -38.74365124
OS 40.02638934 -38.75104772
OS 40.02454022 -38.7676898
OS 40.02084198 -38.78803012
OS 40.01621918 -38.809295
OS 40.00974726 -38.83148444
OS 40.00142622 -38.85367388
OS 40.00142622 -38.85459844
OS 40.00050166 -38.85644756
OS 39.99865254 -38.85922124
OS 39.99680342 -38.86291948
OS 39.9903315 -38.87308964
OS 39.98201046 -38.88603348
OS 39.9718403 -38.89990188
OS 39.95889646 -38.91377028
OS 39.9441035 -38.92763868
OS 39.92653686 -38.94058252
OS 39.9256123 -38.94058252
OS 39.92468774 -38.94150708
OS 39.92191406 -38.9433562
OS 39.91821582 -38.94520532
OS 39.90897022 -38.94982812
OS 39.89602638 -38.95537548
OS 39.88030886 -38.96092284
OS 39.86366678 -38.96554564
OS 39.84425102 -38.96924388
OS 39.82483526 -38.97016844
OS 39.81836334 -38.97016844
OS 39.81096686 -38.96924388
OS 39.80172126 -38.96831932
OS 39.79062654 -38.9664702
OS 39.77860726 -38.96369652
OS 39.76658798 -38.95999828
OS 39.7545687 -38.95445092
OS 39.75364414 -38.95352636
OS 39.74902134 -38.95167724
OS 39.74347398 -38.947979
OS 39.7360775 -38.94243164
OS 39.72868102 -38.93688428
OS 39.71943542 -38.9294878
OS 39.71111438 -38.92116676
OS 39.7037179 -38.91192116
OS 39.7037179 -39.1375138
OS 39.6251303 -39.1375138
OS 39.6251303 -38.49586916
OS 39.69632142 -38.49586916
OS 39.69632142 -38.55689012
OS 39.69724598 -38.555041
OS 39.70094422 -38.55134276
OS 39.70556702 -38.54487084
OS 39.7129635 -38.53747436
OS 39.72128454 -38.52822876
OS 39.73053014 -38.51990772
OS 39.74162486 -38.51158668
OS 39.75271958 -38.5041902
OS 39.7545687 -38.50326564
OS 39.75826694 -38.50141652
OS 39.76566342 -38.49864284
OS 39.77490902 -38.4949446
OS 39.78600374 -38.49124636
OS 39.79894758 -38.48847268
OS 39.81374054 -38.48662356
OS 39.83038262 -38.485699
OS 39.84055278 -38.485699
OS 39.84517558 -38.48662356
OE
OB 44.92193454 -38.40988508 I
OS 44.84334694 -38.40988508
OS 44.84334694 -38.32020276
OS 44.92193454 -38.32020276
OS 44.92193454 -38.40988508
OE
OB 45.24553054 -38.48662356 I
OS 45.25385158 -38.48754812
OS 45.26309718 -38.48939724
OS 45.27326734 -38.49124636
OS 45.28528662 -38.49309548
OS 45.31024974 -38.50141652
OS 45.32319358 -38.50603932
OS 45.33613742 -38.51251124
OS 45.34908126 -38.51898316
OS 45.3620251 -38.52822876
OS 45.37404438 -38.53747436
OS 45.38606366 -38.54856908
OS 45.38698822 -38.54949364
OS 45.38883734 -38.55134276
OS 45.39161102 -38.555041
OS 45.39530926 -38.5596638
OS 45.39993206 -38.56613572
OS 45.40547942 -38.57445676
OS 45.41102678 -38.58370236
OS 45.41657414 -38.59387252
OS 45.4221215 -38.60496724
OS 45.42766886 -38.61883564
OS 45.43321622 -38.63270404
OS 45.43783902 -38.64842156
OS 45.44153726 -38.66506364
OS 45.44431094 -38.68263028
OS 45.44616006 -38.70112148
OS 45.44708462 -38.7214618
OS 45.44708462 -38.72238636
OS 45.44708462 -38.72516004
OS 45.44708462 -38.72978284
OS 45.44708462 -38.73625476
OS 45.44616006 -38.74365124
OS 45.4452355 -38.75289684
OS 45.4452355 -38.76214244
OS 45.44338638 -38.7723126
OS 45.4406127 -38.7954266
OS 45.43506534 -38.8185406
OS 45.42859342 -38.8416546
OS 45.41934782 -38.86291948
OS 45.41934782 -38.86384404
OS 45.41842326 -38.8647686
OS 45.41657414 -38.86754228
OS 45.41472502 -38.87124052
OS 45.4082531 -38.88048612
OS 45.39993206 -38.89158084
OS 45.38883734 -38.90452468
OS 45.37496894 -38.91746852
OS 45.35925142 -38.93041236
OS 45.34076022 -38.94243164
OS 45.33983566 -38.94243164
OS 45.3389111 -38.9433562
OS 45.33613742 -38.94520532
OS 45.33151462 -38.94705444
OS 45.32689182 -38.94890356
OS 45.32134446 -38.95075268
OS 45.30747606 -38.95630004
OS 45.29175854 -38.96092284
OS 45.27234278 -38.96554564
OS 45.25200246 -38.96924388
OS 45.22981302 -38.97016844
OS 45.22056742 -38.97016844
OS 45.21317094 -38.96924388
OS 45.2048499 -38.96831932
OS 45.1956043 -38.9664702
OS 45.18450958 -38.96462108
OS 45.17341486 -38.96277196
OS 45.14845174 -38.95537548
OS 45.13458334 -38.94982812
OS 45.1216395 -38.94428076
OS 45.10869566 -38.93688428
OS 45.09575182 -38.92856324
OS 45.08373254 -38.91931764
OS 45.07171326 -38.90822292
OS 45.0707887 -38.90729836
OS 45.06893958 -38.90544924
OS 45.0661659 -38.901751
OS 45.06246766 -38.89620364
OS 45.05784486 -38.88973172
OS 45.05322206 -38.88233524
OS 45.0476747 -38.87308964
OS 45.04212734 -38.86199492
OS 45.03657998 -38.84997564
OS 45.03103262 -38.83610724
OS 45.02640982 -38.82131428
OS 45.02178702 -38.80559676
OS 45.01808878 -38.78803012
OS 45.0153151 -38.76953892
OS 45.01346598 -38.7491986
OS 45.01254142 -38.72793372
OS 45.01254142 -38.7260846
OS 45.01254142 -38.72238636
OS 45.01346598 -38.71591444
OS 45.01346598 -38.70666884
OS 45.01439054 -38.69649868
OS 45.01623966 -38.68355484
OS 45.01808878 -38.670611
OS 45.02178702 -38.65581804
OS 45.02548526 -38.64102508
OS 45.03010806 -38.62530756
OS 45.03565542 -38.60866548
OS 45.0430519 -38.59294796
OS 45.05044838 -38.578155
OS 45.06061854 -38.56336204
OS 45.0707887 -38.54949364
OS 45.08373254 -38.53747436
OS 45.0846571 -38.5365498
OS 45.08650622 -38.53562524
OS 45.09020446 -38.53285156
OS 45.09482726 -38.52915332
OS 45.10037462 -38.52545508
OS 45.1077711 -38.52083228
OS 45.11516758 -38.51620948
OS 45.12441318 -38.51158668
OS 45.13458334 -38.50696388
OS 45.14567806 -38.50234108
OS 45.17064118 -38.49402004
OS 45.19930254 -38.48754812
OS 45.2140955 -38.48662356
OS 45.22981302 -38.485699
OS 45.23905862 -38.485699
OS 45.24553054 -38.48662356
OE
OB 44.92193454 -38.95999828 I
OS 44.84334694 -38.95999828
OS 44.84334694 -38.49586916
OS 44.92193454 -38.49586916
OS 44.92193454 -38.95999828
OE
OB 46.10722046 -38.42745172 I
OS 46.08595558 -38.54671996
OS 46.0369539 -38.54671996
OS 46.01753814 -38.42745172
OS 46.01753814 -38.32020276
OS 46.10722046 -38.32020276
OS 46.10722046 -38.42745172
OE
OB 45.77160518 -38.48662356 I
OS 45.78177534 -38.48754812
OS 45.79379462 -38.48939724
OS 45.80673846 -38.49217092
OS 45.82060686 -38.49586916
OS 45.8335507 -38.50141652
OS 45.83539982 -38.50234108
OS 45.83909806 -38.5041902
OS 45.84556998 -38.50696388
OS 45.85296646 -38.51158668
OS 45.86221206 -38.51713404
OS 45.8705331 -38.52453052
OS 45.87885414 -38.531927
OS 45.88625062 -38.5411726
OS 45.88717518 -38.54209716
OS 45.8890243 -38.5457954
OS 45.89179798 -38.5504182
OS 45.89642078 -38.55689012
OS 45.90011902 -38.56613572
OS 45.90381726 -38.57538132
OS 45.90844006 -38.58647604
OS 45.91121374 -38.59849532
OS 45.91121374 -38.59941988
OS 45.9121383 -38.60311812
OS 45.91306286 -38.60866548
OS 45.91398742 -38.61606196
OS 45.91398742 -38.62715668
OS 45.91491198 -38.64010052
OS 45.91583654 -38.65581804
OS 45.91583654 -38.6752338
OS 45.91583654 -38.95999828
OS 45.83724894 -38.95999828
OS 45.83724894 -38.67893204
OS 45.83724894 -38.67800748
OS 45.83724894 -38.67708292
OS 45.83724894 -38.670611
OS 45.83724894 -38.66228996
OS 45.83632438 -38.6521198
OS 45.83539982 -38.64010052
OS 45.8335507 -38.62808124
OS 45.83077702 -38.61698652
OS 45.82800334 -38.60681636
OS 45.82800334 -38.6058918
OS 45.82615422 -38.60311812
OS 45.82338054 -38.59849532
OS 45.82060686 -38.59294796
OS 45.81598406 -38.5874006
OS 45.8104367 -38.58092868
OS 45.80304022 -38.57445676
OS 45.79471918 -38.5689094
OS 45.79379462 -38.56798484
OS 45.79102094 -38.56613572
OS 45.78547358 -38.5642866
OS 45.77900166 -38.56151292
OS 45.77160518 -38.55873924
OS 45.76235958 -38.55596556
OS 45.75126486 -38.555041
OS 45.74017014 -38.55411644
OS 45.73554734 -38.55411644
OS 45.7318491 -38.555041
OS 45.7226035 -38.55596556
OS 45.71058422 -38.55781468
OS 45.69764038 -38.56243748
OS 45.68284742 -38.56798484
OS 45.66805446 -38.57538132
OS 45.65418606 -38.58647604
OS 45.65233694 -38.58832516
OS 45.6486387 -38.59294796
OS 45.64586502 -38.5966462
OS 45.64309134 -38.601269
OS 45.6393931 -38.60681636
OS 45.63661942 -38.61328828
OS 45.63292118 -38.62068476
OS 45.62922294 -38.62993036
OS 45.62644926 -38.64010052
OS 45.62367558 -38.65119524
OS 45.62182646 -38.66321452
OS 45.61997734 -38.67615836
OS 45.61812822 -38.69187588
OS 45.61812822 -38.7075934
OS 45.61812822 -38.95999828
OS 45.53954062 -38.95999828
OS 45.53954062 -38.49586916
OS 45.60980718 -38.49586916
OS 45.60980718 -38.56243748
OS 45.61073174 -38.56151292
OS 45.61258086 -38.55873924
OS 45.61535454 -38.555041
OS 45.61905278 -38.5504182
OS 45.62460014 -38.54487084
OS 45.63107206 -38.53839892
OS 45.63846854 -38.53100244
OS 45.64771414 -38.52360596
OS 45.65695974 -38.51713404
OS 45.66805446 -38.50973756
OS 45.68007374 -38.50326564
OS 45.69301758 -38.49771828
OS 45.70781054 -38.49309548
OS 45.7226035 -38.48939724
OS 45.73924558 -38.48662356
OS 45.75681222 -38.485699
OS 45.7642087 -38.485699
OS 45.77160518 -38.48662356
OE
OB 44.2756671 -38.95999828 I
OS 44.1970795 -38.95999828
OS 44.1970795 -38.49586916
OS 44.2756671 -38.49586916
OS 44.2756671 -38.95999828
OE
OB 43.4574315 -38.48662356 I
OS 43.46482798 -38.48754812
OS 43.47407358 -38.48939724
OS 43.48424374 -38.49124636
OS 43.49626302 -38.49402004
OS 43.50735774 -38.49679372
OS 43.52030158 -38.50141652
OS 43.53232086 -38.50603932
OS 43.5452647 -38.51251124
OS 43.55820854 -38.51990772
OS 43.57115238 -38.52822876
OS 43.58317166 -38.53839892
OS 43.59426638 -38.54949364
OS 43.59519094 -38.5504182
OS 43.59704006 -38.55226732
OS 43.59981374 -38.55596556
OS 43.60351198 -38.56151292
OS 43.60813478 -38.56798484
OS 43.61275758 -38.57538132
OS 43.61830494 -38.58462692
OS 43.6238523 -38.59572164
OS 43.62939966 -38.60774092
OS 43.63494702 -38.62068476
OS 43.63956982 -38.63547772
OS 43.64419262 -38.65119524
OS 43.64789086 -38.66876188
OS 43.65066454 -38.68725308
OS 43.65251366 -38.70666884
OS 43.65343822 -38.72793372
OS 43.65343822 -38.72885828
OS 43.65343822 -38.73255652
OS 43.65343822 -38.73902844
OS 43.65251366 -38.74827404
OS 43.30580366 -38.74827404
OS 43.30580366 -38.7491986
OS 43.30580366 -38.75197228
OS 43.30672822 -38.75567052
OS 43.30672822 -38.76121788
OS 43.30765278 -38.7676898
OS 43.3095019 -38.77508628
OS 43.31227558 -38.79172836
OS 43.31782294 -38.81021956
OS 43.32521942 -38.83055988
OS 43.33538958 -38.84905108
OS 43.34833342 -38.86569316
OS 43.34925798 -38.86569316
OS 43.35018254 -38.86754228
OS 43.3557299 -38.87216508
OS 43.36405094 -38.878637
OS 43.37514566 -38.88510892
OS 43.38993862 -38.8925054
OS 43.4065807 -38.89897732
OS 43.4250719 -38.90360012
OS 43.43524206 -38.90452468
OS 43.44633678 -38.90544924
OS 43.45373326 -38.90544924
OS 43.4620543 -38.90452468
OS 43.47222446 -38.90267556
OS 43.48331918 -38.89990188
OS 43.49626302 -38.89620364
OS 43.5082823 -38.89065628
OS 43.52030158 -38.8832598
OS 43.52122614 -38.88233524
OS 43.52584894 -38.878637
OS 43.5313963 -38.87308964
OS 43.53786822 -38.86569316
OS 43.5452647 -38.855523
OS 43.55358574 -38.84257916
OS 43.56190678 -38.8277862
OS 43.56930326 -38.81021956
OS 43.65066454 -38.82038972
OS 43.65066454 -38.82131428
OS 43.64973998 -38.8231634
OS 43.64881542 -38.82686164
OS 43.6469663 -38.832409
OS 43.64419262 -38.83795636
OS 43.64141894 -38.84535284
OS 43.63402246 -38.86107036
OS 43.62477686 -38.878637
OS 43.61183302 -38.8971282
OS 43.59704006 -38.91469484
OS 43.57854886 -38.93133692
OS 43.5776243 -38.93133692
OS 43.57577518 -38.93318604
OS 43.5730015 -38.93503516
OS 43.56930326 -38.93780884
OS 43.5637559 -38.94058252
OS 43.55820854 -38.9433562
OS 43.55081206 -38.94705444
OS 43.54249102 -38.95075268
OS 43.53324542 -38.95445092
OS 43.52399982 -38.95814916
OS 43.50088582 -38.96369652
OS 43.47499814 -38.96831932
OS 43.44633678 -38.97016844
OS 43.43616662 -38.97016844
OS 43.4296947 -38.96924388
OS 43.42137366 -38.96831932
OS 43.4112035 -38.9664702
OS 43.40010878 -38.96462108
OS 43.3880895 -38.96277196
OS 43.36220182 -38.95537548
OS 43.34833342 -38.94982812
OS 43.33538958 -38.94428076
OS 43.32152118 -38.93688428
OS 43.30857734 -38.92856324
OS 43.29655806 -38.91931764
OS 43.28453878 -38.90822292
OS 43.28361422 -38.90729836
OS 43.2817651 -38.90544924
OS 43.27899142 -38.901751
OS 43.27529318 -38.89620364
OS 43.27067038 -38.88973172
OS 43.26604758 -38.88233524
OS 43.26050022 -38.87308964
OS 43.25495286 -38.86291948
OS 43.2494055 -38.8509002
OS 43.24385814 -38.83795636
OS 43.23923534 -38.8231634
OS 43.23461254 -38.80744588
OS 43.2309143 -38.7908038
OS 43.22814062 -38.7723126
OS 43.2262915 -38.75289684
OS 43.22536694 -38.73255652
OS 43.22536694 -38.73163196
OS 43.22536694 -38.72700916
OS 43.22536694 -38.7214618
OS 43.2262915 -38.71314076
OS 43.22721606 -38.7029706
OS 43.22814062 -38.69187588
OS 43.22998974 -38.67893204
OS 43.23276342 -38.6659882
OS 43.2401599 -38.63640228
OS 43.2447827 -38.62160932
OS 43.25033006 -38.6058918
OS 43.25772654 -38.59109884
OS 43.26604758 -38.57723044
OS 43.27529318 -38.56336204
OS 43.28546334 -38.5504182
OS 43.2863879 -38.54949364
OS 43.28823702 -38.54764452
OS 43.29193526 -38.54487084
OS 43.29655806 -38.54024804
OS 43.30210542 -38.53562524
OS 43.3095019 -38.53007788
OS 43.31782294 -38.52360596
OS 43.3279931 -38.5180586
OS 43.33816326 -38.51158668
OS 43.35018254 -38.50603932
OS 43.36312638 -38.50049196
OS 43.37699478 -38.49586916
OS 43.39178774 -38.49124636
OS 43.40750526 -38.48847268
OS 43.42414734 -38.48662356
OS 43.44171398 -38.485699
OS 43.45095958 -38.485699
OS 43.4574315 -38.48662356
OE
OB 43.13938286 -38.48662356 I
OS 43.14955302 -38.48847268
OS 43.1615723 -38.49217092
OS 43.17451614 -38.49679372
OS 43.1893091 -38.50326564
OS 43.20502662 -38.51158668
OS 43.17636526 -38.58370236
OS 43.1754407 -38.5827778
OS 43.17174246 -38.58092868
OS 43.1661951 -38.578155
OS 43.15879862 -38.57538132
OS 43.15047758 -38.57260764
OS 43.14030742 -38.56983396
OS 43.13013726 -38.56798484
OS 43.1199671 -38.56706028
OS 43.1153443 -38.56706028
OS 43.1107215 -38.56798484
OS 43.10424958 -38.5689094
OS 43.09777766 -38.57075852
OS 43.08945662 -38.5735322
OS 43.08113558 -38.57723044
OS 43.0737391 -38.5827778
OS 43.07281454 -38.58370236
OS 43.07004086 -38.58555148
OS 43.06726718 -38.58924972
OS 43.06264438 -38.59387252
OS 43.05802158 -38.60034444
OS 43.05339878 -38.60774092
OS 43.04877598 -38.61606196
OS 43.04507774 -38.62623212
OS 43.04415318 -38.62808124
OS 43.04322862 -38.6336286
OS 43.0413795 -38.64194964
OS 43.03860582 -38.65304436
OS 43.03583214 -38.66691276
OS 43.03398302 -38.68263028
OS 43.03305846 -38.69927236
OS 43.0321339 -38.71776356
OS 43.0321339 -38.95999828
OS 42.9535463 -38.95999828
OS 42.9535463 -38.49586916
OS 43.02473742 -38.49586916
OS 43.02473742 -38.56613572
OS 43.02566198 -38.56521116
OS 43.02936022 -38.55873924
OS 43.03398302 -38.5504182
OS 43.0413795 -38.54024804
OS 43.04877598 -38.53007788
OS 43.05709702 -38.51898316
OS 43.06541806 -38.50973756
OS 43.0737391 -38.50234108
OS 43.07466366 -38.50141652
OS 43.07743734 -38.4995674
OS 43.0829847 -38.49679372
OS 43.08853206 -38.49402004
OS 43.09592854 -38.49124636
OS 43.10517414 -38.48847268
OS 43.11441974 -38.48662356
OS 43.1245899 -38.485699
OS 43.13106182 -38.485699
OS 43.13938286 -38.48662356
OE
OB 43.95022198 -38.95999828 I
OS 43.87533262 -38.95999828
OS 43.70059078 -38.49586916
OS 43.78380118 -38.49586916
OS 43.88365366 -38.77416172
OS 43.88365366 -38.77508628
OS 43.88457822 -38.77601084
OS 43.88550278 -38.77878452
OS 43.88642734 -38.7815582
OS 43.88920102 -38.7908038
OS 43.89289926 -38.80282308
OS 43.89752206 -38.81669148
OS 43.90306942 -38.832409
OS 43.90769222 -38.84997564
OS 43.91323958 -38.86754228
OS 43.91416414 -38.86569316
OS 43.9150887 -38.86107036
OS 43.91786238 -38.85367388
OS 43.92063606 -38.84257916
OS 43.92525886 -38.83055988
OS 43.92988166 -38.81484236
OS 43.93635358 -38.79820028
OS 43.9428255 -38.77970908
OS 44.04545166 -38.49586916
OS 44.12681294 -38.49586916
OS 43.95022198 -38.95999828
OE
OB 44.2756671 -38.40988508 I
OS 44.1970795 -38.40988508
OS 44.1970795 -38.32020276
OS 44.2756671 -38.32020276
OS 44.2756671 -38.40988508
OE
OB 44.5669035 -38.48662356 I
OS 44.5807719 -38.48754812
OS 44.59556486 -38.48939724
OS 44.61128238 -38.49309548
OS 44.62792446 -38.49679372
OS 44.64364198 -38.50234108
OS 44.64456654 -38.50234108
OS 44.6454911 -38.50326564
OS 44.6501139 -38.50511476
OS 44.65751038 -38.508813
OS 44.66675598 -38.5134358
OS 44.67692614 -38.51990772
OS 44.6870963 -38.5273042
OS 44.6963419 -38.53562524
OS 44.70466294 -38.54487084
OS 44.7055875 -38.5457954
OS 44.70743662 -38.54949364
OS 44.71113486 -38.55596556
OS 44.71575766 -38.56336204
OS 44.72038046 -38.57445676
OS 44.72500326 -38.58647604
OS 44.7287015 -38.60034444
OS 44.73239974 -38.61606196
OS 44.65566126 -38.62623212
OS 44.65566126 -38.624383
OS 44.6547367 -38.62068476
OS 44.65288758 -38.61421284
OS 44.6501139 -38.6058918
OS 44.6454911 -38.59757076
OS 44.63994374 -38.58832516
OS 44.63347182 -38.57907956
OS 44.62422622 -38.57075852
OS 44.62330166 -38.56983396
OS 44.61960342 -38.56798484
OS 44.61405606 -38.5642866
OS 44.60573502 -38.56058836
OS 44.59648942 -38.55689012
OS 44.58447014 -38.55319188
OS 44.56967718 -38.55134276
OS 44.55395966 -38.5504182
OS 44.54471406 -38.5504182
OS 44.53546846 -38.55134276
OS 44.52344918 -38.55226732
OS 44.5114299 -38.555041
OS 44.49848606 -38.55781468
OS 44.48646678 -38.56243748
OS 44.47629662 -38.5689094
OS 44.47537206 -38.56983396
OS 44.47259838 -38.57168308
OS 44.46890014 -38.57538132
OS 44.4652019 -38.58092868
OS 44.4605791 -38.58647604
OS 44.45688086 -38.59387252
OS 44.45410718 -38.60219356
OS 44.45318262 -38.6105146
OS 44.45318262 -38.61143916
OS 44.45318262 -38.61328828
OS 44.45410718 -38.61606196
OS 44.45410718 -38.6197602
OS 44.45688086 -38.6290058
OS 44.46242822 -38.6382514
OS 44.46335278 -38.63917596
OS 44.46427734 -38.64010052
OS 44.46612646 -38.6428742
OS 44.4698247 -38.64564788
OS 44.47352294 -38.64842156
OS 44.4790703 -38.6521198
OS 44.48554222 -38.65489348
OS 44.4929387 -38.65859172
OS 44.49386326 -38.65859172
OS 44.49571238 -38.65951628
OS 44.49941062 -38.66044084
OS 44.50588254 -38.66321452
OS 44.51512814 -38.6659882
OS 44.52714742 -38.66876188
OS 44.5345439 -38.67153556
OS 44.54286494 -38.67338468
OS 44.55211054 -38.67615836
OS 44.5622807 -38.67893204
OS 44.56320526 -38.67893204
OS 44.56597894 -38.6798566
OS 44.57060174 -38.68078116
OS 44.5761491 -38.68263028
OS 44.58262102 -38.6844794
OS 44.59094206 -38.68632852
OS 44.6085087 -38.69187588
OS 44.62792446 -38.69742324
OS 44.64734022 -38.70389516
OS 44.66490686 -38.71036708
OS 44.67230334 -38.71314076
OS 44.67877526 -38.71591444
OS 44.68062438 -38.716839
OS 44.68432262 -38.71868812
OS 44.68986998 -38.7214618
OS 44.69819102 -38.7260846
OS 44.70651206 -38.73163196
OS 44.7148331 -38.73902844
OS 44.72315414 -38.74734948
OS 44.73055062 -38.75659508
OS 44.73147518 -38.75751964
OS 44.7333243 -38.76121788
OS 44.73702254 -38.76676524
OS 44.74072078 -38.77508628
OS 44.74349446 -38.78525644
OS 44.7471927 -38.79635116
OS 44.74904182 -38.809295
OS 44.74996638 -38.82408796
OS 44.74996638 -38.82593708
OS 44.74996638 -38.83055988
OS 44.74904182 -38.83795636
OS 44.7471927 -38.84812652
OS 44.74441902 -38.85922124
OS 44.73979622 -38.87124052
OS 44.73424886 -38.88510892
OS 44.72685238 -38.89805276
OS 44.72592782 -38.89990188
OS 44.72222958 -38.90360012
OS 44.71760678 -38.91007204
OS 44.7102103 -38.91746852
OS 44.70004014 -38.92578956
OS 44.68894542 -38.93503516
OS 44.67600158 -38.9433562
OS 44.66028406 -38.95167724
OS 44.6593595 -38.95167724
OS 44.65843494 -38.9526018
OS 44.65288758 -38.95445092
OS 44.64364198 -38.9572246
OS 44.6316227 -38.96092284
OS 44.61682974 -38.96462108
OS 44.60018766 -38.96739476
OS 44.58262102 -38.96924388
OS 44.5622807 -38.97016844
OS 44.55395966 -38.97016844
OS 44.54748774 -38.96924388
OS 44.54009126 -38.96924388
OS 44.53084566 -38.96831932
OS 44.52160006 -38.96739476
OS 44.5114299 -38.96554564
OS 44.48924046 -38.96092284
OS 44.46612646 -38.95445092
OS 44.44393702 -38.94520532
OS 44.43376686 -38.93965796
OS 44.42452126 -38.93318604
OS 44.4235967 -38.93226148
OS 44.42267214 -38.93133692
OS 44.41712478 -38.92578956
OS 44.40880374 -38.91746852
OS 44.39955814 -38.90452468
OS 44.38938798 -38.88880716
OS 44.37921782 -38.87031596
OS 44.37089678 -38.84720196
OS 44.36442486 -38.82131428
OS 44.4420879 -38.809295
OS 44.4420879 -38.81021956
OS 44.4420879 -38.81114412
OS 44.44393702 -38.81669148
OS 44.44578614 -38.82593708
OS 44.44948438 -38.83610724
OS 44.45410718 -38.84720196
OS 44.45965454 -38.85922124
OS 44.46797558 -38.87124052
OS 44.47814574 -38.88141068
OS 44.47999486 -38.88233524
OS 44.4836931 -38.88510892
OS 44.49108958 -38.88880716
OS 44.50033518 -38.89342996
OS 44.51235446 -38.89805276
OS 44.52622286 -38.901751
OS 44.54286494 -38.90452468
OS 44.5622807 -38.90544924
OS 44.5715263 -38.90544924
OS 44.5807719 -38.90452468
OS 44.59279118 -38.90267556
OS 44.60573502 -38.89990188
OS 44.61960342 -38.89620364
OS 44.6316227 -38.89158084
OS 44.64271742 -38.88418436
OS 44.64364198 -38.8832598
OS 44.64734022 -38.88048612
OS 44.65103846 -38.87586332
OS 44.65658582 -38.8693914
OS 44.66120862 -38.86199492
OS 44.66583142 -38.85274932
OS 44.6686051 -38.84350372
OS 44.66952966 -38.832409
OS 44.66952966 -38.83148444
OS 44.66952966 -38.8277862
OS 44.6686051 -38.8231634
OS 44.66675598 -38.81669148
OS 44.6639823 -38.81021956
OS 44.6593595 -38.80374764
OS 44.65381214 -38.79635116
OS 44.6454911 -38.7908038
OS 44.64456654 -38.78987924
OS 44.64179286 -38.78895468
OS 44.63717006 -38.786181
OS 44.62977358 -38.78340732
OS 44.61867886 -38.77970908
OS 44.61220694 -38.7769354
OS 44.60481046 -38.77508628
OS 44.59648942 -38.7723126
OS 44.58724382 -38.76953892
OS 44.57707366 -38.76676524
OS 44.56505438 -38.76399156
OS 44.56412982 -38.76399156
OS 44.56135614 -38.763067
OS 44.55673334 -38.76214244
OS 44.55118598 -38.76029332
OS 44.5437895 -38.7584442
OS 44.53546846 -38.75567052
OS 44.51790182 -38.75104772
OS 44.4975615 -38.7445758
OS 44.47814574 -38.73902844
OS 44.45965454 -38.73255652
OS 44.4513335 -38.72885828
OS 44.44486158 -38.7260846
OS 44.44301246 -38.72516004
OS 44.43931422 -38.72331092
OS 44.43376686 -38.71961268
OS 44.42637038 -38.71498988
OS 44.41804934 -38.70851796
OS 44.4097283 -38.70112148
OS 44.40140726 -38.69280044
OS 44.39401078 -38.68263028
OS 44.39308622 -38.68170572
OS 44.3912371 -38.67800748
OS 44.38846342 -38.67153556
OS 44.38568974 -38.66413908
OS 44.38291606 -38.65489348
OS 44.38014238 -38.64379876
OS 44.37829326 -38.63270404
OS 44.3773687 -38.6197602
OS 44.3773687 -38.61791108
OS 44.3773687 -38.61421284
OS 44.37829326 -38.60866548
OS 44.37921782 -38.60034444
OS 44.38106694 -38.5920234
OS 44.38291606 -38.58185324
OS 44.3866143 -38.57260764
OS 44.3912371 -38.56243748
OS 44.39216166 -38.56151292
OS 44.39401078 -38.55781468
OS 44.39678446 -38.55319188
OS 44.40140726 -38.54671996
OS 44.40695462 -38.54024804
OS 44.41342654 -38.531927
OS 44.42082302 -38.52453052
OS 44.43006862 -38.5180586
OS 44.43099318 -38.51713404
OS 44.43376686 -38.51620948
OS 44.4374651 -38.5134358
OS 44.44301246 -38.51066212
OS 44.45040894 -38.50696388
OS 44.45872998 -38.50326564
OS 44.46890014 -38.4995674
OS 44.47999486 -38.49586916
OS 44.48184398 -38.4949446
OS 44.48554222 -38.49402004
OS 44.49201414 -38.49217092
OS 44.50033518 -38.4903218
OS 44.51050534 -38.48847268
OS 44.52160006 -38.48754812
OS 44.5345439 -38.485699
OS 44.55673334 -38.485699
OS 44.5669035 -38.48662356
OE
OB 33.15968222 -38.32112732 I
OS 33.17539974 -38.32205188
OS 33.19204182 -38.32297644
OS 33.20775934 -38.32482556
OS 33.22162774 -38.32667468
OS 33.22347686 -38.32667468
OS 33.22994878 -38.3285238
OS 33.23826982 -38.33037292
OS 33.24936454 -38.3331466
OS 33.26138382 -38.3377694
OS 33.27432766 -38.34331676
OS 33.28819606 -38.34978868
OS 33.30021534 -38.35718516
OS 33.30206446 -38.35810972
OS 33.3057627 -38.3608834
OS 33.31131006 -38.36643076
OS 33.31870654 -38.37290268
OS 33.32702758 -38.38122372
OS 33.33534862 -38.39231844
OS 33.34459422 -38.40433772
OS 33.3519907 -38.41820612
OS 33.35291526 -38.42005524
OS 33.35476438 -38.42467804
OS 33.35846262 -38.43299908
OS 33.36216086 -38.4440938
OS 33.36493454 -38.45703764
OS 33.36863278 -38.4718306
OS 33.3704819 -38.48847268
OS 33.37140646 -38.50603932
OS 33.37140646 -38.50696388
OS 33.37140646 -38.50973756
OS 33.37140646 -38.5134358
OS 33.3704819 -38.51990772
OS 33.36955734 -38.52637964
OS 33.36863278 -38.53470068
OS 33.36678366 -38.54394628
OS 33.36493454 -38.55411644
OS 33.35846262 -38.57538132
OS 33.35476438 -38.58647604
OS 33.34921702 -38.59849532
OS 33.3427451 -38.6105146
OS 33.33627318 -38.62160932
OS 33.32795214 -38.63270404
OS 33.31870654 -38.64379876
OS 33.31778198 -38.64472332
OS 33.31593286 -38.64657244
OS 33.31315918 -38.64934612
OS 33.30853638 -38.6521198
OS 33.30298902 -38.6567426
OS 33.29559254 -38.6613654
OS 33.28634694 -38.66691276
OS 33.27617678 -38.67153556
OS 33.2641575 -38.67708292
OS 33.2502891 -38.68263028
OS 33.23549614 -38.68725308
OS 33.2179295 -38.69095132
OS 33.1994383 -38.69464956
OS 33.17909798 -38.69742324
OS 33.15598398 -38.69927236
OS 33.13194542 -38.70019692
OS 32.9682983 -38.70019692
OS 32.9682983 -38.95999828
OS 32.88323878 -38.95999828
OS 32.88323878 -38.32020276
OS 33.14581382 -38.32020276
OS 33.15968222 -38.32112732
OE
OB 32.75195126 -38.98403684 I
OS 32.75195126 -38.9849614
OS 32.75195126 -38.98773508
OS 32.75195126 -38.99235788
OS 32.75195126 -38.99790524
OS 32.7510267 -39.00530172
OS 32.7510267 -39.0126982
OS 32.74917758 -39.0311894
OS 32.7464039 -39.05060516
OS 32.74270566 -39.07094548
OS 32.7371583 -39.08851212
OS 32.73346006 -39.09683316
OS 32.72976182 -39.10330508
OS 32.72976182 -39.10422964
OS 32.72883726 -39.1051542
OS 32.72421446 -39.109777
OS 32.71681798 -39.11717348
OS 32.70757238 -39.12549452
OS 32.69462854 -39.13381556
OS 32.67798646 -39.14028748
OS 32.6585707 -39.14583484
OS 32.64747598 -39.1467594
OS 32.6354567 -39.14768396
OS 32.62990934 -39.14768396
OS 32.62436198 -39.1467594
OS 32.61604094 -39.1467594
OS 32.60679534 -39.14583484
OS 32.59662518 -39.14398572
OS 32.57443574 -39.13843836
OS 32.5892287 -39.07187004
OS 32.59015326 -39.07187004
OS 32.59292694 -39.0727946
OS 32.59754974 -39.07371916
OS 32.60217254 -39.07464372
OS 32.61419182 -39.0774174
OS 32.61973918 -39.07834196
OS 32.62898478 -39.07834196
OS 32.63360758 -39.0774174
OS 32.63915494 -39.07649284
OS 32.6447023 -39.07464372
OS 32.65024966 -39.07094548
OS 32.65672158 -39.06724724
OS 32.66134438 -39.06169988
OS 32.66226894 -39.06077532
OS 32.6631935 -39.05800164
OS 32.66504262 -39.05337884
OS 32.6678163 -39.04598236
OS 32.66966542 -39.0358122
OS 32.67058998 -39.02841572
OS 32.67151454 -39.0219438
OS 32.6724391 -39.01362276
OS 32.6724391 -39.0034526
OS 32.67336366 -38.99328244
OS 32.67336366 -38.98218772
OS 32.67336366 -38.49586916
OS 32.75195126 -38.49586916
OS 32.75195126 -38.98403684
OE
OB 33.77174094 -38.3100326 I
OS 33.78006198 -38.31095716
OS 33.79023214 -38.31188172
OS 33.8004023 -38.31280628
OS 33.81242158 -38.31557996
OS 33.8373847 -38.32112732
OS 33.8651215 -38.32944836
OS 33.8789899 -38.33499572
OS 33.89193374 -38.34146764
OS 33.90487758 -38.34978868
OS 33.91782142 -38.35810972
OS 33.91874598 -38.35903428
OS 33.9205951 -38.35995884
OS 33.92429334 -38.36273252
OS 33.92891614 -38.36735532
OS 33.93353894 -38.37197812
OS 33.94001086 -38.37845004
OS 33.94648278 -38.38584652
OS 33.95387926 -38.393243
OS 33.96127574 -38.4024886
OS 33.96867222 -38.41358332
OS 33.97699326 -38.42467804
OS 33.98438974 -38.43669732
OS 33.99086166 -38.45056572
OS 33.99825814 -38.46443412
OS 34.0038055 -38.47922708
OS 34.00935286 -38.49586916
OS 33.92614246 -38.51528492
OS 33.92614246 -38.51436036
OS 33.9252179 -38.51251124
OS 33.92336878 -38.508813
OS 33.92151966 -38.5041902
OS 33.91967054 -38.49864284
OS 33.91689686 -38.49124636
OS 33.90950038 -38.4764534
OS 33.90025478 -38.45981132
OS 33.88916006 -38.44316924
OS 33.87529166 -38.42745172
OS 33.8604987 -38.41358332
OS 33.85864958 -38.4117342
OS 33.85310222 -38.40803596
OS 33.84385662 -38.40341316
OS 33.83183734 -38.39694124
OS 33.81611982 -38.39139388
OS 33.79855318 -38.38584652
OS 33.7772883 -38.38214828
OS 33.7541743 -38.38122372
OS 33.74677782 -38.38122372
OS 33.74215502 -38.38214828
OS 33.7356831 -38.38214828
OS 33.72828662 -38.38307284
OS 33.71071998 -38.38584652
OS 33.69130422 -38.38954476
OS 33.6709639 -38.39601668
OS 33.64969902 -38.40526228
OS 33.63028326 -38.41728156
OS 33.6293587 -38.41728156
OS 33.62843414 -38.41913068
OS 33.62196222 -38.42375348
OS 33.61364118 -38.43114996
OS 33.60347102 -38.44224468
OS 33.59145174 -38.45611308
OS 33.58035702 -38.4718306
OS 33.57018686 -38.49124636
OS 33.56094126 -38.51251124
OS 33.56094126 -38.5134358
OS 33.5600167 -38.51528492
OS 33.55909214 -38.5180586
OS 33.55816758 -38.5226814
OS 33.55631846 -38.52822876
OS 33.55446934 -38.53470068
OS 33.55169566 -38.5504182
OS 33.54799742 -38.5689094
OS 33.54429918 -38.58924972
OS 33.54245006 -38.61143916
OS 33.5415255 -38.63547772
OS 33.5415255 -38.63640228
OS 33.5415255 -38.63917596
OS 33.5415255 -38.64379876
OS 33.5415255 -38.64934612
OS 33.54245006 -38.65581804
OS 33.54245006 -38.66413908
OS 33.54337462 -38.67338468
OS 33.54429918 -38.68355484
OS 33.54707286 -38.70574428
OS 33.55169566 -38.72978284
OS 33.55724302 -38.7538214
OS 33.5646395 -38.77785996
OS 33.5646395 -38.77878452
OS 33.56556406 -38.78063364
OS 33.56741318 -38.78340732
OS 33.5692623 -38.78803012
OS 33.57480966 -38.79912484
OS 33.5831307 -38.81206868
OS 33.59330086 -38.82686164
OS 33.6062447 -38.84257916
OS 33.62103766 -38.85644756
OS 33.6386043 -38.8693914
OS 33.63952886 -38.8693914
OS 33.64137798 -38.87031596
OS 33.64415166 -38.87216508
OS 33.6478499 -38.8740142
OS 33.6524727 -38.87586332
OS 33.65802006 -38.878637
OS 33.6709639 -38.88418436
OS 33.68760598 -38.88973172
OS 33.70609718 -38.89435452
OS 33.7264375 -38.89805276
OS 33.74770238 -38.89897732
OS 33.7541743 -38.89897732
OS 33.75972166 -38.89805276
OS 33.76619358 -38.89805276
OS 33.7726655 -38.8971282
OS 33.78930758 -38.89342996
OS 33.80872334 -38.88880716
OS 33.8281391 -38.88141068
OS 33.84847942 -38.87124052
OS 33.85864958 -38.86569316
OS 33.86789518 -38.85829668
OS 33.86881974 -38.85737212
OS 33.8697443 -38.85644756
OS 33.87251798 -38.85367388
OS 33.87621622 -38.8509002
OS 33.87991446 -38.8462774
OS 33.88453726 -38.84073004
OS 33.89008462 -38.83518268
OS 33.89470742 -38.8277862
OS 33.90025478 -38.81946516
OS 33.9067267 -38.81021956
OS 33.91227406 -38.80097396
OS 33.91782142 -38.78987924
OS 33.92244422 -38.77785996
OS 33.92706702 -38.76491612
OS 33.93168982 -38.75104772
OS 33.93538806 -38.73625476
OS 34.02044758 -38.75751964
OS 34.02044758 -38.7584442
OS 34.01952302 -38.76214244
OS 34.0176739 -38.7676898
OS 34.01490022 -38.77508628
OS 34.01212654 -38.78340732
OS 34.0084283 -38.79357748
OS 34.0038055 -38.8046722
OS 33.99825814 -38.81669148
OS 33.9853143 -38.84257916
OS 33.96867222 -38.86846684
OS 33.95850206 -38.88141068
OS 33.9483319 -38.89435452
OS 33.93723718 -38.90544924
OS 33.92429334 -38.91654396
OS 33.92336878 -38.91746852
OS 33.92151966 -38.91931764
OS 33.91689686 -38.92116676
OS 33.91227406 -38.924865
OS 33.90487758 -38.9294878
OS 33.8974811 -38.9341106
OS 33.88731094 -38.9387334
OS 33.87714078 -38.9433562
OS 33.8651215 -38.94890356
OS 33.85217766 -38.95352636
OS 33.83830926 -38.95814916
OS 33.8235163 -38.96277196
OS 33.80779878 -38.9664702
OS 33.7911567 -38.96831932
OS 33.77359006 -38.97016844
OS 33.75509886 -38.971093
OS 33.7449287 -38.971093
OS 33.73753222 -38.97016844
OS 33.72921118 -38.97016844
OS 33.71904102 -38.96924388
OS 33.7079463 -38.96739476
OS 33.69500246 -38.96554564
OS 33.66819022 -38.96092284
OS 33.64045342 -38.95352636
OS 33.61271662 -38.9433562
OS 33.59977278 -38.93688428
OS 33.58682894 -38.9294878
OS 33.58590438 -38.92856324
OS 33.58405526 -38.92763868
OS 33.58035702 -38.924865
OS 33.57665878 -38.92116676
OS 33.57111142 -38.91746852
OS 33.5646395 -38.91192116
OS 33.55724302 -38.90544924
OS 33.54984654 -38.89805276
OS 33.54245006 -38.88973172
OS 33.53412902 -38.88141068
OS 33.51748694 -38.8601458
OS 33.50176942 -38.83518268
OS 33.48790102 -38.80744588
OS 33.48790102 -38.80652132
OS 33.4860519 -38.80374764
OS 33.48512734 -38.79912484
OS 33.48235366 -38.79357748
OS 33.48050454 -38.786181
OS 33.47773086 -38.7769354
OS 33.47403262 -38.76676524
OS 33.47125894 -38.75567052
OS 33.46848526 -38.74365124
OS 33.46478702 -38.72978284
OS 33.46016422 -38.70112148
OS 33.45646598 -38.66876188
OS 33.45461686 -38.63547772
OS 33.45461686 -38.63455316
OS 33.45461686 -38.63085492
OS 33.45461686 -38.62530756
OS 33.45554142 -38.61883564
OS 33.45554142 -38.60959004
OS 33.45646598 -38.60034444
OS 33.45739054 -38.58832516
OS 33.45923966 -38.57630588
OS 33.46386246 -38.54949364
OS 33.47033438 -38.51990772
OS 33.47957998 -38.4903218
OS 33.49252382 -38.46166044
OS 33.49344838 -38.46073588
OS 33.49437294 -38.4579622
OS 33.49622206 -38.45426396
OS 33.4999203 -38.44964116
OS 33.50361854 -38.44316924
OS 33.50824134 -38.43577276
OS 33.52026062 -38.41913068
OS 33.53597814 -38.40063948
OS 33.55446934 -38.38214828
OS 33.57573422 -38.36365708
OS 33.60069734 -38.34793956
OS 33.6016219 -38.347015
OS 33.60439558 -38.34609044
OS 33.60809382 -38.34424132
OS 33.61271662 -38.34146764
OS 33.6201131 -38.33869396
OS 33.62750958 -38.33592028
OS 33.63675518 -38.33222204
OS 33.64692534 -38.3285238
OS 33.65802006 -38.32482556
OS 33.67003934 -38.32112732
OS 33.69592702 -38.31557996
OS 33.72551294 -38.31095716
OS 33.75602342 -38.30910804
OS 33.76526902 -38.30910804
OS 33.77174094 -38.3100326
OE
OB 35.15858094 -39.1375138 I
OS 34.63805366 -39.1375138
OS 34.63805366 -39.08111564
OS 35.15858094 -39.08111564
OS 35.15858094 -39.1375138
OE
OB 34.37917686 -38.32112732 I
OS 34.38657334 -38.32112732
OS 34.40321542 -38.32297644
OS 34.42170662 -38.32482556
OS 34.44112238 -38.3285238
OS 34.46053814 -38.3331466
OS 34.47810478 -38.33961852
OS 34.47902934 -38.33961852
OS 34.4799539 -38.34054308
OS 34.48550126 -38.34331676
OS 34.4938223 -38.34793956
OS 34.5030679 -38.35441148
OS 34.51416262 -38.36273252
OS 34.5261819 -38.37290268
OS 34.53727662 -38.38584652
OS 34.54744678 -38.39971492
OS 34.54837134 -38.40156404
OS 34.55114502 -38.4071114
OS 34.55576782 -38.41450788
OS 34.56039062 -38.4256026
OS 34.56501342 -38.43854644
OS 34.56963622 -38.45241484
OS 34.5724099 -38.46813236
OS 34.57333446 -38.48384988
OS 34.57333446 -38.485699
OS 34.57333446 -38.4903218
OS 34.5724099 -38.49864284
OS 34.57056078 -38.508813
OS 34.5677871 -38.52083228
OS 34.5631643 -38.53377612
OS 34.55761694 -38.54671996
OS 34.55022046 -38.56058836
OS 34.5492959 -38.56243748
OS 34.54652222 -38.56613572
OS 34.54097486 -38.5735322
OS 34.53357838 -38.58092868
OS 34.52433278 -38.59017428
OS 34.51323806 -38.60034444
OS 34.49936966 -38.60959004
OS 34.48365214 -38.61883564
OS 34.4845767 -38.61883564
OS 34.48642582 -38.6197602
OS 34.4891995 -38.62068476
OS 34.49289774 -38.62253388
OS 34.50399246 -38.62623212
OS 34.5169363 -38.63270404
OS 34.5308047 -38.64102508
OS 34.54652222 -38.65119524
OS 34.56039062 -38.66321452
OS 34.57333446 -38.67800748
OS 34.57425902 -38.6798566
OS 34.57795726 -38.68540396
OS 34.58350462 -38.693725
OS 34.58905198 -38.70481972
OS 34.59459934 -38.71961268
OS 34.6001467 -38.7353302
OS 34.60384494 -38.7538214
OS 34.6047695 -38.77416172
OS 34.6047695 -38.77508628
OS 34.6047695 -38.77601084
OS 34.6047695 -38.7815582
OS 34.60384494 -38.7908038
OS 34.60199582 -38.80189852
OS 34.6001467 -38.81484236
OS 34.59644846 -38.82871076
OS 34.59182566 -38.84350372
OS 34.58535374 -38.85829668
OS 34.58442918 -38.8601458
OS 34.5816555 -38.8647686
OS 34.57795726 -38.87124052
OS 34.5724099 -38.88048612
OS 34.56501342 -38.88973172
OS 34.55761694 -38.89990188
OS 34.54837134 -38.91007204
OS 34.53820118 -38.91839308
OS 34.53727662 -38.91931764
OS 34.53357838 -38.92209132
OS 34.52710646 -38.92578956
OS 34.51878542 -38.9294878
OS 34.50861526 -38.93503516
OS 34.49659598 -38.94058252
OS 34.48365214 -38.94520532
OS 34.46793462 -38.94982812
OS 34.4660855 -38.94982812
OS 34.46053814 -38.95167724
OS 34.45129254 -38.9526018
OS 34.43927326 -38.95445092
OS 34.4244803 -38.95630004
OS 34.40691366 -38.95814916
OS 34.3874979 -38.95907372
OS 34.36530846 -38.95999828
OS 34.12122462 -38.95999828
OS 34.12122462 -38.32020276
OS 34.37270494 -38.32020276
OS 34.37917686 -38.32112732
OE
OB 31.74233174 -38.95999828 I
OS 31.65264942 -38.95999828
OS 31.65264942 -38.87031596
OS 31.74233174 -38.87031596
OS 31.74233174 -38.95999828
OE
OB 31.52968294 -38.42745172 I
OS 31.50841806 -38.54671996
OS 31.45941638 -38.54671996
OS 31.44000062 -38.42745172
OS 31.44000062 -38.32020276
OS 31.52968294 -38.32020276
OS 31.52968294 -38.42745172
OE
OB 32.0992119 -38.48662356 I
OS 32.10568382 -38.48754812
OS 32.11955222 -38.48939724
OS 32.1361943 -38.49309548
OS 32.15376094 -38.49864284
OS 32.17132758 -38.50696388
OS 32.18889422 -38.51713404
OS 32.18981878 -38.51713404
OS 32.19074334 -38.51898316
OS 32.1962907 -38.5226814
OS 32.20461174 -38.53007788
OS 32.2147819 -38.53932348
OS 32.22587662 -38.55134276
OS 32.23697134 -38.56613572
OS 32.24806606 -38.58370236
OS 32.25731166 -38.60311812
OS 32.25731166 -38.60404268
OS 32.25823622 -38.6058918
OS 32.25916078 -38.60866548
OS 32.2610099 -38.61236372
OS 32.26285902 -38.61791108
OS 32.26470814 -38.624383
OS 32.26933094 -38.63917596
OS 32.27395374 -38.65766716
OS 32.27765198 -38.67800748
OS 32.28042566 -38.70112148
OS 32.28135022 -38.72516004
OS 32.28135022 -38.7260846
OS 32.28135022 -38.72793372
OS 32.28135022 -38.73163196
OS 32.28135022 -38.73717932
OS 32.28042566 -38.74365124
OS 32.28042566 -38.75104772
OS 32.27857654 -38.7676898
OS 32.2748783 -38.78803012
OS 32.2702555 -38.809295
OS 32.26378358 -38.83148444
OS 32.25546254 -38.85367388
OS 32.25546254 -38.85459844
OS 32.25453798 -38.85644756
OS 32.25268886 -38.85922124
OS 32.25083974 -38.86291948
OS 32.24436782 -38.87308964
OS 32.23604678 -38.88603348
OS 32.22587662 -38.89990188
OS 32.21293278 -38.91377028
OS 32.19813982 -38.92763868
OS 32.18057318 -38.94058252
OS 32.17964862 -38.94058252
OS 32.17872406 -38.94150708
OS 32.17595038 -38.9433562
OS 32.17225214 -38.94520532
OS 32.16300654 -38.94982812
OS 32.1500627 -38.95537548
OS 32.13434518 -38.96092284
OS 32.1177031 -38.96554564
OS 32.09828734 -38.96924388
OS 32.07887158 -38.97016844
OS 32.07239966 -38.97016844
OS 32.06500318 -38.96924388
OS 32.05575758 -38.96831932
OS 32.04466286 -38.9664702
OS 32.03264358 -38.96369652
OS 32.0206243 -38.95999828
OS 32.00860502 -38.95445092
OS 32.00768046 -38.95352636
OS 32.00305766 -38.95167724
OS 31.9975103 -38.947979
OS 31.99011382 -38.94243164
OS 31.98271734 -38.93688428
OS 31.97347174 -38.9294878
OS 31.9651507 -38.92116676
OS 31.95775422 -38.91192116
OS 31.95775422 -39.1375138
OS 31.87916662 -39.1375138
OS 31.87916662 -38.49586916
OS 31.95035774 -38.49586916
OS 31.95035774 -38.55689012
OS 31.9512823 -38.555041
OS 31.95498054 -38.55134276
OS 31.95960334 -38.54487084
OS 31.96699982 -38.53747436
OS 31.97532086 -38.52822876
OS 31.98456646 -38.51990772
OS 31.99566118 -38.51158668
OS 32.0067559 -38.5041902
OS 32.00860502 -38.50326564
OS 32.01230326 -38.50141652
OS 32.01969974 -38.49864284
OS 32.02894534 -38.4949446
OS 32.04004006 -38.49124636
OS 32.0529839 -38.48847268
OS 32.06777686 -38.48662356
OS 32.08441894 -38.485699
OS 32.0945891 -38.485699
OS 32.0992119 -38.48662356
OE
OB 32.5614919 -38.48662356 I
OS 32.57166206 -38.48847268
OS 32.58368134 -38.49217092
OS 32.59662518 -38.49679372
OS 32.61141814 -38.50326564
OS 32.62713566 -38.51158668
OS 32.5984743 -38.58370236
OS 32.59754974 -38.5827778
OS 32.5938515 -38.58092868
OS 32.58830414 -38.578155
OS 32.58090766 -38.57538132
OS 32.57258662 -38.57260764
OS 32.56241646 -38.56983396
OS 32.5522463 -38.56798484
OS 32.54207614 -38.56706028
OS 32.53745334 -38.56706028
OS 32.53283054 -38.56798484
OS 32.52635862 -38.5689094
OS 32.5198867 -38.57075852
OS 32.51156566 -38.5735322
OS 32.50324462 -38.57723044
OS 32.49584814 -38.5827778
OS 32.49492358 -38.58370236
OS 32.4921499 -38.58555148
OS 32.48937622 -38.58924972
OS 32.48475342 -38.59387252
OS 32.48013062 -38.60034444
OS 32.47550782 -38.60774092
OS 32.47088502 -38.61606196
OS 32.46718678 -38.62623212
OS 32.46626222 -38.62808124
OS 32.46533766 -38.6336286
OS 32.46348854 -38.64194964
OS 32.46071486 -38.65304436
OS 32.45794118 -38.66691276
OS 32.45609206 -38.68263028
OS 32.4551675 -38.69927236
OS 32.45424294 -38.71776356
OS 32.45424294 -38.95999828
OS 32.37565534 -38.95999828
OS 32.37565534 -38.49586916
OS 32.44684646 -38.49586916
OS 32.44684646 -38.56613572
OS 32.44777102 -38.56521116
OS 32.45146926 -38.55873924
OS 32.45609206 -38.5504182
OS 32.46348854 -38.54024804
OS 32.47088502 -38.53007788
OS 32.47920606 -38.51898316
OS 32.4875271 -38.50973756
OS 32.49584814 -38.50234108
OS 32.4967727 -38.50141652
OS 32.49954638 -38.4995674
OS 32.50509374 -38.49679372
OS 32.5106411 -38.49402004
OS 32.51803758 -38.49124636
OS 32.52728318 -38.48847268
OS 32.53652878 -38.48662356
OS 32.54669894 -38.485699
OS 32.55317086 -38.485699
OS 32.5614919 -38.48662356
OE
OB 32.75195126 -38.4117342 I
OS 32.67336366 -38.4117342
OS 32.67336366 -38.32020276
OS 32.75195126 -38.32020276
OS 32.75195126 -38.4117342
OE
OB 36.56668582 -38.95999828 I
OS 36.47885262 -38.95999828
OS 36.1441619 -38.4579622
OS 36.1441619 -38.95999828
OS 36.06280062 -38.95999828
OS 36.06280062 -38.32020276
OS 36.14970926 -38.32020276
OS 36.48532454 -38.8231634
OS 36.48532454 -38.32020276
OS 36.56668582 -38.32020276
OS 36.56668582 -38.95999828
OE
OB 35.74382742 -38.32112732 I
OS 35.75954494 -38.32205188
OS 35.77618702 -38.32297644
OS 35.79190454 -38.32482556
OS 35.80577294 -38.32667468
OS 35.80762206 -38.32667468
OS 35.81409398 -38.3285238
OS 35.82241502 -38.33037292
OS 35.83350974 -38.3331466
OS 35.84552902 -38.3377694
OS 35.85847286 -38.34331676
OS 35.87234126 -38.34978868
OS 35.88436054 -38.35718516
OS 35.88620966 -38.35810972
OS 35.8899079 -38.3608834
OS 35.89545526 -38.36643076
OS 35.90285174 -38.37290268
OS 35.91117278 -38.38122372
OS 35.91949382 -38.39231844
OS 35.92873942 -38.40433772
OS 35.9361359 -38.41820612
OS 35.93706046 -38.42005524
OS 35.93890958 -38.42467804
OS 35.94260782 -38.43299908
OS 35.94630606 -38.4440938
OS 35.94907974 -38.45703764
OS 35.95277798 -38.4718306
OS 35.9546271 -38.48847268
OS 35.95555166 -38.50603932
OS 35.95555166 -38.50696388
OS 35.95555166 -38.50973756
OS 35.95555166 -38.5134358
OS 35.9546271 -38.51990772
OS 35.95370254 -38.52637964
OS 35.95277798 -38.53470068
OS 35.95092886 -38.54394628
OS 35.94907974 -38.55411644
OS 35.94260782 -38.57538132
OS 35.93890958 -38.58647604
OS 35.93336222 -38.59849532
OS 35.9268903 -38.6105146
OS 35.92041838 -38.62160932
OS 35.91209734 -38.63270404
OS 35.90285174 -38.64379876
OS 35.90192718 -38.64472332
OS 35.90007806 -38.64657244
OS 35.89730438 -38.64934612
OS 35.89268158 -38.6521198
OS 35.88713422 -38.6567426
OS 35.87973774 -38.6613654
OS 35.87049214 -38.66691276
OS 35.86032198 -38.67153556
OS 35.8483027 -38.67708292
OS 35.8344343 -38.68263028
OS 35.81964134 -38.68725308
OS 35.8020747 -38.69095132
OS 35.7835835 -38.69464956
OS 35.76324318 -38.69742324
OS 35.74012918 -38.69927236
OS 35.71609062 -38.70019692
OS 35.5524435 -38.70019692
OS 35.5524435 -38.95999828
OS 35.46738398 -38.95999828
OS 35.46738398 -38.32020276
OS 35.72995902 -38.32020276
OS 35.74382742 -38.32112732
OE
OB 36.76916446 -38.42745172 I
OS 36.74789958 -38.54671996
OS 36.6988979 -38.54671996
OS 36.67948214 -38.42745172
OS 36.67948214 -38.32020276
OS 36.76916446 -38.32020276
OS 36.76916446 -38.42745172
OE
OB 38.2382903 -38.39601668 I
OS 37.86014526 -38.39601668
OS 37.86014526 -38.59109884
OS 38.21425174 -38.59109884
OS 38.21425174 -38.66691276
OS 37.86014526 -38.66691276
OS 37.86014526 -38.88418436
OS 38.25308326 -38.88418436
OS 38.25308326 -38.95999828
OS 37.77508574 -38.95999828
OS 37.77508574 -38.32020276
OS 38.2382903 -38.32020276
OS 38.2382903 -38.39601668
OE
OB 37.4339231 -38.32112732 I
OS 37.44224414 -38.32112732
OS 37.4616599 -38.32205188
OS 37.48200022 -38.32482556
OS 37.50418966 -38.32759924
OS 37.52452998 -38.33222204
OS 37.53470014 -38.33499572
OS 37.54302118 -38.3377694
OS 37.54394574 -38.3377694
OS 37.5448703 -38.33869396
OS 37.55041766 -38.34146764
OS 37.5587387 -38.34516588
OS 37.56890886 -38.3516378
OS 37.58000358 -38.35995884
OS 37.59202286 -38.37105356
OS 37.60311758 -38.3839974
OS 37.6142123 -38.39879036
OS 37.6142123 -38.39971492
OS 37.61513686 -38.40063948
OS 37.6188351 -38.40618684
OS 37.62253334 -38.41543244
OS 37.6280807 -38.42745172
OS 37.6327035 -38.44132012
OS 37.6373263 -38.4579622
OS 37.64009998 -38.47552884
OS 37.64102454 -38.4949446
OS 37.64102454 -38.49586916
OS 37.64102454 -38.49771828
OS 37.64102454 -38.50141652
OS 37.64009998 -38.50603932
OS 37.64009998 -38.51251124
OS 37.63917542 -38.51898316
OS 37.63547718 -38.53470068
OS 37.62992982 -38.55319188
OS 37.62253334 -38.57260764
OS 37.61143862 -38.5920234
OS 37.60404214 -38.601269
OS 37.59664566 -38.6105146
OS 37.5957211 -38.61143916
OS 37.59479654 -38.61236372
OS 37.59202286 -38.6151374
OS 37.58832462 -38.61791108
OS 37.58370182 -38.62160932
OS 37.57815446 -38.62530756
OS 37.57075798 -38.62993036
OS 37.5633615 -38.63547772
OS 37.5541159 -38.64010052
OS 37.54394574 -38.64472332
OS 37.53285102 -38.65027068
OS 37.52083174 -38.65489348
OS 37.50696334 -38.65859172
OS 37.49309494 -38.66321452
OS 37.47737742 -38.6659882
OS 37.46073534 -38.66876188
OS 37.46258446 -38.66968644
OS 37.4662827 -38.67153556
OS 37.47183006 -38.6752338
OS 37.47922654 -38.67893204
OS 37.49586862 -38.6891022
OS 37.50418966 -38.69557412
OS 37.51158614 -38.70112148
OS 37.51343526 -38.7029706
OS 37.51805806 -38.7075934
OS 37.52545454 -38.71498988
OS 37.53470014 -38.72423548
OS 37.5448703 -38.73717932
OS 37.55688958 -38.75104772
OS 37.56890886 -38.7676898
OS 37.5818527 -38.786181
OS 37.69187534 -38.95999828
OS 37.5864755 -38.95999828
OS 37.50234054 -38.82686164
OS 37.50234054 -38.82593708
OS 37.50049142 -38.82408796
OS 37.4986423 -38.82131428
OS 37.49586862 -38.81761604
OS 37.4893967 -38.80744588
OS 37.48107566 -38.79450204
OS 37.4709055 -38.78063364
OS 37.46073534 -38.76584068
OS 37.45056518 -38.75197228
OS 37.44131958 -38.73902844
OS 37.44039502 -38.73810388
OS 37.43762134 -38.73440564
OS 37.43299854 -38.72885828
OS 37.42652662 -38.72238636
OS 37.41265822 -38.70851796
OS 37.40526174 -38.70204604
OS 37.39786526 -38.69649868
OS 37.3969407 -38.69557412
OS 37.39509158 -38.69464956
OS 37.39139334 -38.69280044
OS 37.38584598 -38.69002676
OS 37.38029862 -38.68725308
OS 37.3738267 -38.6844794
OS 37.35903374 -38.6798566
OS 37.35810918 -38.6798566
OS 37.35626006 -38.67893204
OS 37.35256182 -38.67893204
OS 37.34793902 -38.67800748
OS 37.3414671 -38.67708292
OS 37.33407062 -38.67708292
OS 37.32390046 -38.67615836
OS 37.21480238 -38.67615836
OS 37.21480238 -38.95999828
OS 37.12974286 -38.95999828
OS 37.12974286 -38.32020276
OS 37.42652662 -38.32020276
OS 37.4339231 -38.32112732
OE
OB 35.31760526 -38.95999828 I
OS 35.23254574 -38.95999828
OS 35.23254574 -38.32020276
OS 35.31760526 -38.32020276
OS 35.31760526 -38.95999828
OE
OB 42.12051774 -38.66413908 H
OS 41.95224782 -38.66413908
OS 41.95224782 -38.88418436
OS 42.13438614 -38.88418436
OS 42.1538019 -38.8832598
OS 42.16212294 -38.88233524
OS 42.16951942 -38.88141068
OS 42.17044398 -38.88141068
OS 42.17414222 -38.88048612
OS 42.17968958 -38.87956156
OS 42.1861615 -38.87771244
OS 42.20187902 -38.87216508
OS 42.21759654 -38.8647686
OS 42.2185211 -38.86384404
OS 42.22129478 -38.86199492
OS 42.22499302 -38.85922124
OS 42.22961582 -38.855523
OS 42.23423862 -38.84997564
OS 42.24071054 -38.84442828
OS 42.24533334 -38.8370318
OS 42.2508807 -38.82871076
OS 42.25180526 -38.8277862
OS 42.25272982 -38.82501252
OS 42.25457894 -38.81946516
OS 42.25735262 -38.81299324
OS 42.2601263 -38.80559676
OS 42.26197542 -38.79635116
OS 42.26289998 -38.78525644
OS 42.26382454 -38.77416172
OS 42.26382454 -38.7723126
OS 42.26382454 -38.76861436
OS 42.26289998 -38.76121788
OS 42.26105086 -38.75289684
OS 42.25920174 -38.74365124
OS 42.2555035 -38.73348108
OS 42.2508807 -38.72331092
OS 42.24440878 -38.71314076
OS 42.24348422 -38.7122162
OS 42.24071054 -38.70851796
OS 42.2370123 -38.70389516
OS 42.23146494 -38.6983478
OS 42.22406846 -38.69187588
OS 42.21482286 -38.68540396
OS 42.2046527 -38.6798566
OS 42.19263342 -38.6752338
OS 42.1907843 -38.67430924
OS 42.18708606 -38.67338468
OS 42.17876502 -38.67153556
OS 42.16859486 -38.66968644
OS 42.15565102 -38.66783732
OS 42.1399335 -38.6659882
OS 42.12051774 -38.66413908
OE
OB 45.22981302 -38.5504182 H
OS 45.22426566 -38.5504182
OS 45.21964286 -38.55134276
OS 45.2094727 -38.55226732
OS 45.1956043 -38.55596556
OS 45.17988678 -38.56151292
OS 45.1632447 -38.5689094
OS 45.14752718 -38.58000412
OS 45.13920614 -38.5874006
OS 45.13180966 -38.59479708
OS 45.13180966 -38.59572164
OS 45.12996054 -38.5966462
OS 45.12811142 -38.59941988
OS 45.12533774 -38.60311812
OS 45.12256406 -38.60774092
OS 45.11979038 -38.61328828
OS 45.11609214 -38.62068476
OS 45.1123939 -38.62808124
OS 45.10869566 -38.63732684
OS 45.10499742 -38.64657244
OS 45.10222374 -38.65766716
OS 45.09945006 -38.66968644
OS 45.09667638 -38.68263028
OS 45.09482726 -38.69649868
OS 45.0939027 -38.7122162
OS 45.09297814 -38.72793372
OS 45.09297814 -38.72885828
OS 45.09297814 -38.73163196
OS 45.09297814 -38.73625476
OS 45.0939027 -38.74272668
OS 45.0939027 -38.75012316
OS 45.09482726 -38.7584442
OS 45.09760094 -38.77785996
OS 45.10222374 -38.8000494
OS 45.10962022 -38.82223884
OS 45.11886582 -38.84350372
OS 45.12533774 -38.85274932
OS 45.13180966 -38.86199492
OS 45.13273422 -38.86199492
OS 45.13365878 -38.86384404
OS 45.13920614 -38.86846684
OS 45.14752718 -38.87586332
OS 45.1586219 -38.8832598
OS 45.1724903 -38.89158084
OS 45.18913238 -38.89897732
OS 45.20854814 -38.90360012
OS 45.2187183 -38.90452468
OS 45.22981302 -38.90544924
OS 45.23536038 -38.90544924
OS 45.23998318 -38.90452468
OS 45.25015334 -38.90267556
OS 45.26402174 -38.89990188
OS 45.2788147 -38.89435452
OS 45.29545678 -38.88695804
OS 45.3111743 -38.87586332
OS 45.31949534 -38.86846684
OS 45.32689182 -38.86107036
OS 45.32781638 -38.8601458
OS 45.32874094 -38.85922124
OS 45.33059006 -38.85644756
OS 45.33336374 -38.85274932
OS 45.33613742 -38.84812652
OS 45.33983566 -38.84257916
OS 45.3435339 -38.83518268
OS 45.34723214 -38.8277862
OS 45.35093038 -38.8185406
OS 45.35370406 -38.80837044
OS 45.3574023 -38.79727572
OS 45.36017598 -38.78525644
OS 45.36294966 -38.77138804
OS 45.36479878 -38.75751964
OS 45.3666479 -38.74180212
OS 45.3666479 -38.72516004
OS 45.3666479 -38.72423548
OS 45.3666479 -38.7214618
OS 45.3666479 -38.716839
OS 45.36572334 -38.71129164
OS 45.36572334 -38.70389516
OS 45.36479878 -38.69557412
OS 45.3620251 -38.67615836
OS 45.3574023 -38.65581804
OS 45.35000582 -38.6336286
OS 45.33983566 -38.61328828
OS 45.3342883 -38.60311812
OS 45.32689182 -38.59479708
OS 45.32689182 -38.59387252
OS 45.3250427 -38.59294796
OS 45.31949534 -38.5874006
OS 45.3111743 -38.58092868
OS 45.30007958 -38.57260764
OS 45.28621118 -38.5642866
OS 45.2695691 -38.55689012
OS 45.2510779 -38.55226732
OS 45.24090774 -38.55134276
OS 45.22981302 -38.5504182
OE
OB 32.07702246 -38.54764452 H
OS 32.07239966 -38.54764452
OS 32.06870142 -38.54856908
OS 32.05945582 -38.5504182
OS 32.04743654 -38.55319188
OS 32.03356814 -38.55873924
OS 32.01877518 -38.56706028
OS 32.01045414 -38.57260764
OS 32.00305766 -38.57907956
OS 31.99566118 -38.58647604
OS 31.9882647 -38.59479708
OS 31.9882647 -38.59572164
OS 31.98641558 -38.5966462
OS 31.98456646 -38.59941988
OS 31.98271734 -38.60311812
OS 31.97994366 -38.60866548
OS 31.97624542 -38.61421284
OS 31.97254718 -38.62160932
OS 31.9697735 -38.6290058
OS 31.96607526 -38.6382514
OS 31.96237702 -38.64842156
OS 31.95960334 -38.65951628
OS 31.9559051 -38.67153556
OS 31.95405598 -38.68540396
OS 31.95220686 -38.69927236
OS 31.95035774 -38.71406532
OS 31.95035774 -38.7307074
OS 31.95035774 -38.73163196
OS 31.95035774 -38.73440564
OS 31.95035774 -38.73902844
OS 31.9512823 -38.74550036
OS 31.9512823 -38.75289684
OS 31.95220686 -38.76121788
OS 31.95498054 -38.78063364
OS 31.95960334 -38.80282308
OS 31.9651507 -38.82408796
OS 31.9743963 -38.84535284
OS 31.97994366 -38.85459844
OS 31.98641558 -38.86291948
OS 31.9882647 -38.8647686
OS 31.9928875 -38.8693914
OS 32.00028398 -38.87678788
OS 32.01045414 -38.88418436
OS 32.02339798 -38.89158084
OS 32.03819094 -38.89897732
OS 32.05483302 -38.90360012
OS 32.06407862 -38.90452468
OS 32.07332422 -38.90544924
OS 32.07887158 -38.90544924
OS 32.08256982 -38.90452468
OS 32.09181542 -38.90267556
OS 32.10475926 -38.89990188
OS 32.11862766 -38.89435452
OS 32.13342062 -38.88695804
OS 32.14821358 -38.87586332
OS 32.15561006 -38.8693914
OS 32.16300654 -38.86199492
OS 32.16300654 -38.86107036
OS 32.16485566 -38.8601458
OS 32.16670478 -38.85737212
OS 32.1685539 -38.85367388
OS 32.17225214 -38.84905108
OS 32.17502582 -38.84257916
OS 32.17872406 -38.83610724
OS 32.1824223 -38.8277862
OS 32.18519598 -38.81946516
OS 32.18889422 -38.80837044
OS 32.19259246 -38.79727572
OS 32.19536614 -38.78525644
OS 32.19721526 -38.77138804
OS 32.19906438 -38.75659508
OS 32.2009135 -38.74087756
OS 32.2009135 -38.72423548
OS 32.2009135 -38.72331092
OS 32.2009135 -38.72053724
OS 32.2009135 -38.71591444
OS 32.19998894 -38.70944252
OS 32.19998894 -38.70204604
OS 32.19906438 -38.693725
OS 32.1962907 -38.67430924
OS 32.1916679 -38.65304436
OS 32.18519598 -38.63177948
OS 32.17595038 -38.6105146
OS 32.17040302 -38.60034444
OS 32.1639311 -38.5920234
OS 32.1639311 -38.59109884
OS 32.16208198 -38.59017428
OS 32.15745918 -38.58462692
OS 32.1500627 -38.578155
OS 32.13989254 -38.56983396
OS 32.1269487 -38.56151292
OS 32.11215574 -38.55411644
OS 32.09551366 -38.54949364
OS 32.08626806 -38.54856908
OS 32.07702246 -38.54764452
OE
OB 42.10387566 -38.39601668 H
OS 41.95224782 -38.39601668
OS 41.95224782 -38.58832516
OS 42.10942302 -38.58832516
OS 42.1214423 -38.5874006
OS 42.13438614 -38.58647604
OS 42.14732998 -38.58555148
OS 42.16027382 -38.58370236
OS 42.17044398 -38.58185324
OS 42.1722931 -38.58092868
OS 42.17599134 -38.58000412
OS 42.1815387 -38.57723044
OS 42.18893518 -38.5735322
OS 42.19633166 -38.56983396
OS 42.2046527 -38.5642866
OS 42.21297374 -38.55689012
OS 42.21944566 -38.54949364
OS 42.22037022 -38.54856908
OS 42.22221934 -38.5457954
OS 42.22499302 -38.54024804
OS 42.2277667 -38.53377612
OS 42.23054038 -38.52637964
OS 42.23331406 -38.51713404
OS 42.23516318 -38.50603932
OS 42.23608774 -38.49402004
OS 42.23608774 -38.49217092
OS 42.23608774 -38.48847268
OS 42.23516318 -38.48292532
OS 42.23423862 -38.47552884
OS 42.2323895 -38.46628324
OS 42.22961582 -38.45703764
OS 42.22591758 -38.44779204
OS 42.22037022 -38.43854644
OS 42.21944566 -38.43762188
OS 42.21759654 -38.4348482
OS 42.2138983 -38.4302254
OS 42.2092755 -38.4256026
OS 42.20280358 -38.42005524
OS 42.1954071 -38.41450788
OS 42.1861615 -38.40896052
OS 42.17599134 -38.40526228
OS 42.17506678 -38.40526228
OS 42.17044398 -38.40341316
OS 42.16397206 -38.4024886
OS 42.1538019 -38.40063948
OS 42.1399335 -38.39879036
OS 42.12421598 -38.3978658
OS 42.10387566 -38.39601668
OE
OB 37.41635646 -38.39139388 H
OS 37.21480238 -38.39139388
OS 37.21480238 -38.60311812
OS 37.40526174 -38.60311812
OS 37.41635646 -38.60219356
OS 37.4293003 -38.601269
OS 37.44409326 -38.60034444
OS 37.45888622 -38.59849532
OS 37.47367918 -38.59572164
OS 37.48662302 -38.5920234
OS 37.48847214 -38.59109884
OS 37.49217038 -38.58924972
OS 37.49771774 -38.58647604
OS 37.50511422 -38.5827778
OS 37.51343526 -38.57723044
OS 37.5217563 -38.57075852
OS 37.53007734 -38.56243748
OS 37.53654926 -38.55319188
OS 37.53747382 -38.55226732
OS 37.53932294 -38.54856908
OS 37.54209662 -38.54302172
OS 37.54579486 -38.53562524
OS 37.54856854 -38.5273042
OS 37.55134222 -38.5180586
OS 37.55319134 -38.50696388
OS 37.5541159 -38.49586916
OS 37.5541159 -38.4949446
OS 37.5541159 -38.49402004
OS 37.55319134 -38.48847268
OS 37.55226678 -38.48015164
OS 37.55041766 -38.46905692
OS 37.54579486 -38.4579622
OS 37.5402475 -38.44501836
OS 37.53192646 -38.43299908
OS 37.52083174 -38.4209798
OS 37.51898262 -38.42005524
OS 37.51435982 -38.416357
OS 37.50696334 -38.4117342
OS 37.49494406 -38.40618684
OS 37.48107566 -38.40063948
OS 37.46258446 -38.39601668
OS 37.44131958 -38.39231844
OS 37.41635646 -38.39139388
OE
OB 39.82298614 -38.54764452 H
OS 39.81836334 -38.54764452
OS 39.8146651 -38.54856908
OS 39.8054195 -38.5504182
OS 39.79340022 -38.55319188
OS 39.77953182 -38.55873924
OS 39.76473886 -38.56706028
OS 39.75641782 -38.57260764
OS 39.74902134 -38.57907956
OS 39.74162486 -38.58647604
OS 39.73422838 -38.59479708
OS 39.73422838 -38.59572164
OS 39.73237926 -38.5966462
OS 39.73053014 -38.59941988
OS 39.72868102 -38.60311812
OS 39.72590734 -38.60866548
OS 39.7222091 -38.61421284
OS 39.71851086 -38.62160932
OS 39.71573718 -38.6290058
OS 39.71203894 -38.6382514
OS 39.7083407 -38.64842156
OS 39.70556702 -38.65951628
OS 39.70186878 -38.67153556
OS 39.70001966 -38.68540396
OS 39.69817054 -38.69927236
OS 39.69632142 -38.71406532
OS 39.69632142 -38.7307074
OS 39.69632142 -38.73163196
OS 39.69632142 -38.73440564
OS 39.69632142 -38.73902844
OS 39.69724598 -38.74550036
OS 39.69724598 -38.75289684
OS 39.69817054 -38.76121788
OS 39.70094422 -38.78063364
OS 39.70556702 -38.80282308
OS 39.71111438 -38.82408796
OS 39.72035998 -38.84535284
OS 39.72590734 -38.85459844
OS 39.73237926 -38.86291948
OS 39.73422838 -38.8647686
OS 39.73885118 -38.8693914
OS 39.74624766 -38.87678788
OS 39.75641782 -38.88418436
OS 39.76936166 -38.89158084
OS 39.78415462 -38.89897732
OS 39.8007967 -38.90360012
OS 39.8100423 -38.90452468
OS 39.8192879 -38.90544924
OS 39.82483526 -38.90544924
OS 39.8285335 -38.90452468
OS 39.8377791 -38.90267556
OS 39.85072294 -38.89990188
OS 39.86459134 -38.89435452
OS 39.8793843 -38.88695804
OS 39.89417726 -38.87586332
OS 39.90157374 -38.8693914
OS 39.90897022 -38.86199492
OS 39.90897022 -38.86107036
OS 39.91081934 -38.8601458
OS 39.91266846 -38.85737212
OS 39.91451758 -38.85367388
OS 39.91821582 -38.84905108
OS 39.9209895 -38.84257916
OS 39.92468774 -38.83610724
OS 39.92838598 -38.8277862
OS 39.93115966 -38.81946516
OS 39.9348579 -38.80837044
OS 39.93855614 -38.79727572
OS 39.94132982 -38.78525644
OS 39.94317894 -38.77138804
OS 39.94502806 -38.75659508
OS 39.94687718 -38.74087756
OS 39.94687718 -38.72423548
OS 39.94687718 -38.72331092
OS 39.94687718 -38.72053724
OS 39.94687718 -38.71591444
OS 39.94595262 -38.70944252
OS 39.94595262 -38.70204604
OS 39.94502806 -38.693725
OS 39.94225438 -38.67430924
OS 39.93763158 -38.65304436
OS 39.93115966 -38.63177948
OS 39.92191406 -38.6105146
OS 39.9163667 -38.60034444
OS 39.90989478 -38.5920234
OS 39.90989478 -38.59109884
OS 39.90804566 -38.59017428
OS 39.90342286 -38.58462692
OS 39.89602638 -38.578155
OS 39.88585622 -38.56983396
OS 39.87291238 -38.56151292
OS 39.85811942 -38.55411644
OS 39.84147734 -38.54949364
OS 39.83223174 -38.54856908
OS 39.82298614 -38.54764452
OE
OB 35.73550638 -38.39601668 H
OS 35.5524435 -38.39601668
OS 35.5524435 -38.624383
OS 35.72441166 -38.624383
OS 35.73088358 -38.62345844
OS 35.7373555 -38.62345844
OS 35.74475198 -38.62253388
OS 35.76231862 -38.62068476
OS 35.78173438 -38.61698652
OS 35.80115014 -38.61143916
OS 35.81871678 -38.60404268
OS 35.82703782 -38.59941988
OS 35.83350974 -38.59387252
OS 35.83535886 -38.5920234
OS 35.8390571 -38.58832516
OS 35.84460446 -38.58092868
OS 35.85107638 -38.57168308
OS 35.8575483 -38.5596638
OS 35.86309566 -38.54487084
OS 35.8667939 -38.52822876
OS 35.86864302 -38.508813
OS 35.86864302 -38.50788844
OS 35.86864302 -38.50696388
OS 35.86864302 -38.50234108
OS 35.86771846 -38.49402004
OS 35.86586934 -38.48477444
OS 35.86402022 -38.47460428
OS 35.86032198 -38.462585
OS 35.85477462 -38.45149028
OS 35.8483027 -38.44039556
OS 35.84737814 -38.439471
OS 35.84460446 -38.43577276
OS 35.83998166 -38.43114996
OS 35.8344343 -38.42467804
OS 35.82611326 -38.41820612
OS 35.81686766 -38.41265876
OS 35.8066975 -38.4071114
OS 35.79467822 -38.4024886
OS 35.79375366 -38.4024886
OS 35.79005542 -38.40156404
OS 35.78450806 -38.40063948
OS 35.77711158 -38.39879036
OS 35.76601686 -38.3978658
OS 35.75214846 -38.39694124
OS 35.73550638 -38.39601668
OE
OB 43.44263854 -38.5504182 H
OS 43.43709118 -38.5504182
OS 43.43339294 -38.55134276
OS 43.42322278 -38.55226732
OS 43.4112035 -38.555041
OS 43.39641054 -38.5596638
OS 43.38069302 -38.56613572
OS 43.36590006 -38.57538132
OS 43.3511071 -38.5874006
OS 43.34925798 -38.58924972
OS 43.34555974 -38.59387252
OS 43.33908782 -38.60219356
OS 43.3326159 -38.61328828
OS 43.32521942 -38.62623212
OS 43.3187475 -38.6428742
OS 43.31320014 -38.66228996
OS 43.31042646 -38.68355484
OS 43.57022782 -38.68355484
OS 43.57022782 -38.68263028
OS 43.57022782 -38.68078116
OS 43.56930326 -38.67800748
OS 43.56930326 -38.67430924
OS 43.56745414 -38.66321452
OS 43.56468046 -38.65119524
OS 43.56005766 -38.63640228
OS 43.55543486 -38.62253388
OS 43.54803838 -38.60866548
OS 43.53971734 -38.5966462
OS 43.53971734 -38.59572164
OS 43.53786822 -38.59479708
OS 43.53324542 -38.58924972
OS 43.52492438 -38.58185324
OS 43.51382966 -38.5735322
OS 43.49996126 -38.56521116
OS 43.48331918 -38.55781468
OS 43.46390342 -38.55226732
OS 43.45373326 -38.55134276
OS 43.44263854 -38.5504182
OE
OB 34.35791198 -38.39601668 H
OS 34.20628414 -38.39601668
OS 34.20628414 -38.58832516
OS 34.36345934 -38.58832516
OS 34.37547862 -38.5874006
OS 34.38842246 -38.58647604
OS 34.4013663 -38.58555148
OS 34.41431014 -38.58370236
OS 34.4244803 -38.58185324
OS 34.42632942 -38.58092868
OS 34.43002766 -38.58000412
OS 34.43557502 -38.57723044
OS 34.4429715 -38.5735322
OS 34.45036798 -38.56983396
OS 34.45868902 -38.5642866
OS 34.46701006 -38.55689012
OS 34.47348198 -38.54949364
OS 34.47440654 -38.54856908
OS 34.47625566 -38.5457954
OS 34.47902934 -38.54024804
OS 34.48180302 -38.53377612
OS 34.4845767 -38.52637964
OS 34.48735038 -38.51713404
OS 34.4891995 -38.50603932
OS 34.49012406 -38.49402004
OS 34.49012406 -38.49217092
OS 34.49012406 -38.48847268
OS 34.4891995 -38.48292532
OS 34.48827494 -38.47552884
OS 34.48642582 -38.46628324
OS 34.48365214 -38.45703764
OS 34.4799539 -38.44779204
OS 34.47440654 -38.43854644
OS 34.47348198 -38.43762188
OS 34.47163286 -38.4348482
OS 34.46793462 -38.4302254
OS 34.46331182 -38.4256026
OS 34.4568399 -38.42005524
OS 34.44944342 -38.41450788
OS 34.44019782 -38.40896052
OS 34.43002766 -38.40526228
OS 34.4291031 -38.40526228
OS 34.4244803 -38.40341316
OS 34.41800838 -38.4024886
OS 34.40783822 -38.40063948
OS 34.39396982 -38.39879036
OS 34.3782523 -38.3978658
OS 34.35791198 -38.39601668
OE
OB 40.89732486 -38.39601668 H
OS 40.71426198 -38.39601668
OS 40.71426198 -38.624383
OS 40.88623014 -38.624383
OS 40.89270206 -38.62345844
OS 40.89917398 -38.62345844
OS 40.90657046 -38.62253388
OS 40.9241371 -38.62068476
OS 40.94355286 -38.61698652
OS 40.96296862 -38.61143916
OS 40.98053526 -38.60404268
OS 40.9888563 -38.59941988
OS 40.99532822 -38.59387252
OS 40.99717734 -38.5920234
OS 41.00087558 -38.58832516
OS 41.00642294 -38.58092868
OS 41.01289486 -38.57168308
OS 41.01936678 -38.5596638
OS 41.02491414 -38.54487084
OS 41.02861238 -38.52822876
OS 41.0304615 -38.508813
OS 41.0304615 -38.50788844
OS 41.0304615 -38.50696388
OS 41.0304615 -38.50234108
OS 41.02953694 -38.49402004
OS 41.02768782 -38.48477444
OS 41.0258387 -38.47460428
OS 41.02214046 -38.462585
OS 41.0165931 -38.45149028
OS 41.01012118 -38.44039556
OS 41.00919662 -38.439471
OS 41.00642294 -38.43577276
OS 41.00180014 -38.43114996
OS 40.99625278 -38.42467804
OS 40.98793174 -38.41820612
OS 40.97868614 -38.41265876
OS 40.96851598 -38.4071114
OS 40.9564967 -38.4024886
OS 40.95557214 -38.4024886
OS 40.9518739 -38.40156404
OS 40.94632654 -38.40063948
OS 40.93893006 -38.39879036
OS 40.92783534 -38.3978658
OS 40.91396694 -38.39694124
OS 40.89732486 -38.39601668
OE
OB 33.15136118 -38.39601668 H
OS 32.9682983 -38.39601668
OS 32.9682983 -38.624383
OS 33.14026646 -38.624383
OS 33.14673838 -38.62345844
OS 33.1532103 -38.62345844
OS 33.16060678 -38.62253388
OS 33.17817342 -38.62068476
OS 33.19758918 -38.61698652
OS 33.21700494 -38.61143916
OS 33.23457158 -38.60404268
OS 33.24289262 -38.59941988
OS 33.24936454 -38.59387252
OS 33.25121366 -38.5920234
OS 33.2549119 -38.58832516
OS 33.26045926 -38.58092868
OS 33.26693118 -38.57168308
OS 33.2734031 -38.5596638
OS 33.27895046 -38.54487084
OS 33.2826487 -38.52822876
OS 33.28449782 -38.508813
OS 33.28449782 -38.50788844
OS 33.28449782 -38.50696388
OS 33.28449782 -38.50234108
OS 33.28357326 -38.49402004
OS 33.28172414 -38.48477444
OS 33.27987502 -38.47460428
OS 33.27617678 -38.462585
OS 33.27062942 -38.45149028
OS 33.2641575 -38.44039556
OS 33.26323294 -38.439471
OS 33.26045926 -38.43577276
OS 33.25583646 -38.43114996
OS 33.2502891 -38.42467804
OS 33.24196806 -38.41820612
OS 33.23272246 -38.41265876
OS 33.2225523 -38.4071114
OS 33.21053302 -38.4024886
OS 33.20960846 -38.4024886
OS 33.20591022 -38.40156404
OS 33.20036286 -38.40063948
OS 33.19296638 -38.39879036
OS 33.18187166 -38.3978658
OS 33.16800326 -38.39694124
OS 33.15136118 -38.39601668
OE
OB 34.37455406 -38.66413908 H
OS 34.20628414 -38.66413908
OS 34.20628414 -38.88418436
OS 34.38842246 -38.88418436
OS 34.40783822 -38.8832598
OS 34.41615926 -38.88233524
OS 34.42355574 -38.88141068
OS 34.4244803 -38.88141068
OS 34.42817854 -38.88048612
OS 34.4337259 -38.87956156
OS 34.44019782 -38.87771244
OS 34.45591534 -38.87216508
OS 34.47163286 -38.8647686
OS 34.47255742 -38.86384404
OS 34.4753311 -38.86199492
OS 34.47902934 -38.85922124
OS 34.48365214 -38.855523
OS 34.48827494 -38.84997564
OS 34.49474686 -38.84442828
OS 34.49936966 -38.8370318
OS 34.50491702 -38.82871076
OS 34.50584158 -38.8277862
OS 34.50676614 -38.82501252
OS 34.50861526 -38.81946516
OS 34.51138894 -38.81299324
OS 34.51416262 -38.80559676
OS 34.51601174 -38.79635116
OS 34.5169363 -38.78525644
OS 34.51786086 -38.77416172
OS 34.51786086 -38.7723126
OS 34.51786086 -38.76861436
OS 34.5169363 -38.76121788
OS 34.51508718 -38.75289684
OS 34.51323806 -38.74365124
OS 34.50953982 -38.73348108
OS 34.50491702 -38.72331092
OS 34.4984451 -38.71314076
OS 34.49752054 -38.7122162
OS 34.49474686 -38.70851796
OS 34.49104862 -38.70389516
OS 34.48550126 -38.6983478
OS 34.47810478 -38.69187588
OS 34.46885918 -38.68540396
OS 34.45868902 -38.6798566
OS 34.44666974 -38.6752338
OS 34.44482062 -38.67430924
OS 34.44112238 -38.67338468
OS 34.43280134 -38.67153556
OS 34.42263118 -38.66968644
OS 34.40968734 -38.66783732
OS 34.39396982 -38.6659882
OS 34.37455406 -38.66413908
OE
SE
S P 0
OB 48.49040086 -36.61402634 I
OS 48.17420134 -36.61402634
OS 48.17420134 -37.45999874
OS 48.04661206 -37.45999874
OS 48.04661206 -36.61402634
OS 47.73041254 -36.61402634
OS 47.73041254 -36.50030546
OS 48.49040086 -36.50030546
OS 48.49040086 -36.61402634
OE
OB 47.69990206 -37.45999874 I
OS 47.5556707 -37.45999874
OS 47.44333666 -37.16876234
OS 47.04115306 -37.16876234
OS 46.93714006 -37.45999874
OS 46.80261658 -37.45999874
OS 47.16874234 -36.50030546
OS 47.30742634 -36.50030546
OS 47.69990206 -37.45999874
OE
OB 49.31834434 -36.61402634 I
OS 48.75112678 -36.61402634
OS 48.75112678 -36.90664958
OS 49.2822865 -36.90664958
OS 49.2822865 -37.02037046
OS 48.75112678 -37.02037046
OS 48.75112678 -37.34627786
OS 49.34053378 -37.34627786
OS 49.34053378 -37.45999874
OS 48.6235375 -37.45999874
OS 48.6235375 -36.50030546
OS 49.31834434 -36.50030546
OS 49.31834434 -36.61402634
OE
OB 46.33386466 -36.5016923 I
OS 46.36160146 -36.50307914
OS 46.38933826 -36.50585282
OS 46.41707506 -36.51001334
OS 46.44065134 -36.51417386
OS 46.44203818 -36.51417386
OS 46.44481186 -36.5155607
OS 46.44897238 -36.5155607
OS 46.45451974 -36.51833438
OS 46.46977498 -36.5224949
OS 46.48919074 -36.5294291
OS 46.51138018 -36.53913698
OS 46.53495646 -36.55161854
OS 46.55853274 -36.56548694
OS 46.58072218 -36.58351586
OS 46.58210902 -36.5849027
OS 46.58349586 -36.58628954
OS 46.58765638 -36.59045006
OS 46.59320374 -36.59461058
OS 46.60707214 -36.60847898
OS 46.62371422 -36.62789474
OS 46.64174314 -36.65147102
OS 46.6611589 -36.67920782
OS 46.67918782 -36.71110514
OS 46.69444306 -36.74716298
OS 46.69444306 -36.74854982
OS 46.6958299 -36.7513235
OS 46.69860358 -36.75687086
OS 46.69999042 -36.7651919
OS 46.70415094 -36.77489978
OS 46.70692462 -36.7859945
OS 46.7096983 -36.79847606
OS 46.71385882 -36.8137313
OS 46.71801934 -36.82898654
OS 46.72079302 -36.84701546
OS 46.72772722 -36.88584698
OS 46.73188774 -36.92883902
OS 46.73327458 -36.97599158
OS 46.73327458 -36.97737842
OS 46.73327458 -36.9801521
OS 46.73327458 -36.9870863
OS 46.73327458 -36.9940205
OS 46.73188774 -37.00372838
OS 46.73188774 -37.0148231
OS 46.7305009 -37.04117306
OS 46.72634038 -37.07168354
OS 46.72217986 -37.10358086
OS 46.71524566 -37.13686502
OS 46.70692462 -37.17014918
OS 46.70692462 -37.17153602
OS 46.70553778 -37.1743097
OS 46.70415094 -37.17847022
OS 46.7027641 -37.18401758
OS 46.69721674 -37.19927282
OS 46.6888957 -37.21868858
OS 46.68057466 -37.24087802
OS 46.66947994 -37.26306746
OS 46.65561154 -37.28664374
OS 46.64174314 -37.30883318
OS 46.6403563 -37.31160686
OS 46.63480894 -37.31854106
OS 46.6264879 -37.32824894
OS 46.61539318 -37.3407305
OS 46.60291162 -37.3545989
OS 46.58765638 -37.3684673
OS 46.57240114 -37.38372254
OS 46.55437222 -37.3962041
OS 46.55159854 -37.39759094
OS 46.54605118 -37.40175146
OS 46.5363433 -37.40729882
OS 46.5224749 -37.41423302
OS 46.50583282 -37.42255406
OS 46.48641706 -37.42948826
OS 46.46422762 -37.4378093
OS 46.4392645 -37.4447435
OS 46.43649082 -37.4447435
OS 46.4323303 -37.44613034
OS 46.42816978 -37.44751718
OS 46.41430138 -37.44890402
OS 46.39488562 -37.4516777
OS 46.37269618 -37.45445138
OS 46.34634622 -37.45722506
OS 46.31722258 -37.4586119
OS 46.28532526 -37.45999874
OS 45.9400021 -37.45999874
OS 45.9400021 -36.50030546
OS 46.30890154 -36.50030546
OS 46.33386466 -36.5016923
OE
OB 46.28948578 -36.61402634 H
OS 46.06759138 -36.61402634
OS 46.06759138 -37.34627786
OS 46.29503314 -37.34627786
OS 46.30474102 -37.34489102
OS 46.32554362 -37.34350418
OS 46.3491199 -37.34211734
OS 46.37408302 -37.33934366
OS 46.39904614 -37.33518314
OS 46.41984874 -37.32963578
OS 46.42262242 -37.32824894
OS 46.42955662 -37.3268621
OS 46.4392645 -37.32270158
OS 46.45174606 -37.31715422
OS 46.46561446 -37.30883318
OS 46.47948286 -37.30051214
OS 46.49335126 -37.29080426
OS 46.50721966 -37.27970954
OS 46.5086065 -37.27693586
OS 46.51415386 -37.2713885
OS 46.5224749 -37.26168062
OS 46.53218278 -37.24781222
OS 46.5432775 -37.2297833
OS 46.55575906 -37.2089807
OS 46.56685378 -37.18540442
OS 46.57656166 -37.15905446
OS 46.57656166 -37.15766762
OS 46.5779485 -37.15489394
OS 46.57933534 -37.15073342
OS 46.58072218 -37.14518606
OS 46.58210902 -37.13825186
OS 46.5848827 -37.12854398
OS 46.58765638 -37.1188361
OS 46.59043006 -37.10774138
OS 46.59459058 -37.08000458
OS 46.5987511 -37.04810726
OS 46.60152478 -37.01204942
OS 46.60291162 -36.9732179
OS 46.60291162 -36.97183106
OS 46.60291162 -36.9662837
OS 46.60291162 -36.9593495
OS 46.60152478 -36.94825478
OS 46.60152478 -36.93577322
OS 46.60013794 -36.92190482
OS 46.5987511 -36.90526274
OS 46.59736426 -36.88862066
OS 46.59043006 -36.85117598
OS 46.58210902 -36.81234446
OS 46.56962746 -36.77628662
OS 46.56130642 -36.7582577
OS 46.55298538 -36.74300246
OS 46.55298538 -36.74161562
OS 46.5502117 -36.73884194
OS 46.54743802 -36.73468142
OS 46.54466434 -36.72913406
OS 46.53356962 -36.71526566
OS 46.51970122 -36.69862358
OS 46.5016723 -36.68059466
OS 46.4808697 -36.66256574
OS 46.45729342 -36.6473105
OS 46.4323303 -36.63482894
OS 46.42955662 -36.6334421
OS 46.42262242 -36.63205526
OS 46.41014086 -36.62789474
OS 46.39211194 -36.62373422
OS 46.3699225 -36.62096054
OS 46.3421857 -36.61680002
OS 46.32554362 -36.61541318
OS 46.3075147 -36.61541318
OS 46.28948578 -36.61402634
OE
OB 47.23531066 -36.60015794 H
OS 47.23531066 -36.60154478
OS 47.23392382 -36.60431846
OS 47.23392382 -36.60986582
OS 47.23115014 -36.61541318
OS 47.2297633 -36.62512106
OS 47.22698962 -36.63482894
OS 47.22144226 -36.65840522
OS 47.21450806 -36.68614202
OS 47.20480018 -36.7166525
OS 47.1950923 -36.74993666
OS 47.18261074 -36.78460766
OS 47.07859774 -37.06474934
OS 47.4031183 -37.06474934
OS 47.30326582 -36.80124974
OS 47.30326582 -36.7998629
OS 47.30187898 -36.79570238
OS 47.2991053 -36.78876818
OS 47.29633162 -36.78044714
OS 47.2921711 -36.77073926
OS 47.28801058 -36.7582577
OS 47.28385006 -36.7443893
OS 47.2783027 -36.7305209
OS 47.26720798 -36.69862358
OS 47.25611326 -36.66533942
OS 47.24501854 -36.63205526
OS 47.23531066 -36.60015794
OE
SE
S P 0
OB 53.64989524 -38.94890356 I
OS 53.57130764 -38.94890356
OS 53.57130764 -38.4487166
OS 53.57038308 -38.44964116
OS 53.56576028 -38.4533394
OS 53.56021292 -38.45888676
OS 53.55096732 -38.46535868
OS 53.54079716 -38.47367972
OS 53.52785332 -38.48292532
OS 53.51306036 -38.49309548
OS 53.49641828 -38.50326564
OS 53.49549372 -38.50326564
OS 53.49456916 -38.5041902
OS 53.4890218 -38.50788844
OS 53.4797762 -38.51251124
OS 53.46868148 -38.5180586
OS 53.45573764 -38.52453052
OS 53.44186924 -38.53100244
OS 53.42800084 -38.53747436
OS 53.41413244 -38.54302172
OS 53.41413244 -38.4672078
OS 53.415057 -38.4672078
OS 53.41690612 -38.46535868
OS 53.42060436 -38.46443412
OS 53.42522716 -38.46166044
OS 53.43077452 -38.45888676
OS 53.43724644 -38.45518852
OS 53.45296396 -38.44594292
OS 53.47145516 -38.43577276
OS 53.48994636 -38.42282892
OS 53.50936212 -38.40803596
OS 53.52877788 -38.39231844
OS 53.52970244 -38.39139388
OS 53.530627 -38.39046932
OS 53.53340068 -38.38769564
OS 53.53709892 -38.38492196
OS 53.54541996 -38.37567636
OS 53.55651468 -38.36458164
OS 53.5676094 -38.3516378
OS 53.57962868 -38.33684484
OS 53.58979884 -38.32205188
OS 53.59904444 -38.30633436
OS 53.64989524 -38.30633436
OS 53.64989524 -38.94890356
OE
OB 54.07334372 -38.30725892 I
OS 54.0807402 -38.30818348
OS 54.08906124 -38.30910804
OS 54.09830684 -38.3100326
OS 54.10755244 -38.31280628
OS 54.12974188 -38.31835364
OS 54.15193132 -38.32667468
OS 54.16302604 -38.33222204
OS 54.17412076 -38.33869396
OS 54.18429092 -38.347015
OS 54.19446108 -38.35533604
OS 54.19538564 -38.3562606
OS 54.1963102 -38.35718516
OS 54.19908388 -38.35995884
OS 54.20278212 -38.36365708
OS 54.20648036 -38.36920444
OS 54.21110316 -38.3747518
OS 54.22034876 -38.3886202
OS 54.22959436 -38.40618684
OS 54.2379154 -38.42652716
OS 54.24438732 -38.44964116
OS 54.24531188 -38.46166044
OS 54.24623644 -38.47460428
OS 54.24623644 -38.47552884
OS 54.24623644 -38.4764534
OS 54.24623644 -38.48200076
OS 54.24531188 -38.4903218
OS 54.24346276 -38.50049196
OS 54.24068908 -38.5134358
OS 54.23606628 -38.52637964
OS 54.23051892 -38.53932348
OS 54.22219788 -38.55226732
OS 54.22127332 -38.55411644
OS 54.21757508 -38.55781468
OS 54.21202772 -38.56336204
OS 54.20463124 -38.57075852
OS 54.19446108 -38.57907956
OS 54.1824418 -38.5874006
OS 54.1685734 -38.59572164
OS 54.15193132 -38.60311812
OS 54.15285588 -38.60311812
OS 54.154705 -38.60404268
OS 54.15747868 -38.60496724
OS 54.16117692 -38.60681636
OS 54.17227164 -38.61143916
OS 54.18521548 -38.61791108
OS 54.19908388 -38.62715668
OS 54.21387684 -38.63732684
OS 54.22774524 -38.65027068
OS 54.24068908 -38.66506364
OS 54.24068908 -38.6659882
OS 54.24161364 -38.66691276
OS 54.24531188 -38.67246012
OS 54.25085924 -38.68170572
OS 54.2564066 -38.693725
OS 54.26195396 -38.70851796
OS 54.26750132 -38.7260846
OS 54.27119956 -38.74550036
OS 54.27212412 -38.76676524
OS 54.27212412 -38.7676898
OS 54.27212412 -38.77046348
OS 54.27212412 -38.77508628
OS 54.27119956 -38.78063364
OS 54.270275 -38.78710556
OS 54.26935044 -38.7954266
OS 54.26750132 -38.8046722
OS 54.26472764 -38.81484236
OS 54.25825572 -38.83610724
OS 54.25363292 -38.84812652
OS 54.247161 -38.85922124
OS 54.24068908 -38.87124052
OS 54.2332926 -38.88233524
OS 54.224047 -38.89342996
OS 54.21387684 -38.90452468
OS 54.21295228 -38.90544924
OS 54.21110316 -38.90729836
OS 54.20832948 -38.91007204
OS 54.20370668 -38.91284572
OS 54.19723476 -38.91746852
OS 54.19076284 -38.92209132
OS 54.1824418 -38.92671412
OS 54.1731962 -38.93226148
OS 54.16302604 -38.93780884
OS 54.15100676 -38.94243164
OS 54.13806292 -38.94705444
OS 54.12511908 -38.95167724
OS 54.11032612 -38.95445092
OS 54.0946086 -38.9572246
OS 54.07889108 -38.95907372
OS 54.06132444 -38.95999828
OS 54.05207884 -38.95999828
OS 54.04560692 -38.95907372
OS 54.03728588 -38.95814916
OS 54.02804028 -38.9572246
OS 54.01787012 -38.95537548
OS 54.0067754 -38.9526018
OS 53.98181228 -38.94612988
OS 53.96886844 -38.94150708
OS 53.95684916 -38.93688428
OS 53.94390532 -38.93041236
OS 53.93096148 -38.92301588
OS 53.9189422 -38.91469484
OS 53.90784748 -38.90452468
OS 53.90692292 -38.90360012
OS 53.9050738 -38.901751
OS 53.90230012 -38.89897732
OS 53.89860188 -38.89435452
OS 53.89490364 -38.88880716
OS 53.88935628 -38.88233524
OS 53.88473348 -38.87493876
OS 53.87918612 -38.86569316
OS 53.87363876 -38.85644756
OS 53.86901596 -38.84535284
OS 53.85977036 -38.82223884
OS 53.85607212 -38.80837044
OS 53.85329844 -38.79450204
OS 53.85144932 -38.77970908
OS 53.85052476 -38.76491612
OS 53.85052476 -38.76399156
OS 53.85052476 -38.76214244
OS 53.85052476 -38.7584442
OS 53.85144932 -38.75474596
OS 53.85144932 -38.7491986
OS 53.85237388 -38.74272668
OS 53.854223 -38.72793372
OS 53.85792124 -38.71129164
OS 53.8634686 -38.69464956
OS 53.87178964 -38.67708292
OS 53.8819598 -38.66044084
OS 53.8819598 -38.65951628
OS 53.88380892 -38.65859172
OS 53.88750716 -38.65396892
OS 53.89490364 -38.64657244
OS 53.9050738 -38.63732684
OS 53.91801764 -38.62808124
OS 53.93373516 -38.61791108
OS 53.9513018 -38.60959004
OS 53.97256668 -38.60311812
OS 53.97164212 -38.60311812
OS 53.97071756 -38.60219356
OS 53.96794388 -38.601269
OS 53.96424564 -38.59941988
OS 53.9559246 -38.59572164
OS 53.94482988 -38.59017428
OS 53.9328106 -38.5827778
OS 53.92079132 -38.5735322
OS 53.9096966 -38.56336204
OS 53.89952644 -38.55226732
OS 53.89860188 -38.5504182
OS 53.8958282 -38.54671996
OS 53.89212996 -38.53932348
OS 53.88843172 -38.53007788
OS 53.88380892 -38.5180586
OS 53.88011068 -38.5041902
OS 53.877337 -38.48847268
OS 53.87641244 -38.4718306
OS 53.87641244 -38.47090604
OS 53.87641244 -38.46905692
OS 53.87641244 -38.46535868
OS 53.877337 -38.45981132
OS 53.87826156 -38.45426396
OS 53.87918612 -38.44686748
OS 53.88288436 -38.43114996
OS 53.88843172 -38.41265876
OS 53.89767732 -38.393243
OS 53.90322468 -38.38307284
OS 53.9096966 -38.37290268
OS 53.91801764 -38.36365708
OS 53.92633868 -38.35441148
OS 53.92726324 -38.35348692
OS 53.92911236 -38.35256236
OS 53.93188604 -38.34978868
OS 53.93558428 -38.347015
OS 53.94020708 -38.34331676
OS 53.946679 -38.33961852
OS 53.95407548 -38.33499572
OS 53.96147196 -38.33037292
OS 53.97071756 -38.32575012
OS 53.98088772 -38.32112732
OS 53.99198244 -38.31742908
OS 54.00400172 -38.31373084
OS 54.0298894 -38.30818348
OS 54.04468236 -38.30725892
OS 54.05947532 -38.30633436
OS 54.06779636 -38.30633436
OS 54.07334372 -38.30725892
OE
OB 53.23846604 -38.94890356 I
OS 53.14878372 -38.94890356
OS 53.14878372 -38.85922124
OS 53.23846604 -38.85922124
OS 53.23846604 -38.94890356
OE
OB 53.00177868 -38.39231844 I
OS 52.74567556 -38.39231844
OS 52.71146684 -38.56521116
OS 52.7123914 -38.5642866
OS 52.71424052 -38.56336204
OS 52.7170142 -38.56151292
OS 52.721637 -38.55873924
OS 52.72718436 -38.55596556
OS 52.73365628 -38.55226732
OS 52.74844924 -38.54487084
OS 52.76694044 -38.53747436
OS 52.78728076 -38.53100244
OS 52.8094702 -38.52637964
OS 52.82056492 -38.52453052
OS 52.84090524 -38.52453052
OS 52.8464526 -38.52545508
OS 52.85384908 -38.52637964
OS 52.86217012 -38.5273042
OS 52.87141572 -38.52915332
OS 52.88158588 -38.531927
OS 52.90377532 -38.53839892
OS 52.9157946 -38.54302172
OS 52.92781388 -38.54949364
OS 52.93983316 -38.55596556
OS 52.95185244 -38.56336204
OS 52.96294716 -38.57260764
OS 52.97404188 -38.5827778
OS 52.97496644 -38.58370236
OS 52.97681556 -38.58555148
OS 52.97958924 -38.58832516
OS 52.98328748 -38.59294796
OS 52.98791028 -38.59941988
OS 52.99253308 -38.6058918
OS 52.99808044 -38.61421284
OS 53.0036278 -38.62345844
OS 53.0082506 -38.6336286
OS 53.01379796 -38.64472332
OS 53.01842076 -38.65766716
OS 53.02304356 -38.670611
OS 53.0267418 -38.6844794
OS 53.02951548 -38.70019692
OS 53.0313646 -38.71591444
OS 53.03228916 -38.73255652
OS 53.03228916 -38.73348108
OS 53.03228916 -38.73625476
OS 53.03228916 -38.74087756
OS 53.0313646 -38.74734948
OS 53.03044004 -38.75474596
OS 53.02951548 -38.763067
OS 53.02766636 -38.77323716
OS 53.02581724 -38.78340732
OS 53.02026988 -38.80744588
OS 53.01102428 -38.832409
OS 53.00547692 -38.84535284
OS 52.99808044 -38.85737212
OS 52.99068396 -38.87031596
OS 52.98143836 -38.88233524
OS 52.9805138 -38.8832598
OS 52.97866468 -38.88603348
OS 52.97496644 -38.88973172
OS 52.97034364 -38.89435452
OS 52.96387172 -38.89990188
OS 52.95647524 -38.90729836
OS 52.94722964 -38.91377028
OS 52.93705948 -38.92116676
OS 52.92596476 -38.92856324
OS 52.91302092 -38.93503516
OS 52.89915252 -38.94150708
OS 52.88435956 -38.947979
OS 52.86864204 -38.9526018
OS 52.8510754 -38.95630004
OS 52.8325842 -38.95907372
OS 52.81316844 -38.95999828
OS 52.8048474 -38.95999828
OS 52.79837548 -38.95907372
OS 52.790979 -38.95814916
OS 52.78265796 -38.9572246
OS 52.7724878 -38.95630004
OS 52.76231764 -38.95352636
OS 52.73920364 -38.947979
OS 52.71608964 -38.93965796
OS 52.70407036 -38.9341106
OS 52.69205108 -38.92763868
OS 52.68095636 -38.9202422
OS 52.66986164 -38.91192116
OS 52.66893708 -38.9109966
OS 52.66708796 -38.91007204
OS 52.66523884 -38.9063738
OS 52.6615406 -38.90267556
OS 52.6569178 -38.89805276
OS 52.652295 -38.8925054
OS 52.64674764 -38.88510892
OS 52.64212484 -38.87678788
OS 52.63657748 -38.86846684
OS 52.63103012 -38.85829668
OS 52.62085996 -38.83610724
OS 52.61253892 -38.81021956
OS 52.60976524 -38.79635116
OS 52.60791612 -38.7815582
OS 52.69020196 -38.77508628
OS 52.69020196 -38.77601084
OS 52.69020196 -38.77785996
OS 52.69112652 -38.78063364
OS 52.69205108 -38.78525644
OS 52.69482476 -38.7954266
OS 52.698523 -38.809295
OS 52.70407036 -38.8231634
OS 52.71146684 -38.83888092
OS 52.72071244 -38.85274932
OS 52.73180716 -38.86569316
OS 52.73365628 -38.86661772
OS 52.73735452 -38.87031596
OS 52.744751 -38.87493876
OS 52.75492116 -38.88048612
OS 52.76601588 -38.88603348
OS 52.77988428 -38.89065628
OS 52.7956018 -38.89435452
OS 52.81316844 -38.89527908
OS 52.8187158 -38.89527908
OS 52.82241404 -38.89435452
OS 52.83350876 -38.89342996
OS 52.8464526 -38.88973172
OS 52.86217012 -38.88510892
OS 52.87788764 -38.87771244
OS 52.89452972 -38.86661772
OS 52.9019262 -38.8601458
OS 52.90932268 -38.85274932
OS 52.91024724 -38.85182476
OS 52.9111718 -38.8509002
OS 52.91302092 -38.84812652
OS 52.9157946 -38.84535284
OS 52.92226652 -38.83518268
OS 52.929663 -38.82223884
OS 52.93613492 -38.80652132
OS 52.94260684 -38.78710556
OS 52.94722964 -38.76399156
OS 52.94907876 -38.75197228
OS 52.94907876 -38.73902844
OS 52.94907876 -38.73810388
OS 52.94907876 -38.73625476
OS 52.94907876 -38.73255652
OS 52.9481542 -38.72793372
OS 52.9481542 -38.72238636
OS 52.94722964 -38.71591444
OS 52.94445596 -38.70112148
OS 52.93983316 -38.68355484
OS 52.93336124 -38.6659882
OS 52.92411564 -38.64934612
OS 52.9111718 -38.6336286
OS 52.9111718 -38.63270404
OS 52.90932268 -38.63177948
OS 52.90469988 -38.62715668
OS 52.89637884 -38.62068476
OS 52.88528412 -38.61328828
OS 52.87049116 -38.60681636
OS 52.85384908 -38.60034444
OS 52.83443332 -38.59572164
OS 52.8233386 -38.59387252
OS 52.80577196 -38.59387252
OS 52.79837548 -38.59479708
OS 52.78912988 -38.59572164
OS 52.77803516 -38.59849532
OS 52.76694044 -38.601269
OS 52.75492116 -38.6058918
OS 52.74290188 -38.61143916
OS 52.74197732 -38.61236372
OS 52.73827908 -38.61421284
OS 52.73273172 -38.61883564
OS 52.72533524 -38.62345844
OS 52.71793876 -38.62993036
OS 52.71054228 -38.6382514
OS 52.70222124 -38.64657244
OS 52.69574932 -38.6567426
OS 52.62178452 -38.64657244
OS 52.68373004 -38.31742908
OS 53.00177868 -38.31742908
OS 53.00177868 -38.39231844
OE
OB 53.23846604 -38.57445676 I
OS 53.14878372 -38.57445676
OS 53.14878372 -38.48477444
OS 53.23846604 -38.48477444
OS 53.23846604 -38.57445676
OE
OB 54.48199924 -38.57445676 I
OS 54.39231692 -38.57445676
OS 54.39231692 -38.48477444
OS 54.48199924 -38.48477444
OS 54.48199924 -38.57445676
OE
OB 56.14990548 -38.3100326 I
OS 56.165623 -38.31095716
OS 56.18226508 -38.31188172
OS 56.1979826 -38.31373084
OS 56.211851 -38.31557996
OS 56.21370012 -38.31557996
OS 56.22017204 -38.31742908
OS 56.22849308 -38.3192782
OS 56.2395878 -38.32205188
OS 56.25160708 -38.32667468
OS 56.26455092 -38.33222204
OS 56.27841932 -38.33869396
OS 56.2904386 -38.34609044
OS 56.29228772 -38.347015
OS 56.29598596 -38.34978868
OS 56.30153332 -38.35533604
OS 56.3089298 -38.36180796
OS 56.31725084 -38.370129
OS 56.32557188 -38.38122372
OS 56.33481748 -38.393243
OS 56.34221396 -38.4071114
OS 56.34313852 -38.40896052
OS 56.34498764 -38.41358332
OS 56.34868588 -38.42190436
OS 56.35238412 -38.43299908
OS 56.3551578 -38.44594292
OS 56.35885604 -38.46073588
OS 56.36070516 -38.47737796
OS 56.36162972 -38.4949446
OS 56.36162972 -38.49586916
OS 56.36162972 -38.49864284
OS 56.36162972 -38.50234108
OS 56.36070516 -38.508813
OS 56.3597806 -38.51528492
OS 56.35885604 -38.52360596
OS 56.35700692 -38.53285156
OS 56.3551578 -38.54302172
OS 56.34868588 -38.5642866
OS 56.34498764 -38.57538132
OS 56.33944028 -38.5874006
OS 56.33296836 -38.59941988
OS 56.32649644 -38.6105146
OS 56.3181754 -38.62160932
OS 56.3089298 -38.63270404
OS 56.30800524 -38.6336286
OS 56.30615612 -38.63547772
OS 56.30338244 -38.6382514
OS 56.29875964 -38.64102508
OS 56.29321228 -38.64564788
OS 56.2858158 -38.65027068
OS 56.2765702 -38.65581804
OS 56.26640004 -38.66044084
OS 56.25438076 -38.6659882
OS 56.24051236 -38.67153556
OS 56.2257194 -38.67615836
OS 56.20815276 -38.6798566
OS 56.18966156 -38.68355484
OS 56.16932124 -38.68632852
OS 56.14620724 -38.68817764
OS 56.12216868 -38.6891022
OS 55.95852156 -38.6891022
OS 55.95852156 -38.94890356
OS 55.87346204 -38.94890356
OS 55.87346204 -38.30910804
OS 56.13603708 -38.30910804
OS 56.14990548 -38.3100326
OE
OB 57.07723916 -38.94890356 I
OS 56.99587788 -38.94890356
OS 56.99587788 -38.41358332
OS 56.80911676 -38.94890356
OS 56.73330284 -38.94890356
OS 56.54839084 -38.40433772
OS 56.54839084 -38.94890356
OS 56.46702956 -38.94890356
OS 56.46702956 -38.30910804
OS 56.59369428 -38.30910804
OS 56.74532212 -38.763067
OS 56.74532212 -38.76399156
OS 56.74624668 -38.76584068
OS 56.74717124 -38.76861436
OS 56.74902036 -38.77323716
OS 56.7527186 -38.78433188
OS 56.7573414 -38.79820028
OS 56.7619642 -38.8139178
OS 56.76751156 -38.82963532
OS 56.77213436 -38.84442828
OS 56.7758326 -38.85737212
OS 56.77675716 -38.855523
OS 56.77768172 -38.8509002
OS 56.7804554 -38.84257916
OS 56.78415364 -38.83148444
OS 56.78877644 -38.81669148
OS 56.79524836 -38.79912484
OS 56.80172028 -38.77878452
OS 56.81004132 -38.75474596
OS 56.96351828 -38.30910804
OS 57.07723916 -38.30910804
OS 57.07723916 -38.94890356
OE
OB 55.39084172 -38.94890356 I
OS 55.31225412 -38.94890356
OS 55.31225412 -38.4487166
OS 55.31132956 -38.44964116
OS 55.30670676 -38.4533394
OS 55.3011594 -38.45888676
OS 55.2919138 -38.46535868
OS 55.28174364 -38.47367972
OS 55.2687998 -38.48292532
OS 55.25400684 -38.49309548
OS 55.23736476 -38.50326564
OS 55.2364402 -38.50326564
OS 55.23551564 -38.5041902
OS 55.22996828 -38.50788844
OS 55.22072268 -38.51251124
OS 55.20962796 -38.5180586
OS 55.19668412 -38.52453052
OS 55.18281572 -38.53100244
OS 55.16894732 -38.53747436
OS 55.15507892 -38.54302172
OS 55.15507892 -38.4672078
OS 55.15600348 -38.4672078
OS 55.1578526 -38.46535868
OS 55.16155084 -38.46443412
OS 55.16617364 -38.46166044
OS 55.171721 -38.45888676
OS 55.17819292 -38.45518852
OS 55.19391044 -38.44594292
OS 55.21240164 -38.43577276
OS 55.23089284 -38.42282892
OS 55.2503086 -38.40803596
OS 55.26972436 -38.39231844
OS 55.27064892 -38.39139388
OS 55.27157348 -38.39046932
OS 55.27434716 -38.38769564
OS 55.2780454 -38.38492196
OS 55.28636644 -38.37567636
OS 55.29746116 -38.36458164
OS 55.30855588 -38.3516378
OS 55.32057516 -38.33684484
OS 55.33074532 -38.32205188
OS 55.33999092 -38.30633436
OS 55.39084172 -38.30633436
OS 55.39084172 -38.94890356
OE
OB 54.48199924 -38.94890356 I
OS 54.39231692 -38.94890356
OS 54.39231692 -38.85922124
OS 54.48199924 -38.85922124
OS 54.48199924 -38.94890356
OE
OB 54.825011 -38.30725892 I
OS 54.83703028 -38.30910804
OS 54.85089868 -38.31188172
OS 54.86569164 -38.31557996
OS 54.88140916 -38.32020276
OS 54.89620212 -38.32759924
OS 54.89712668 -38.32759924
OS 54.89805124 -38.3285238
OS 54.90267404 -38.33129748
OS 54.91007052 -38.33592028
OS 54.91931612 -38.3423922
OS 54.92948628 -38.3516378
OS 54.940581 -38.36180796
OS 54.95075116 -38.37382724
OS 54.96092132 -38.38769564
OS 54.96184588 -38.38954476
OS 54.96554412 -38.39416756
OS 54.96924236 -38.4024886
OS 54.97571428 -38.41450788
OS 54.98126164 -38.42837628
OS 54.98865812 -38.4440938
OS 54.99513004 -38.462585
OS 55.0006774 -38.48292532
OS 55.0006774 -38.48384988
OS 55.00160196 -38.485699
OS 55.00252652 -38.48847268
OS 55.00345108 -38.49309548
OS 55.00437564 -38.49864284
OS 55.0053002 -38.50511476
OS 55.00714932 -38.5134358
OS 55.00807388 -38.5226814
OS 55.009923 -38.53285156
OS 55.01084756 -38.54394628
OS 55.01177212 -38.55689012
OS 55.01362124 -38.56983396
OS 55.0145458 -38.58462692
OS 55.0145458 -38.59941988
OS 55.01547036 -38.61606196
OS 55.01547036 -38.6336286
OS 55.01547036 -38.63455316
OS 55.01547036 -38.6382514
OS 55.01547036 -38.64472332
OS 55.01547036 -38.6521198
OS 55.0145458 -38.66228996
OS 55.0145458 -38.67338468
OS 55.01362124 -38.68540396
OS 55.01269668 -38.6983478
OS 55.009923 -38.72793372
OS 55.0053002 -38.7584442
OS 54.99975284 -38.78803012
OS 54.9960546 -38.80189852
OS 54.9914318 -38.81576692
OS 54.9914318 -38.81669148
OS 54.99050724 -38.8185406
OS 54.98865812 -38.82223884
OS 54.986809 -38.82686164
OS 54.98495988 -38.83333356
OS 54.98126164 -38.83980548
OS 54.97386516 -38.855523
OS 54.96461956 -38.87216508
OS 54.95260028 -38.89065628
OS 54.93873188 -38.90729836
OS 54.9220898 -38.92301588
OS 54.92116524 -38.92301588
OS 54.92024068 -38.924865
OS 54.917467 -38.92671412
OS 54.91376876 -38.92856324
OS 54.90914596 -38.93133692
OS 54.90452316 -38.93503516
OS 54.89065476 -38.94150708
OS 54.87401268 -38.947979
OS 54.85459692 -38.95445092
OS 54.83148292 -38.95814916
OS 54.8065198 -38.95999828
OS 54.7972742 -38.95999828
OS 54.79080228 -38.95907372
OS 54.7834058 -38.95814916
OS 54.7741602 -38.95630004
OS 54.76399004 -38.95445092
OS 54.75289532 -38.95167724
OS 54.7418006 -38.947979
OS 54.72978132 -38.94428076
OS 54.71776204 -38.9387334
OS 54.70574276 -38.93226148
OS 54.69372348 -38.924865
OS 54.6817042 -38.9156194
OS 54.67060948 -38.90544924
OS 54.66043932 -38.89435452
OS 54.65951476 -38.89342996
OS 54.65766564 -38.89065628
OS 54.65489196 -38.88603348
OS 54.65026916 -38.878637
OS 54.64564636 -38.87031596
OS 54.64102356 -38.85922124
OS 54.63455164 -38.8462774
OS 54.62900428 -38.83148444
OS 54.62345692 -38.81484236
OS 54.61790956 -38.7954266
OS 54.6123622 -38.77416172
OS 54.6077394 -38.75012316
OS 54.6031166 -38.72423548
OS 54.60034292 -38.69649868
OS 54.5984938 -38.6659882
OS 54.59756924 -38.6336286
OS 54.59756924 -38.63270404
OS 54.59756924 -38.6290058
OS 54.59756924 -38.62253388
OS 54.59756924 -38.6151374
OS 54.5984938 -38.60496724
OS 54.5984938 -38.59387252
OS 54.59941836 -38.58185324
OS 54.60034292 -38.56798484
OS 54.6031166 -38.53932348
OS 54.6077394 -38.508813
OS 54.61328676 -38.47830252
OS 54.616985 -38.46443412
OS 54.62068324 -38.45056572
OS 54.62068324 -38.44964116
OS 54.6216078 -38.44779204
OS 54.62345692 -38.4440938
OS 54.62530604 -38.439471
OS 54.62715516 -38.43299908
OS 54.6308534 -38.42652716
OS 54.63824988 -38.41080964
OS 54.64749548 -38.39416756
OS 54.65951476 -38.37660092
OS 54.67338316 -38.35903428
OS 54.69002524 -38.34424132
OS 54.6909498 -38.34424132
OS 54.69187436 -38.3423922
OS 54.69464804 -38.34054308
OS 54.69834628 -38.33869396
OS 54.70296908 -38.33499572
OS 54.70851644 -38.33222204
OS 54.72238484 -38.32482556
OS 54.73902692 -38.31835364
OS 54.75844268 -38.31188172
OS 54.78155668 -38.30818348
OS 54.8065198 -38.30633436
OS 54.81484084 -38.30633436
OS 54.825011 -38.30725892
OE
OB 49.95350436 -38.72331092 I
OS 50.040413 -38.72331092
OS 50.040413 -38.7954266
OS 49.95350436 -38.7954266
OS 49.95350436 -38.94890356
OS 49.87491676 -38.94890356
OS 49.87491676 -38.7954266
OS 49.5966242 -38.7954266
OS 49.5966242 -38.72331092
OS 49.88970972 -38.30910804
OS 49.95350436 -38.30910804
OS 49.95350436 -38.72331092
OE
OB 50.1467374 -38.95999828 I
OS 50.08386732 -38.95999828
OS 50.26970388 -38.29801332
OS 50.33257396 -38.29801332
OS 50.1467374 -38.95999828
OE
OB 50.59699812 -38.30725892 I
OS 50.6043946 -38.30818348
OS 50.6136402 -38.30910804
OS 50.62381036 -38.31095716
OS 50.63398052 -38.31280628
OS 50.65801908 -38.3192782
OS 50.68205764 -38.3285238
OS 50.69407692 -38.33407116
OS 50.7060962 -38.34054308
OS 50.71719092 -38.34886412
OS 50.72736108 -38.35810972
OS 50.72828564 -38.35903428
OS 50.73013476 -38.35995884
OS 50.73198388 -38.36365708
OS 50.73568212 -38.36735532
OS 50.74030492 -38.37197812
OS 50.74492772 -38.37845004
OS 50.74955052 -38.38492196
OS 50.75509788 -38.393243
OS 50.76434348 -38.41080964
OS 50.77358908 -38.43299908
OS 50.77728732 -38.4440938
OS 50.77913644 -38.45703764
OS 50.78098556 -38.46998148
OS 50.78191012 -38.48384988
OS 50.78191012 -38.485699
OS 50.78191012 -38.4903218
OS 50.78098556 -38.49771828
OS 50.780061 -38.50788844
OS 50.77821188 -38.51898316
OS 50.77451364 -38.531927
OS 50.7708154 -38.5457954
OS 50.76526804 -38.5596638
OS 50.76434348 -38.56151292
OS 50.76249436 -38.56613572
OS 50.75879612 -38.5735322
OS 50.75324876 -38.58370236
OS 50.74585228 -38.59479708
OS 50.73660668 -38.60866548
OS 50.72551196 -38.62253388
OS 50.71256812 -38.6382514
OS 50.710719 -38.64010052
OS 50.7060962 -38.64564788
OS 50.7014734 -38.65027068
OS 50.6968506 -38.65489348
OS 50.69130324 -38.66044084
OS 50.68390676 -38.66783732
OS 50.67651028 -38.6752338
OS 50.66726468 -38.68355484
OS 50.65801908 -38.69280044
OS 50.64692436 -38.7029706
OS 50.63490508 -38.71314076
OS 50.62196124 -38.72516004
OS 50.60716828 -38.73717932
OS 50.59237532 -38.75012316
OS 50.59145076 -38.75104772
OS 50.58960164 -38.75289684
OS 50.5859034 -38.75567052
OS 50.5812806 -38.75936876
OS 50.57573324 -38.76491612
OS 50.56926132 -38.77046348
OS 50.55446836 -38.78248276
OS 50.53875084 -38.79635116
OS 50.52395788 -38.81021956
OS 50.51101404 -38.82223884
OS 50.50546668 -38.82686164
OS 50.50084388 -38.83148444
OS 50.49991932 -38.832409
OS 50.49714564 -38.83518268
OS 50.4934474 -38.83888092
OS 50.4888246 -38.84442828
OS 50.4842018 -38.8509002
OS 50.47865444 -38.85737212
OS 50.46755972 -38.87308964
OS 50.78283468 -38.87308964
OS 50.78283468 -38.94890356
OS 50.35846164 -38.94890356
OS 50.35846164 -38.947979
OS 50.35846164 -38.94428076
OS 50.35846164 -38.9387334
OS 50.3593862 -38.93133692
OS 50.36031076 -38.92301588
OS 50.36215988 -38.91377028
OS 50.364009 -38.90452468
OS 50.36770724 -38.89435452
OS 50.36770724 -38.89342996
OS 50.3686318 -38.8925054
OS 50.37048092 -38.88695804
OS 50.37417916 -38.878637
OS 50.37972652 -38.86754228
OS 50.387123 -38.85459844
OS 50.3963686 -38.83980548
OS 50.40653876 -38.82501252
OS 50.4194826 -38.809295
OS 50.4194826 -38.80837044
OS 50.42133172 -38.80744588
OS 50.42595452 -38.80189852
OS 50.43427556 -38.79357748
OS 50.44629484 -38.7815582
OS 50.46016324 -38.7676898
OS 50.47772988 -38.75104772
OS 50.49899476 -38.73255652
OS 50.52210876 -38.71314076
OS 50.52303332 -38.7122162
OS 50.52673156 -38.70944252
OS 50.53227892 -38.70481972
OS 50.53875084 -38.69927236
OS 50.54707188 -38.69187588
OS 50.55724204 -38.68355484
OS 50.5674122 -38.67430924
OS 50.57943148 -38.66413908
OS 50.60254548 -38.64194964
OS 50.62565948 -38.6197602
OS 50.6367542 -38.60866548
OS 50.64692436 -38.59757076
OS 50.65616996 -38.5874006
OS 50.66356644 -38.57723044
OS 50.66356644 -38.57630588
OS 50.66541556 -38.57538132
OS 50.66726468 -38.57260764
OS 50.6691138 -38.5689094
OS 50.67558572 -38.55873924
OS 50.6829822 -38.54671996
OS 50.68945412 -38.531927
OS 50.69592604 -38.51620948
OS 50.69962428 -38.49864284
OS 50.7014734 -38.48200076
OS 50.7014734 -38.4810762
OS 50.7014734 -38.48015164
OS 50.70054884 -38.47460428
OS 50.69962428 -38.46535868
OS 50.6968506 -38.45518852
OS 50.69315236 -38.44224468
OS 50.68668044 -38.42930084
OS 50.6783594 -38.416357
OS 50.66726468 -38.40341316
OS 50.66541556 -38.40156404
OS 50.66079276 -38.3978658
OS 50.65432084 -38.393243
OS 50.64415068 -38.38677108
OS 50.63120684 -38.38122372
OS 50.61641388 -38.37567636
OS 50.59884724 -38.37197812
OS 50.57943148 -38.37105356
OS 50.57388412 -38.37105356
OS 50.57018588 -38.37197812
OS 50.55909116 -38.37290268
OS 50.54614732 -38.37567636
OS 50.53227892 -38.3793746
OS 50.5165614 -38.38584652
OS 50.50176844 -38.39416756
OS 50.48790004 -38.40526228
OS 50.48605092 -38.4071114
OS 50.48235268 -38.4117342
OS 50.47680532 -38.41913068
OS 50.47125796 -38.4302254
OS 50.46478604 -38.44316924
OS 50.45923868 -38.45981132
OS 50.45554044 -38.47830252
OS 50.45369132 -38.4995674
OS 50.3732546 -38.49124636
OS 50.3732546 -38.4903218
OS 50.37417916 -38.48754812
OS 50.37417916 -38.48292532
OS 50.37510372 -38.4764534
OS 50.37695284 -38.46905692
OS 50.37880196 -38.46073588
OS 50.38157564 -38.45056572
OS 50.38434932 -38.44039556
OS 50.3917458 -38.41820612
OS 50.40284052 -38.39601668
OS 50.40931244 -38.38492196
OS 50.41763348 -38.37382724
OS 50.42595452 -38.36365708
OS 50.43520012 -38.35441148
OS 50.43612468 -38.35348692
OS 50.4379738 -38.35256236
OS 50.44074748 -38.34978868
OS 50.44537028 -38.347015
OS 50.45091764 -38.34331676
OS 50.45738956 -38.33961852
OS 50.46478604 -38.33499572
OS 50.47403164 -38.33037292
OS 50.4842018 -38.32575012
OS 50.49529652 -38.32112732
OS 50.5073158 -38.31742908
OS 50.52025964 -38.31373084
OS 50.53412804 -38.31095716
OS 50.548921 -38.30818348
OS 50.56463852 -38.30725892
OS 50.5812806 -38.30633436
OS 50.5905262 -38.30633436
OS 50.59699812 -38.30725892
OE
OB 48.67576244 -38.94890356 I
OS 48.59717484 -38.94890356
OS 48.59717484 -38.4487166
OS 48.59625028 -38.44964116
OS 48.59162748 -38.4533394
OS 48.58608012 -38.45888676
OS 48.57683452 -38.46535868
OS 48.56666436 -38.47367972
OS 48.55372052 -38.48292532
OS 48.53892756 -38.49309548
OS 48.52228548 -38.50326564
OS 48.52136092 -38.50326564
OS 48.52043636 -38.5041902
OS 48.514889 -38.50788844
OS 48.5056434 -38.51251124
OS 48.49454868 -38.5180586
OS 48.48160484 -38.52453052
OS 48.46773644 -38.53100244
OS 48.45386804 -38.53747436
OS 48.43999964 -38.54302172
OS 48.43999964 -38.4672078
OS 48.4409242 -38.4672078
OS 48.44277332 -38.46535868
OS 48.44647156 -38.46443412
OS 48.45109436 -38.46166044
OS 48.45664172 -38.45888676
OS 48.46311364 -38.45518852
OS 48.47883116 -38.44594292
OS 48.49732236 -38.43577276
OS 48.51581356 -38.42282892
OS 48.53522932 -38.40803596
OS 48.55464508 -38.39231844
OS 48.55556964 -38.39139388
OS 48.5564942 -38.39046932
OS 48.55926788 -38.38769564
OS 48.56296612 -38.38492196
OS 48.57128716 -38.37567636
OS 48.58238188 -38.36458164
OS 48.5934766 -38.3516378
OS 48.60549588 -38.33684484
OS 48.61566604 -38.32205188
OS 48.62491164 -38.30633436
OS 48.67576244 -38.30633436
OS 48.67576244 -38.94890356
OE
OB 48.9032042 -38.95999828 I
OS 48.84033412 -38.95999828
OS 49.02617068 -38.29801332
OS 49.08904076 -38.29801332
OS 48.9032042 -38.95999828
OE
OB 49.35346492 -38.30725892 I
OS 49.3608614 -38.30818348
OS 49.370107 -38.30910804
OS 49.38027716 -38.31095716
OS 49.39044732 -38.31280628
OS 49.41448588 -38.3192782
OS 49.43852444 -38.3285238
OS 49.45054372 -38.33407116
OS 49.462563 -38.34054308
OS 49.47365772 -38.34886412
OS 49.48382788 -38.35810972
OS 49.48475244 -38.35903428
OS 49.48660156 -38.35995884
OS 49.48845068 -38.36365708
OS 49.49214892 -38.36735532
OS 49.49677172 -38.37197812
OS 49.50139452 -38.37845004
OS 49.50601732 -38.38492196
OS 49.51156468 -38.393243
OS 49.52081028 -38.41080964
OS 49.53005588 -38.43299908
OS 49.53375412 -38.4440938
OS 49.53560324 -38.45703764
OS 49.53745236 -38.46998148
OS 49.53837692 -38.48384988
OS 49.53837692 -38.485699
OS 49.53837692 -38.4903218
OS 49.53745236 -38.49771828
OS 49.5365278 -38.50788844
OS 49.53467868 -38.51898316
OS 49.53098044 -38.531927
OS 49.5272822 -38.5457954
OS 49.52173484 -38.5596638
OS 49.52081028 -38.56151292
OS 49.51896116 -38.56613572
OS 49.51526292 -38.5735322
OS 49.50971556 -38.58370236
OS 49.50231908 -38.59479708
OS 49.49307348 -38.60866548
OS 49.48197876 -38.62253388
OS 49.46903492 -38.6382514
OS 49.4671858 -38.64010052
OS 49.462563 -38.64564788
OS 49.4579402 -38.65027068
OS 49.4533174 -38.65489348
OS 49.44777004 -38.66044084
OS 49.44037356 -38.66783732
OS 49.43297708 -38.6752338
OS 49.42373148 -38.68355484
OS 49.41448588 -38.69280044
OS 49.40339116 -38.7029706
OS 49.39137188 -38.71314076
OS 49.37842804 -38.72516004
OS 49.36363508 -38.73717932
OS 49.34884212 -38.75012316
OS 49.34791756 -38.75104772
OS 49.34606844 -38.75289684
OS 49.3423702 -38.75567052
OS 49.3377474 -38.75936876
OS 49.33220004 -38.76491612
OS 49.32572812 -38.77046348
OS 49.31093516 -38.78248276
OS 49.29521764 -38.79635116
OS 49.28042468 -38.81021956
OS 49.26748084 -38.82223884
OS 49.26193348 -38.82686164
OS 49.25731068 -38.83148444
OS 49.25638612 -38.832409
OS 49.25361244 -38.83518268
OS 49.2499142 -38.83888092
OS 49.2452914 -38.84442828
OS 49.2406686 -38.8509002
OS 49.23512124 -38.85737212
OS 49.22402652 -38.87308964
OS 49.53930148 -38.87308964
OS 49.53930148 -38.94890356
OS 49.11492844 -38.94890356
OS 49.11492844 -38.947979
OS 49.11492844 -38.94428076
OS 49.11492844 -38.9387334
OS 49.115853 -38.93133692
OS 49.11677756 -38.92301588
OS 49.11862668 -38.91377028
OS 49.1204758 -38.90452468
OS 49.12417404 -38.89435452
OS 49.12417404 -38.89342996
OS 49.1250986 -38.8925054
OS 49.12694772 -38.88695804
OS 49.13064596 -38.878637
OS 49.13619332 -38.86754228
OS 49.1435898 -38.85459844
OS 49.1528354 -38.83980548
OS 49.16300556 -38.82501252
OS 49.1759494 -38.809295
OS 49.1759494 -38.80837044
OS 49.17779852 -38.80744588
OS 49.18242132 -38.80189852
OS 49.19074236 -38.79357748
OS 49.20276164 -38.7815582
OS 49.21663004 -38.7676898
OS 49.23419668 -38.75104772
OS 49.25546156 -38.73255652
OS 49.27857556 -38.71314076
OS 49.27950012 -38.7122162
OS 49.28319836 -38.70944252
OS 49.28874572 -38.70481972
OS 49.29521764 -38.69927236
OS 49.30353868 -38.69187588
OS 49.31370884 -38.68355484
OS 49.323879 -38.67430924
OS 49.33589828 -38.66413908
OS 49.35901228 -38.64194964
OS 49.38212628 -38.6197602
OS 49.393221 -38.60866548
OS 49.40339116 -38.59757076
OS 49.41263676 -38.5874006
OS 49.42003324 -38.57723044
OS 49.42003324 -38.57630588
OS 49.42188236 -38.57538132
OS 49.42373148 -38.57260764
OS 49.4255806 -38.5689094
OS 49.43205252 -38.55873924
OS 49.439449 -38.54671996
OS 49.44592092 -38.531927
OS 49.45239284 -38.51620948
OS 49.45609108 -38.49864284
OS 49.4579402 -38.48200076
OS 49.4579402 -38.4810762
OS 49.4579402 -38.48015164
OS 49.45701564 -38.47460428
OS 49.45609108 -38.46535868
OS 49.4533174 -38.45518852
OS 49.44961916 -38.44224468
OS 49.44314724 -38.42930084
OS 49.4348262 -38.416357
OS 49.42373148 -38.40341316
OS 49.42188236 -38.40156404
OS 49.41725956 -38.3978658
OS 49.41078764 -38.393243
OS 49.40061748 -38.38677108
OS 49.38767364 -38.38122372
OS 49.37288068 -38.37567636
OS 49.35531404 -38.37197812
OS 49.33589828 -38.37105356
OS 49.33035092 -38.37105356
OS 49.32665268 -38.37197812
OS 49.31555796 -38.37290268
OS 49.30261412 -38.37567636
OS 49.28874572 -38.3793746
OS 49.2730282 -38.38584652
OS 49.25823524 -38.39416756
OS 49.24436684 -38.40526228
OS 49.24251772 -38.4071114
OS 49.23881948 -38.4117342
OS 49.23327212 -38.41913068
OS 49.22772476 -38.4302254
OS 49.22125284 -38.44316924
OS 49.21570548 -38.45981132
OS 49.21200724 -38.47830252
OS 49.21015812 -38.4995674
OS 49.1297214 -38.49124636
OS 49.1297214 -38.4903218
OS 49.13064596 -38.48754812
OS 49.13064596 -38.48292532
OS 49.13157052 -38.4764534
OS 49.13341964 -38.46905692
OS 49.13526876 -38.46073588
OS 49.13804244 -38.45056572
OS 49.14081612 -38.44039556
OS 49.1482126 -38.41820612
OS 49.15930732 -38.39601668
OS 49.16577924 -38.38492196
OS 49.17410028 -38.37382724
OS 49.18242132 -38.36365708
OS 49.19166692 -38.35441148
OS 49.19259148 -38.35348692
OS 49.1944406 -38.35256236
OS 49.19721428 -38.34978868
OS 49.20183708 -38.347015
OS 49.20738444 -38.34331676
OS 49.21385636 -38.33961852
OS 49.22125284 -38.33499572
OS 49.23049844 -38.33037292
OS 49.2406686 -38.32575012
OS 49.25176332 -38.32112732
OS 49.2637826 -38.31742908
OS 49.27672644 -38.31373084
OS 49.29059484 -38.31095716
OS 49.3053878 -38.30818348
OS 49.32110532 -38.30725892
OS 49.3377474 -38.30633436
OS 49.346993 -38.30633436
OS 49.35346492 -38.30725892
OE
OB 51.0944114 -38.30725892 I
OS 51.10643068 -38.30910804
OS 51.12029908 -38.31188172
OS 51.13509204 -38.31557996
OS 51.15080956 -38.32020276
OS 51.16560252 -38.32759924
OS 51.16652708 -38.32759924
OS 51.16745164 -38.3285238
OS 51.17207444 -38.33129748
OS 51.17947092 -38.33592028
OS 51.18871652 -38.3423922
OS 51.19888668 -38.3516378
OS 51.2099814 -38.36180796
OS 51.22015156 -38.37382724
OS 51.23032172 -38.38769564
OS 51.23124628 -38.38954476
OS 51.23494452 -38.39416756
OS 51.23864276 -38.4024886
OS 51.24511468 -38.41450788
OS 51.25066204 -38.42837628
OS 51.25805852 -38.4440938
OS 51.26453044 -38.462585
OS 51.2700778 -38.48292532
OS 51.2700778 -38.48384988
OS 51.27100236 -38.485699
OS 51.27192692 -38.48847268
OS 51.27285148 -38.49309548
OS 51.27377604 -38.49864284
OS 51.2747006 -38.50511476
OS 51.27654972 -38.5134358
OS 51.27747428 -38.5226814
OS 51.2793234 -38.53285156
OS 51.28024796 -38.54394628
OS 51.28117252 -38.55689012
OS 51.28302164 -38.56983396
OS 51.2839462 -38.58462692
OS 51.2839462 -38.59941988
OS 51.28487076 -38.61606196
OS 51.28487076 -38.6336286
OS 51.28487076 -38.63455316
OS 51.28487076 -38.6382514
OS 51.28487076 -38.64472332
OS 51.28487076 -38.6521198
OS 51.2839462 -38.66228996
OS 51.2839462 -38.67338468
OS 51.28302164 -38.68540396
OS 51.28209708 -38.6983478
OS 51.2793234 -38.72793372
OS 51.2747006 -38.7584442
OS 51.26915324 -38.78803012
OS 51.265455 -38.80189852
OS 51.2608322 -38.81576692
OS 51.2608322 -38.81669148
OS 51.25990764 -38.8185406
OS 51.25805852 -38.82223884
OS 51.2562094 -38.82686164
OS 51.25436028 -38.83333356
OS 51.25066204 -38.83980548
OS 51.24326556 -38.855523
OS 51.23401996 -38.87216508
OS 51.22200068 -38.89065628
OS 51.20813228 -38.90729836
OS 51.1914902 -38.92301588
OS 51.19056564 -38.92301588
OS 51.18964108 -38.924865
OS 51.1868674 -38.92671412
OS 51.18316916 -38.92856324
OS 51.17854636 -38.93133692
OS 51.17392356 -38.93503516
OS 51.16005516 -38.94150708
OS 51.14341308 -38.947979
OS 51.12399732 -38.95445092
OS 51.10088332 -38.95814916
OS 51.0759202 -38.95999828
OS 51.0666746 -38.95999828
OS 51.06020268 -38.95907372
OS 51.0528062 -38.95814916
OS 51.0435606 -38.95630004
OS 51.03339044 -38.95445092
OS 51.02229572 -38.95167724
OS 51.011201 -38.947979
OS 50.99918172 -38.94428076
OS 50.98716244 -38.9387334
OS 50.97514316 -38.93226148
OS 50.96312388 -38.924865
OS 50.9511046 -38.9156194
OS 50.94000988 -38.90544924
OS 50.92983972 -38.89435452
OS 50.92891516 -38.89342996
OS 50.92706604 -38.89065628
OS 50.92429236 -38.88603348
OS 50.91966956 -38.878637
OS 50.91504676 -38.87031596
OS 50.91042396 -38.85922124
OS 50.90395204 -38.8462774
OS 50.89840468 -38.83148444
OS 50.89285732 -38.81484236
OS 50.88730996 -38.7954266
OS 50.8817626 -38.77416172
OS 50.8771398 -38.75012316
OS 50.872517 -38.72423548
OS 50.86974332 -38.69649868
OS 50.8678942 -38.6659882
OS 50.86696964 -38.6336286
OS 50.86696964 -38.63270404
OS 50.86696964 -38.6290058
OS 50.86696964 -38.62253388
OS 50.86696964 -38.6151374
OS 50.8678942 -38.60496724
OS 50.8678942 -38.59387252
OS 50.86881876 -38.58185324
OS 50.86974332 -38.56798484
OS 50.872517 -38.53932348
OS 50.8771398 -38.508813
OS 50.88268716 -38.47830252
OS 50.8863854 -38.46443412
OS 50.89008364 -38.45056572
OS 50.89008364 -38.44964116
OS 50.8910082 -38.44779204
OS 50.89285732 -38.4440938
OS 50.89470644 -38.439471
OS 50.89655556 -38.43299908
OS 50.9002538 -38.42652716
OS 50.90765028 -38.41080964
OS 50.91689588 -38.39416756
OS 50.92891516 -38.37660092
OS 50.94278356 -38.35903428
OS 50.95942564 -38.34424132
OS 50.9603502 -38.34424132
OS 50.96127476 -38.3423922
OS 50.96404844 -38.34054308
OS 50.96774668 -38.33869396
OS 50.97236948 -38.33499572
OS 50.97791684 -38.33222204
OS 50.99178524 -38.32482556
OS 51.00842732 -38.31835364
OS 51.02784308 -38.31188172
OS 51.05095708 -38.30818348
OS 51.0759202 -38.30633436
OS 51.08424124 -38.30633436
OS 51.0944114 -38.30725892
OE
OB 51.59182468 -38.30725892 I
OS 51.59922116 -38.30818348
OS 51.60846676 -38.30910804
OS 51.61863692 -38.31095716
OS 51.62880708 -38.31280628
OS 51.65284564 -38.3192782
OS 51.6768842 -38.3285238
OS 51.68890348 -38.33407116
OS 51.70092276 -38.34054308
OS 51.71201748 -38.34886412
OS 51.72218764 -38.35810972
OS 51.7231122 -38.35903428
OS 51.72496132 -38.35995884
OS 51.72681044 -38.36365708
OS 51.73050868 -38.36735532
OS 51.73513148 -38.37197812
OS 51.73975428 -38.37845004
OS 51.74437708 -38.38492196
OS 51.74992444 -38.393243
OS 51.75917004 -38.41080964
OS 51.76841564 -38.43299908
OS 51.77211388 -38.4440938
OS 51.773963 -38.45703764
OS 51.77581212 -38.46998148
OS 51.77673668 -38.48384988
OS 51.77673668 -38.485699
OS 51.77673668 -38.4903218
OS 51.77581212 -38.49771828
OS 51.77488756 -38.50788844
OS 51.77303844 -38.51898316
OS 51.7693402 -38.531927
OS 51.76564196 -38.5457954
OS 51.7600946 -38.5596638
OS 51.75917004 -38.56151292
OS 51.75732092 -38.56613572
OS 51.75362268 -38.5735322
OS 51.74807532 -38.58370236
OS 51.74067884 -38.59479708
OS 51.73143324 -38.60866548
OS 51.72033852 -38.62253388
OS 51.70739468 -38.6382514
OS 51.70554556 -38.64010052
OS 51.70092276 -38.64564788
OS 51.69629996 -38.65027068
OS 51.69167716 -38.65489348
OS 51.6861298 -38.66044084
OS 51.67873332 -38.66783732
OS 51.67133684 -38.6752338
OS 51.66209124 -38.68355484
OS 51.65284564 -38.69280044
OS 51.64175092 -38.7029706
OS 51.62973164 -38.71314076
OS 51.6167878 -38.72516004
OS 51.60199484 -38.73717932
OS 51.58720188 -38.75012316
OS 51.58627732 -38.75104772
OS 51.5844282 -38.75289684
OS 51.58072996 -38.75567052
OS 51.57610716 -38.75936876
OS 51.5705598 -38.76491612
OS 51.56408788 -38.77046348
OS 51.54929492 -38.78248276
OS 51.5335774 -38.79635116
OS 51.51878444 -38.81021956
OS 51.5058406 -38.82223884
OS 51.50029324 -38.82686164
OS 51.49567044 -38.83148444
OS 51.49474588 -38.832409
OS 51.4919722 -38.83518268
OS 51.48827396 -38.83888092
OS 51.48365116 -38.84442828
OS 51.47902836 -38.8509002
OS 51.473481 -38.85737212
OS 51.46238628 -38.87308964
OS 51.77766124 -38.87308964
OS 51.77766124 -38.94890356
OS 51.3532882 -38.94890356
OS 51.3532882 -38.947979
OS 51.3532882 -38.94428076
OS 51.3532882 -38.9387334
OS 51.35421276 -38.93133692
OS 51.35513732 -38.92301588
OS 51.35698644 -38.91377028
OS 51.35883556 -38.90452468
OS 51.3625338 -38.89435452
OS 51.3625338 -38.89342996
OS 51.36345836 -38.8925054
OS 51.36530748 -38.88695804
OS 51.36900572 -38.878637
OS 51.37455308 -38.86754228
OS 51.38194956 -38.85459844
OS 51.39119516 -38.83980548
OS 51.40136532 -38.82501252
OS 51.41430916 -38.809295
OS 51.41430916 -38.80837044
OS 51.41615828 -38.80744588
OS 51.42078108 -38.80189852
OS 51.42910212 -38.79357748
OS 51.4411214 -38.7815582
OS 51.4549898 -38.7676898
OS 51.47255644 -38.75104772
OS 51.49382132 -38.73255652
OS 51.51693532 -38.71314076
OS 51.51785988 -38.7122162
OS 51.52155812 -38.70944252
OS 51.52710548 -38.70481972
OS 51.5335774 -38.69927236
OS 51.54189844 -38.69187588
OS 51.5520686 -38.68355484
OS 51.56223876 -38.67430924
OS 51.57425804 -38.66413908
OS 51.59737204 -38.64194964
OS 51.62048604 -38.6197602
OS 51.63158076 -38.60866548
OS 51.64175092 -38.59757076
OS 51.65099652 -38.5874006
OS 51.658393 -38.57723044
OS 51.658393 -38.57630588
OS 51.66024212 -38.57538132
OS 51.66209124 -38.57260764
OS 51.66394036 -38.5689094
OS 51.67041228 -38.55873924
OS 51.67780876 -38.54671996
OS 51.68428068 -38.531927
OS 51.6907526 -38.51620948
OS 51.69445084 -38.49864284
OS 51.69629996 -38.48200076
OS 51.69629996 -38.4810762
OS 51.69629996 -38.48015164
OS 51.6953754 -38.47460428
OS 51.69445084 -38.46535868
OS 51.69167716 -38.45518852
OS 51.68797892 -38.44224468
OS 51.681507 -38.42930084
OS 51.67318596 -38.416357
OS 51.66209124 -38.40341316
OS 51.66024212 -38.40156404
OS 51.65561932 -38.3978658
OS 51.6491474 -38.393243
OS 51.63897724 -38.38677108
OS 51.6260334 -38.38122372
OS 51.61124044 -38.37567636
OS 51.5936738 -38.37197812
OS 51.57425804 -38.37105356
OS 51.56871068 -38.37105356
OS 51.56501244 -38.37197812
OS 51.55391772 -38.37290268
OS 51.54097388 -38.37567636
OS 51.52710548 -38.3793746
OS 51.51138796 -38.38584652
OS 51.496595 -38.39416756
OS 51.4827266 -38.40526228
OS 51.48087748 -38.4071114
OS 51.47717924 -38.4117342
OS 51.47163188 -38.41913068
OS 51.46608452 -38.4302254
OS 51.4596126 -38.44316924
OS 51.45406524 -38.45981132
OS 51.450367 -38.47830252
OS 51.44851788 -38.4995674
OS 51.36808116 -38.49124636
OS 51.36808116 -38.4903218
OS 51.36900572 -38.48754812
OS 51.36900572 -38.48292532
OS 51.36993028 -38.4764534
OS 51.3717794 -38.46905692
OS 51.37362852 -38.46073588
OS 51.3764022 -38.45056572
OS 51.37917588 -38.44039556
OS 51.38657236 -38.41820612
OS 51.39766708 -38.39601668
OS 51.404139 -38.38492196
OS 51.41246004 -38.37382724
OS 51.42078108 -38.36365708
OS 51.43002668 -38.35441148
OS 51.43095124 -38.35348692
OS 51.43280036 -38.35256236
OS 51.43557404 -38.34978868
OS 51.44019684 -38.347015
OS 51.4457442 -38.34331676
OS 51.45221612 -38.33961852
OS 51.4596126 -38.33499572
OS 51.4688582 -38.33037292
OS 51.47902836 -38.32575012
OS 51.49012308 -38.32112732
OS 51.50214236 -38.31742908
OS 51.5150862 -38.31373084
OS 51.5289546 -38.31095716
OS 51.54374756 -38.30818348
OS 51.55946508 -38.30725892
OS 51.57610716 -38.30633436
OS 51.58535276 -38.30633436
OS 51.59182468 -38.30725892
OE
OB 52.08184148 -38.30725892 I
OS 52.09386076 -38.30910804
OS 52.10865372 -38.31188172
OS 52.1252958 -38.31650452
OS 52.14193788 -38.32205188
OS 52.15857996 -38.32944836
OS 52.15950452 -38.32944836
OS 52.16042908 -38.33037292
OS 52.16597644 -38.3331466
OS 52.17429748 -38.33869396
OS 52.18354308 -38.34516588
OS 52.1946378 -38.35441148
OS 52.20573252 -38.36458164
OS 52.21682724 -38.37660092
OS 52.22607284 -38.39046932
OS 52.2269974 -38.39231844
OS 52.22977108 -38.39694124
OS 52.23346932 -38.40526228
OS 52.23809212 -38.41543244
OS 52.24271492 -38.42745172
OS 52.24641316 -38.44132012
OS 52.24918684 -38.45703764
OS 52.2501114 -38.47275516
OS 52.2501114 -38.47460428
OS 52.2501114 -38.48015164
OS 52.24918684 -38.48754812
OS 52.24733772 -38.49771828
OS 52.24456404 -38.50973756
OS 52.23994124 -38.5226814
OS 52.23439388 -38.53562524
OS 52.2269974 -38.54856908
OS 52.22607284 -38.5504182
OS 52.22329916 -38.55411644
OS 52.2177518 -38.56058836
OS 52.21035532 -38.56798484
OS 52.20110972 -38.57630588
OS 52.190015 -38.58555148
OS 52.17707116 -38.59387252
OS 52.16135364 -38.60219356
OS 52.1622782 -38.60219356
OS 52.16412732 -38.60311812
OS 52.166901 -38.60404268
OS 52.17059924 -38.60496724
OS 52.1807694 -38.60866548
OS 52.19371324 -38.61421284
OS 52.2085062 -38.62160932
OS 52.22329916 -38.63085492
OS 52.23716756 -38.6428742
OS 52.2501114 -38.6567426
OS 52.25103596 -38.65859172
OS 52.2547342 -38.66413908
OS 52.26028156 -38.67338468
OS 52.26582892 -38.68540396
OS 52.27137628 -38.70019692
OS 52.27692364 -38.71776356
OS 52.28062188 -38.73810388
OS 52.28154644 -38.76029332
OS 52.28154644 -38.76121788
OS 52.28154644 -38.76399156
OS 52.28154644 -38.76861436
OS 52.28062188 -38.77416172
OS 52.27969732 -38.7815582
OS 52.2778482 -38.78987924
OS 52.27599908 -38.79912484
OS 52.27414996 -38.809295
OS 52.26675348 -38.83148444
OS 52.26120612 -38.84350372
OS 52.25565876 -38.85459844
OS 52.24826228 -38.86661772
OS 52.23994124 -38.878637
OS 52.23069564 -38.89065628
OS 52.21960092 -38.901751
OS 52.21867636 -38.90267556
OS 52.21682724 -38.90452468
OS 52.213129 -38.90729836
OS 52.2085062 -38.9109966
OS 52.20295884 -38.9156194
OS 52.19556236 -38.9202422
OS 52.18724132 -38.92578956
OS 52.17707116 -38.93041236
OS 52.166901 -38.93595972
OS 52.15488172 -38.94150708
OS 52.14286244 -38.94612988
OS 52.12899404 -38.95075268
OS 52.11420108 -38.95445092
OS 52.09848356 -38.9572246
OS 52.08276604 -38.95907372
OS 52.0651994 -38.95999828
OS 52.05687836 -38.95999828
OS 52.051331 -38.95907372
OS 52.04393452 -38.95814916
OS 52.03561348 -38.9572246
OS 52.02636788 -38.95537548
OS 52.01619772 -38.95352636
OS 51.99400828 -38.947979
OS 51.97089428 -38.9387334
OS 51.958875 -38.93318604
OS 51.94778028 -38.92671412
OS 51.93668556 -38.91839308
OS 51.92559084 -38.91007204
OS 51.92466628 -38.90914748
OS 51.92281716 -38.90729836
OS 51.92004348 -38.90452468
OS 51.9172698 -38.90082644
OS 51.912647 -38.89620364
OS 51.9080242 -38.88973172
OS 51.90247684 -38.8832598
OS 51.89692948 -38.87493876
OS 51.89138212 -38.86569316
OS 51.88583476 -38.85644756
OS 51.8756646 -38.83425812
OS 51.86734356 -38.80837044
OS 51.86456988 -38.79450204
OS 51.86272076 -38.77970908
OS 51.94130836 -38.76953892
OS 51.94130836 -38.77046348
OS 51.94223292 -38.7723126
OS 51.94315748 -38.77601084
OS 51.94408204 -38.78063364
OS 51.9450066 -38.786181
OS 51.94685572 -38.79265292
OS 51.95147852 -38.80652132
OS 51.95795044 -38.8231634
OS 51.96627148 -38.83888092
OS 51.97551708 -38.85367388
OS 51.9866118 -38.86661772
OS 51.98846092 -38.86754228
OS 51.99215916 -38.87124052
OS 51.99955564 -38.87586332
OS 52.00880124 -38.88048612
OS 52.01989596 -38.88603348
OS 52.03376436 -38.89065628
OS 52.04948188 -38.89435452
OS 52.06612396 -38.89527908
OS 52.07167132 -38.89527908
OS 52.07536956 -38.89435452
OS 52.08553972 -38.89342996
OS 52.09848356 -38.89065628
OS 52.11327652 -38.88603348
OS 52.12899404 -38.87956156
OS 52.14471156 -38.87031596
OS 52.15950452 -38.85737212
OS 52.16135364 -38.855523
OS 52.16597644 -38.84997564
OS 52.1715238 -38.8416546
OS 52.17892028 -38.83055988
OS 52.18631676 -38.81669148
OS 52.19186412 -38.80097396
OS 52.19648692 -38.78248276
OS 52.19833604 -38.76214244
OS 52.19833604 -38.76121788
OS 52.19833604 -38.75936876
OS 52.19833604 -38.75659508
OS 52.19741148 -38.75289684
OS 52.19648692 -38.74272668
OS 52.19371324 -38.7307074
OS 52.190015 -38.71591444
OS 52.18354308 -38.70112148
OS 52.17429748 -38.68632852
OS 52.1622782 -38.67246012
OS 52.16042908 -38.670611
OS 52.15580628 -38.66691276
OS 52.1484098 -38.6613654
OS 52.13823964 -38.65489348
OS 52.1252958 -38.64842156
OS 52.10957828 -38.6428742
OS 52.09201164 -38.63917596
OS 52.07259588 -38.63732684
OS 52.06427484 -38.63732684
OS 52.05780292 -38.6382514
OS 52.04948188 -38.63917596
OS 52.04023628 -38.64102508
OS 52.02914156 -38.6428742
OS 52.01712228 -38.64564788
OS 52.02636788 -38.57630588
OS 52.03099068 -38.57630588
OS 52.03468892 -38.57723044
OS 52.0467082 -38.57723044
OS 52.05687836 -38.57538132
OS 52.06889764 -38.5735322
OS 52.08276604 -38.57075852
OS 52.09848356 -38.56613572
OS 52.11327652 -38.5596638
OS 52.12899404 -38.55134276
OS 52.1299186 -38.55134276
OS 52.13084316 -38.5504182
OS 52.13546596 -38.54671996
OS 52.14193788 -38.54024804
OS 52.14933436 -38.531927
OS 52.15673084 -38.51990772
OS 52.16320276 -38.50603932
OS 52.16782556 -38.4903218
OS 52.16967468 -38.4810762
OS 52.16967468 -38.47090604
OS 52.16967468 -38.46998148
OS 52.16967468 -38.46905692
OS 52.16967468 -38.46350956
OS 52.16782556 -38.45611308
OS 52.16597644 -38.44594292
OS 52.1622782 -38.4348482
OS 52.1576554 -38.42282892
OS 52.15025892 -38.41080964
OS 52.14008876 -38.39971492
OS 52.1391642 -38.39879036
OS 52.1345414 -38.39509212
OS 52.12806948 -38.39046932
OS 52.11974844 -38.38492196
OS 52.10865372 -38.38029916
OS 52.09570988 -38.37567636
OS 52.08091692 -38.37197812
OS 52.06427484 -38.37105356
OS 52.05687836 -38.37105356
OS 52.04855732 -38.37290268
OS 52.0374626 -38.3747518
OS 52.02544332 -38.37845004
OS 52.01342404 -38.38307284
OS 52.0004802 -38.39046932
OS 51.98846092 -38.39971492
OS 51.98753636 -38.40063948
OS 51.98383812 -38.40526228
OS 51.97829076 -38.4117342
OS 51.97181884 -38.4209798
OS 51.96534692 -38.43299908
OS 51.958875 -38.44779204
OS 51.95332764 -38.46535868
OS 51.9496294 -38.485699
OS 51.8710418 -38.4718306
OS 51.8710418 -38.47090604
OS 51.87196636 -38.46813236
OS 51.87289092 -38.46443412
OS 51.87381548 -38.45888676
OS 51.8756646 -38.45241484
OS 51.87843828 -38.44501836
OS 51.88398564 -38.42745172
OS 51.89323124 -38.4071114
OS 51.90432596 -38.38677108
OS 51.91819436 -38.36735532
OS 51.935761 -38.34978868
OS 51.93668556 -38.34886412
OS 51.93853468 -38.34793956
OS 51.94130836 -38.34609044
OS 51.9450066 -38.34331676
OS 51.9496294 -38.33961852
OS 51.95610132 -38.33592028
OS 51.96257324 -38.33222204
OS 51.97089428 -38.32759924
OS 51.98938548 -38.32020276
OS 52.01065036 -38.31280628
OS 52.03561348 -38.30818348
OS 52.04855732 -38.30633436
OS 52.07167132 -38.30633436
OS 52.08184148 -38.30725892
OE
OB 56.14158444 -38.38492196 H
OS 55.95852156 -38.38492196
OS 55.95852156 -38.61328828
OS 56.13048972 -38.61328828
OS 56.13696164 -38.61236372
OS 56.14343356 -38.61236372
OS 56.15083004 -38.61143916
OS 56.16839668 -38.60959004
OS 56.18781244 -38.6058918
OS 56.2072282 -38.60034444
OS 56.22479484 -38.59294796
OS 56.23311588 -38.58832516
OS 56.2395878 -38.5827778
OS 56.24143692 -38.58092868
OS 56.24513516 -38.57723044
OS 56.25068252 -38.56983396
OS 56.25715444 -38.56058836
OS 56.26362636 -38.54856908
OS 56.26917372 -38.53377612
OS 56.27287196 -38.51713404
OS 56.27472108 -38.49771828
OS 56.27472108 -38.49679372
OS 56.27472108 -38.49586916
OS 56.27472108 -38.49124636
OS 56.27379652 -38.48292532
OS 56.2719474 -38.47367972
OS 56.27009828 -38.46350956
OS 56.26640004 -38.45149028
OS 56.26085268 -38.44039556
OS 56.25438076 -38.42930084
OS 56.2534562 -38.42837628
OS 56.25068252 -38.42467804
OS 56.24605972 -38.42005524
OS 56.24051236 -38.41358332
OS 56.23219132 -38.4071114
OS 56.22294572 -38.40156404
OS 56.21277556 -38.39601668
OS 56.20075628 -38.39139388
OS 56.19983172 -38.39139388
OS 56.19613348 -38.39046932
OS 56.19058612 -38.38954476
OS 56.18318964 -38.38769564
OS 56.17209492 -38.38677108
OS 56.15822652 -38.38584652
OS 56.14158444 -38.38492196
OE
OB 49.87491676 -38.43669732 H
OS 49.67336268 -38.72331092
OS 49.87491676 -38.72331092
OS 49.87491676 -38.43669732
OE
OB 54.06132444 -38.37105356 H
OS 54.05392796 -38.37105356
OS 54.04560692 -38.37290268
OS 54.0345122 -38.3747518
OS 54.02249292 -38.37845004
OS 54.00954908 -38.38307284
OS 53.9975298 -38.39046932
OS 53.98551052 -38.40063948
OS 53.98458596 -38.40156404
OS 53.98088772 -38.40526228
OS 53.97626492 -38.4117342
OS 53.97164212 -38.42005524
OS 53.96609476 -38.4302254
OS 53.96147196 -38.44224468
OS 53.95777372 -38.45518852
OS 53.95684916 -38.46998148
OS 53.95684916 -38.47090604
OS 53.95684916 -38.4718306
OS 53.95777372 -38.47737796
OS 53.95869828 -38.485699
OS 53.9605474 -38.49586916
OS 53.96424564 -38.50788844
OS 53.96886844 -38.51990772
OS 53.97626492 -38.53285156
OS 53.98551052 -38.54394628
OS 53.98643508 -38.54487084
OS 53.99105788 -38.54856908
OS 53.9975298 -38.55319188
OS 54.00585084 -38.55781468
OS 54.01694556 -38.56336204
OS 54.0298894 -38.56798484
OS 54.04468236 -38.57168308
OS 54.06132444 -38.57260764
OS 54.06317356 -38.57260764
OS 54.06872092 -38.57168308
OS 54.07704196 -38.57075852
OS 54.08813668 -38.5689094
OS 54.10015596 -38.56521116
OS 54.11217524 -38.56058836
OS 54.12511908 -38.55319188
OS 54.1362138 -38.54394628
OS 54.13713836 -38.54302172
OS 54.1408366 -38.53839892
OS 54.1454594 -38.53285156
OS 54.15100676 -38.52453052
OS 54.15655412 -38.51436036
OS 54.16117692 -38.50234108
OS 54.16487516 -38.48847268
OS 54.16579972 -38.47367972
OS 54.16579972 -38.47275516
OS 54.16579972 -38.4718306
OS 54.16579972 -38.46628324
OS 54.1639506 -38.4579622
OS 54.16210148 -38.44779204
OS 54.15840324 -38.43669732
OS 54.15285588 -38.42467804
OS 54.1454594 -38.41265876
OS 54.13528924 -38.40063948
OS 54.13436468 -38.39971492
OS 54.12974188 -38.39601668
OS 54.12326996 -38.39139388
OS 54.11494892 -38.38584652
OS 54.1038542 -38.38029916
OS 54.09183492 -38.37567636
OS 54.07704196 -38.37197812
OS 54.06132444 -38.37105356
OE
OB 54.05855076 -38.63640228 H
OS 54.0530034 -38.63640228
OS 54.04930516 -38.63732684
OS 54.039135 -38.6382514
OS 54.02619116 -38.64102508
OS 54.0113982 -38.64564788
OS 53.99660524 -38.6521198
OS 53.98088772 -38.6613654
OS 53.96701932 -38.67338468
OS 53.9651702 -38.6752338
OS 53.96147196 -38.6798566
OS 53.9559246 -38.68817764
OS 53.94945268 -38.6983478
OS 53.9420562 -38.7122162
OS 53.93650884 -38.72793372
OS 53.9328106 -38.74550036
OS 53.93096148 -38.76491612
OS 53.93096148 -38.76676524
OS 53.93096148 -38.77046348
OS 53.93188604 -38.7769354
OS 53.9328106 -38.78525644
OS 53.93465972 -38.7954266
OS 53.9374334 -38.80652132
OS 53.94113164 -38.81761604
OS 53.94575444 -38.82963532
OS 53.946679 -38.83055988
OS 53.94852812 -38.83518268
OS 53.95222636 -38.84073004
OS 53.95777372 -38.84720196
OS 53.96424564 -38.855523
OS 53.97256668 -38.86384404
OS 53.98181228 -38.87124052
OS 53.992907 -38.878637
OS 53.99475612 -38.87956156
OS 53.99845436 -38.88141068
OS 54.00492628 -38.88418436
OS 54.01324732 -38.88695804
OS 54.02341748 -38.88973172
OS 54.03543676 -38.8925054
OS 54.0483806 -38.89435452
OS 54.06132444 -38.89527908
OS 54.0668718 -38.89527908
OS 54.07057004 -38.89435452
OS 54.08166476 -38.89342996
OS 54.0946086 -38.89065628
OS 54.10940156 -38.88603348
OS 54.12511908 -38.88048612
OS 54.13991204 -38.87124052
OS 54.154705 -38.85922124
OS 54.15655412 -38.85737212
OS 54.16025236 -38.85274932
OS 54.16672428 -38.84442828
OS 54.1731962 -38.83425812
OS 54.17966812 -38.82131428
OS 54.18614004 -38.80559676
OS 54.18983828 -38.78710556
OS 54.1916874 -38.7676898
OS 54.1916874 -38.76676524
OS 54.1916874 -38.76491612
OS 54.1916874 -38.76214244
OS 54.19076284 -38.7584442
OS 54.18983828 -38.74827404
OS 54.1870646 -38.73440564
OS 54.1824418 -38.72053724
OS 54.17596988 -38.70481972
OS 54.16672428 -38.6891022
OS 54.15378044 -38.67430924
OS 54.15193132 -38.67246012
OS 54.14730852 -38.66876188
OS 54.13898748 -38.66228996
OS 54.12789276 -38.65489348
OS 54.11402436 -38.64842156
OS 54.09738228 -38.64194964
OS 54.07889108 -38.6382514
OS 54.05855076 -38.63640228
OE
OB 54.80559524 -38.37105356 H
OS 54.80004788 -38.37105356
OS 54.79634964 -38.37197812
OS 54.78617948 -38.37382724
OS 54.7741602 -38.37660092
OS 54.7602918 -38.38214828
OS 54.74549884 -38.39046932
OS 54.73810236 -38.39601668
OS 54.73070588 -38.40156404
OS 54.72423396 -38.40896052
OS 54.71776204 -38.41728156
OS 54.71776204 -38.41820612
OS 54.71591292 -38.42005524
OS 54.7140638 -38.42375348
OS 54.71129012 -38.42837628
OS 54.70851644 -38.43577276
OS 54.7048182 -38.4440938
OS 54.70204452 -38.45426396
OS 54.69834628 -38.46628324
OS 54.69464804 -38.48015164
OS 54.6909498 -38.49586916
OS 54.68725156 -38.5134358
OS 54.68447788 -38.53285156
OS 54.6817042 -38.555041
OS 54.67985508 -38.57907956
OS 54.67893052 -38.60496724
OS 54.67800596 -38.6336286
OS 54.67800596 -38.63547772
OS 54.67800596 -38.64010052
OS 54.67800596 -38.64842156
OS 54.67893052 -38.65951628
OS 54.67893052 -38.67153556
OS 54.67985508 -38.68632852
OS 54.68077964 -38.70204604
OS 54.68262876 -38.71868812
OS 54.68725156 -38.75474596
OS 54.69002524 -38.7723126
OS 54.69372348 -38.78895468
OS 54.69742172 -38.8046722
OS 54.70296908 -38.81946516
OS 54.70851644 -38.832409
OS 54.71498836 -38.84350372
OS 54.71498836 -38.84442828
OS 54.71683748 -38.84535284
OS 54.72146028 -38.85182476
OS 54.72978132 -38.8601458
OS 54.73995148 -38.8693914
OS 54.75381988 -38.878637
OS 54.7695374 -38.88695804
OS 54.78710404 -38.89342996
OS 54.79634964 -38.89435452
OS 54.8065198 -38.89527908
OS 54.81206716 -38.89527908
OS 54.8157654 -38.89435452
OS 54.825011 -38.8925054
OS 54.83795484 -38.88880716
OS 54.85182324 -38.88233524
OS 54.86754076 -38.87308964
OS 54.87493724 -38.86754228
OS 54.88233372 -38.8601458
OS 54.8897302 -38.85274932
OS 54.89712668 -38.84350372
OS 54.89712668 -38.84257916
OS 54.8989758 -38.84073004
OS 54.90082492 -38.83795636
OS 54.90267404 -38.83333356
OS 54.90637228 -38.82686164
OS 54.90914596 -38.8185406
OS 54.9128442 -38.809295
OS 54.91654244 -38.79820028
OS 54.91931612 -38.78433188
OS 54.92301436 -38.76953892
OS 54.9267126 -38.75197228
OS 54.92948628 -38.73348108
OS 54.9313354 -38.71129164
OS 54.93318452 -38.68817764
OS 54.93503364 -38.66228996
OS 54.93503364 -38.6336286
OS 54.93503364 -38.63270404
OS 54.93503364 -38.63177948
OS 54.93503364 -38.62715668
OS 54.93503364 -38.61883564
OS 54.93410908 -38.60774092
OS 54.93410908 -38.59572164
OS 54.93318452 -38.58092868
OS 54.93225996 -38.56521116
OS 54.93041084 -38.54764452
OS 54.92578804 -38.51251124
OS 54.92301436 -38.4949446
OS 54.91931612 -38.47830252
OS 54.91561788 -38.462585
OS 54.91007052 -38.44779204
OS 54.90452316 -38.4348482
OS 54.89805124 -38.42375348
OS 54.89805124 -38.42282892
OS 54.89620212 -38.42190436
OS 54.894353 -38.41913068
OS 54.89157932 -38.41543244
OS 54.88325828 -38.4071114
OS 54.87308812 -38.39694124
OS 54.85921972 -38.38769564
OS 54.8435022 -38.3793746
OS 54.83518116 -38.37567636
OS 54.82593556 -38.37290268
OS 54.8157654 -38.37197812
OS 54.80559524 -38.37105356
OE
OB 51.07499564 -38.37105356 H
OS 51.06944828 -38.37105356
OS 51.06575004 -38.37197812
OS 51.05557988 -38.37382724
OS 51.0435606 -38.37660092
OS 51.0296922 -38.38214828
OS 51.01489924 -38.39046932
OS 51.00750276 -38.39601668
OS 51.00010628 -38.40156404
OS 50.99363436 -38.40896052
OS 50.98716244 -38.41728156
OS 50.98716244 -38.41820612
OS 50.98531332 -38.42005524
OS 50.9834642 -38.42375348
OS 50.98069052 -38.42837628
OS 50.97791684 -38.43577276
OS 50.9742186 -38.4440938
OS 50.97144492 -38.45426396
OS 50.96774668 -38.46628324
OS 50.96404844 -38.48015164
OS 50.9603502 -38.49586916
OS 50.95665196 -38.5134358
OS 50.95387828 -38.53285156
OS 50.9511046 -38.555041
OS 50.94925548 -38.57907956
OS 50.94833092 -38.60496724
OS 50.94740636 -38.6336286
OS 50.94740636 -38.63547772
OS 50.94740636 -38.64010052
OS 50.94740636 -38.64842156
OS 50.94833092 -38.65951628
OS 50.94833092 -38.67153556
OS 50.94925548 -38.68632852
OS 50.95018004 -38.70204604
OS 50.95202916 -38.71868812
OS 50.95665196 -38.75474596
OS 50.95942564 -38.7723126
OS 50.96312388 -38.78895468
OS 50.96682212 -38.8046722
OS 50.97236948 -38.81946516
OS 50.97791684 -38.832409
OS 50.98438876 -38.84350372
OS 50.98438876 -38.84442828
OS 50.98623788 -38.84535284
OS 50.99086068 -38.85182476
OS 50.99918172 -38.8601458
OS 51.00935188 -38.8693914
OS 51.02322028 -38.878637
OS 51.0389378 -38.88695804
OS 51.05650444 -38.89342996
OS 51.06575004 -38.89435452
OS 51.0759202 -38.89527908
OS 51.08146756 -38.89527908
OS 51.0851658 -38.89435452
OS 51.0944114 -38.8925054
OS 51.10735524 -38.88880716
OS 51.12122364 -38.88233524
OS 51.13694116 -38.87308964
OS 51.14433764 -38.86754228
OS 51.15173412 -38.8601458
OS 51.1591306 -38.85274932
OS 51.16652708 -38.84350372
OS 51.16652708 -38.84257916
OS 51.1683762 -38.84073004
OS 51.17022532 -38.83795636
OS 51.17207444 -38.83333356
OS 51.17577268 -38.82686164
OS 51.17854636 -38.8185406
OS 51.1822446 -38.809295
OS 51.18594284 -38.79820028
OS 51.18871652 -38.78433188
OS 51.19241476 -38.76953892
OS 51.196113 -38.75197228
OS 51.19888668 -38.73348108
OS 51.2007358 -38.71129164
OS 51.20258492 -38.68817764
OS 51.20443404 -38.66228996
OS 51.20443404 -38.6336286
OS 51.20443404 -38.63270404
OS 51.20443404 -38.63177948
OS 51.20443404 -38.62715668
OS 51.20443404 -38.61883564
OS 51.20350948 -38.60774092
OS 51.20350948 -38.59572164
OS 51.20258492 -38.58092868
OS 51.20166036 -38.56521116
OS 51.19981124 -38.54764452
OS 51.19518844 -38.51251124
OS 51.19241476 -38.4949446
OS 51.18871652 -38.47830252
OS 51.18501828 -38.462585
OS 51.17947092 -38.44779204
OS 51.17392356 -38.4348482
OS 51.16745164 -38.42375348
OS 51.16745164 -38.42282892
OS 51.16560252 -38.42190436
OS 51.1637534 -38.41913068
OS 51.16097972 -38.41543244
OS 51.15265868 -38.4071114
OS 51.14248852 -38.39694124
OS 51.12862012 -38.38769564
OS 51.1129026 -38.3793746
OS 51.10458156 -38.37567636
OS 51.09533596 -38.37290268
OS 51.0851658 -38.37197812
OS 51.07499564 -38.37105356
OE
SE

### steps/pcb/layers/comp_+_bot/features


### steps/pcb/layers/comp_+_top/features


### steps/pcb/layers/dielectric_1/features
UNITS=MM
#Layer_Color=255
#
#Feature symbol names
#

#
#Feature attribute names
#

#
#Layer features
#

### steps/pcb/layers/dielectric_2/features
UNITS=MM
#Layer_Color=255
#
#Feature symbol names
#

#
#Feature attribute names
#

#
#Layer features
#

### steps/pcb/layers/dielectric_3/features
UNITS=MM
#Layer_Color=255
#
#Feature symbol names
#

#
#Feature attribute names
#

#
#Layer features
#

### steps/pcb/layers/drill_non-plated_bottom-top/features
UNITS=MM
#Layer_Color=9474304
#
#Feature symbol names
#
$0 r2999.99908

#
#Feature attribute names
#
@0 .geometry
@1 .drill

#
#Feature attribute text strings
#
&0 Pad_Simple_X5299.9996Y5299.9996H2999.9991C4015.9991

#
#Layer features
#
P 20.24000016 42.13999954 0 P 0 0 ;0=0,1=1
P 20.43999976 -1.26000002 0 P 0 0 ;0=0,1=1

### steps/pcb/layers/drill_plated_bottom-top/features
UNITS=MM
#Layer_Color=9474304
#
#Feature symbol names
#
$0 r299.9994
$1 r762
$2 r961.9996
$3 r1090.00036
$4 r1200.00014
$5 r3700.00022

#
#Feature attribute names
#
@0 .geometry
@1 .drill

#
#Feature attribute text strings
#
&0 VIA_RoundD599.9988H299.9994C1315.9994
&1 Pad_Simple_X0.0000Y0.0000H3700.0002C4716.0002
&2 Pad_Simple_X1524.0000Y1524.0000H762.0000C1778.0000
&3 Pad_Simple_X1562.0009Y1562.0009H961.9996C1977.9996
&4 Pad_Simple_X2090.0009Y2090.0009H1090.0004C2106.0004
&5 Pad_Simple_X1799.9989Y1799.9989H1200.0001C2216.0001

#
#Layer features
#
P 0 0 3 P 0 0 ;0=4,1=0
P 0 40.64 3 P 0 0 ;0=4,1=0
P 2.0779994 43.3299997 3 P 0 0 ;0=4,1=0
P 4.39999882 2.00000108 5 P 0 0 ;0=1,1=0
P 4.39999882 38.599999 5 P 0 0 ;0=1,1=0
P 4.8300005 7.63999996 4 P 0 0 ;0=5,1=0
P 4.8300005 7.63999996 1 P 0 0 ;0=2,1=0
P 4.8300005 12.71999996 4 P 0 0 ;0=5,1=0
P 4.8300005 12.71999996 1 P 0 0 ;0=2,1=0
P 4.8300005 17.79999996 1 P 0 0 ;0=2,1=0
P 4.8300005 17.79999996 4 P 0 0 ;0=5,1=0
P 4.8300005 33.03999996 1 P 0 0 ;0=2,1=0
P 4.8300005 33.03999996 4 P 0 0 ;0=5,1=0
P 5.1259994 43.3299997 3 P 0 0 ;0=4,1=0
P 8.1739994 43.3299997 3 P 0 0 ;0=4,1=0
P 11.2219994 43.3299997 3 P 0 0 ;0=4,1=0
P 14.2699994 43.3299997 3 P 0 0 ;0=4,1=0
P 35.50000012 -1.00000054 5 P 0 0 ;0=1,1=0
P 36.20000126 40.10000108 5 P 0 0 ;0=1,1=0
P 37.8500005 7.63999996 2 P 0 0 ;0=3,1=0
P 37.8500005 7.63999996 4 P 0 0 ;0=5,1=0
P 37.8500005 12.71999996 2 P 0 0 ;0=3,1=0
P 37.8500005 12.71999996 4 P 0 0 ;0=5,1=0
P 37.8500005 17.79999996 4 P 0 0 ;0=5,1=0
P 37.8500005 17.79999996 2 P 0 0 ;0=3,1=0
P 37.8500005 22.87999996 2 P 0 0 ;0=3,1=0
P 37.8500005 22.87999996 4 P 0 0 ;0=5,1=0
P 37.8500005 33.03999996 2 P 0 0 ;0=3,1=0
P 37.8500005 33.03999996 4 P 0 0 ;0=5,1=0
P 40.64 0 3 P 0 0 ;0=4,1=0
P 40.64 40.64 3 P 0 0 ;0=4,1=0
P 40.67999992 20.33999996 3 P 0 0 ;0=4,1=0
P -2.99999908 16.00000102 0 P 0 0 ;0=0,1=2
P -2.99999908 17.99999956 0 P 0 0 ;0=0,1=2
P -2.99999908 20.00000064 0 P 0 0 ;0=0,1=2
P -2.99999908 21.99999918 0 P 0 0 ;0=0,1=2
P -2.99999908 24.00000026 0 P 0 0 ;0=0,1=2
P -2.99999908 25.9999988 0 P 0 0 ;0=0,1=2
P -2.99999908 27.99999988 0 P 0 0 ;0=0,1=2
P -2.99999908 30.00000096 0 P 0 0 ;0=0,1=2
P -2.99999908 31.9999995 0 P 0 0 ;0=0,1=2
P -2.99999908 34.00000058 0 P 0 0 ;0=0,1=2
P -2.99999908 35.99999912 0 P 0 0 ;0=0,1=2
P -2.99999908 38.0000002 0 P 0 0 ;0=0,1=2
P -2.99999908 39.99999874 0 P 0 0 ;0=0,1=2
P 0.50000154 -3.99999962 0 P 0 0 ;0=0,1=2
P 2.50000008 -3.99999962 0 P 0 0 ;0=0,1=2
P 4.50000116 -3.99999962 0 P 0 0 ;0=0,1=2
P 6.4999997 -3.99999962 0 P 0 0 ;0=0,1=2
P 8.50000078 -3.99999962 0 P 0 0 ;0=0,1=2
P 10.49999932 -3.99999962 0 P 0 0 ;0=0,1=2
P 12.5000004 -3.99999962 0 P 0 0 ;0=0,1=2
P 12.74500118 40.26499948 0 P 0 0 ;0=0,1=2
P 12.74500118 41.21500012 0 P 0 0 ;0=0,1=2
P 12.74500118 44.63999962 0 P 0 0 ;0=0,1=2
P 12.75500116 42.16500076 0 P 0 0 ;0=0,1=2
P 12.98999942 18.0150008 0 P 0 0 ;0=0,1=2
P 14.50000148 -3.99999962 0 P 0 0 ;0=0,1=2
P 15.88470534 21.56499878 0 P 0 0 ;0=0,1=2
P 16.30970576 23.03999964 0 P 0 0 ;0=0,1=2
P 16.50000002 -3.99999962 0 P 0 0 ;0=0,1=2
P 17.57500168 13.89000016 0 P 0 0 ;0=0,1=2
P 17.915001 15.69625258 0 P 0 0 ;0=0,1=2
P 18.8149992 15.10000028 0 P 0 0 ;0=0,1=2
P 18.8149992 15.98270108 0 P 0 0 ;0=0,1=2
P 18.8149992 16.85250122 0 P 0 0 ;0=0,1=2
P 19.01500134 7.39000046 0 P 0 0 ;0=0,1=2
P 19.01500134 8.5900006 0 P 0 0 ;0=0,1=2
P 19.01500134 9.7899982 0 P 0 0 ;0=0,1=2
P 19.01500134 11.09000068 0 P 0 0 ;0=0,1=2
P 19.01500134 12.39000062 0 P 0 0 ;0=0,1=2
P 21.11499968 6.76500044 0 P 0 0 ;0=0,1=2
P 21.11499968 7.78999966 0 P 0 0 ;0=0,1=2
P 21.11499968 8.9899998 0 P 0 0 ;0=0,1=2
P 21.11499968 10.28999974 0 P 0 0 ;0=0,1=2
P 21.11499968 11.38590052 0 P 0 0 ;0=0,1=2
P 22.05919388 12.29000082 0 P 0 0 ;0=0,1=2
P 22.45970616 20.01499934 0 P 0 0 ;0=0,1=2
P 23.29999912 38.90000094 0 P 0 0 ;0=0,1=2
P 23.33999904 44.0138312 0 P 0 0 ;0=0,1=2
P 23.4097068 20.04000056 0 P 0 0 ;0=0,1=2
P 24.35970744 20.04000056 0 P 0 0 ;0=0,1=2
P 24.49999926 -3.50000062 0 P 0 0 ;0=0,1=2
P 25.7999992 38.90000094 0 P 0 0 ;0=0,1=2
P 26.50000034 -3.50000062 0 P 0 0 ;0=0,1=2
P 28.50000142 -3.50000062 0 P 0 0 ;0=0,1=2
P 30.49999996 -3.50000062 0 P 0 0 ;0=0,1=2
P 32.50000104 -3.50000062 0 P 0 0 ;0=0,1=2
P 32.80000044 38.90000094 0 P 0 0 ;0=0,1=2
P 35.30000052 44.0000009 0 P 0 0 ;0=0,1=2
P 38.4999992 -3.50000062 0 P 0 0 ;0=0,1=2
P 39.60000208 38.91499964 0 P 0 0 ;0=0,1=2
P 40.50000028 -3.50000062 0 P 0 0 ;0=0,1=2
P 40.67999992 42.76499956 0 P 0 0 ;0=0,1=2
P 42.2249981 38.91499964 0 P 0 0 ;0=0,1=2
P 44.4999999 0.499999 0 P 0 0 ;0=0,1=2
P 44.4999999 2.50000008 0 P 0 0 ;0=0,1=2
P 44.4999999 4.49999862 0 P 0 0 ;0=0,1=2
P 44.4999999 6.4999997 0 P 0 0 ;0=0,1=2
P 44.4999999 8.49999824 0 P 0 0 ;0=0,1=2
P 44.4999999 10.49999932 0 P 0 0 ;0=0,1=2
P 44.4999999 12.49999786 0 P 0 0 ;0=0,1=2
P 44.4999999 14.49999894 0 P 0 0 ;0=0,1=2
P 44.4999999 16.50000002 0 P 0 0 ;0=0,1=2
P 44.4999999 18.49999856 0 P 0 0 ;0=0,1=2
P 44.4999999 20.49999964 0 P 0 0 ;0=0,1=2
P 44.4999999 22.49999818 0 P 0 0 ;0=0,1=2
P 44.4999999 24.49999926 0 P 0 0 ;0=0,1=2
P 44.4999999 26.4999978 0 P 0 0 ;0=0,1=2
P 44.4999999 28.49999888 0 P 0 0 ;0=0,1=2
P 44.4999999 30.49999996 0 P 0 0 ;0=0,1=2
P 44.4999999 32.4999985 0 P 0 0 ;0=0,1=2
P 44.4999999 34.49999958 0 P 0 0 ;0=0,1=2
P 44.4999999 36.49999812 0 P 0 0 ;0=0,1=2
P 44.4999999 38.4999992 0 P 0 0 ;0=0,1=2
P 44.4999999 40.49999774 0 P 0 0 ;0=0,1=2

### steps/pcb/layers/l01-top_layer/features
UNITS=MM
#Layer_Physical_Order=1
#Layer_Color=255
#
#Feature symbol names
#
$0 r1000.00054
$1 r99.9998
$2 r2090.0009
$3 r5299.99956
$4 r1524
$5 r1562.00094
$6 r1799.99894
$7 r599.9988

#
#Feature attribute names
#
@0 .geometry
@1 .pad_usage
@2 .smd
@3 .nomenclature
@4 .string
@5 .string_angle

#
#Feature attribute text strings
#
&0 SMD_RoundX1000.0005Y1000.0005
&1 Pad_Simple_X2090.0009Y2090.0009H1090.0004C2106.0004
&2 Pad_Simple_X5299.9996Y5299.9996H2999.9991C4015.9991
&3 Pad_Simple_X1524.0000Y1524.0000H762.0000C1778.0000
&4 Pad_Simple_X1562.0009Y1562.0009H961.9996C1977.9996
&5 Pad_Simple_X1799.9989Y1799.9989H1200.0001C2216.0001
&6 VIA_RoundD599.9988H299.9994C1315.9994

#
#Layer features
#
L -9.5600012 -24.45999934 40.4400004 -24.45999934 1 P 0
L -9.5600012 -35.9599992 -9.5600012 -24.45999934 1 P 0
L -9.5600012 -35.9599992 28.439999 -35.9599992 1 P 0
L -9.5600012 -39.45999982 -9.5600012 -35.9599992 1 P 0
L -9.5600012 -39.45999982 28.439999 -39.45999982 1 P 0
L -9.5600012 -42.96000044 -9.5600012 -39.45999982 1 P 0
L -9.5600012 -42.96000044 28.439999 -42.96000044 1 P 0
L -10.0600002 -23.96000034 62.93999858 -23.96000034 1 P 0
L -10.0600002 -43.45999944 -10.0600002 -23.96000034 1 P 0
L -10.0600002 -43.45999944 62.93999858 -43.45999944 1 P 0
L 28.439999 -35.96000174 45.44000056 -35.9599992 1 P 0
L 28.439999 -39.45999982 28.439999 -35.9599992 1 P 0
L 28.439999 -39.46000236 45.44000056 -39.45999982 1 P 0
L 28.439999 -42.96000044 28.439999 -39.45999982 1 P 0
L 28.439999 -42.96000298 45.44000056 -42.96000044 1 P 0
L 40.4400004 -24.45999934 62.43999958 -24.45999934 1 P 0
L 40.4400004 -35.9599992 40.4400004 -24.45999934 1 P 0
L 40.67999992 20.33999996 44.63999962 20.33999996 0 P 0
L 45.44000056 -35.9599992 62.43999958 -35.9599992 1 P 0
L 45.44000056 -39.45999982 62.43999958 -39.45999982 1 P 0
L 45.44000056 -42.96000044 45.44000056 -35.9599992 1 P 0
L 45.44000056 -42.96000044 62.43999958 -42.96000044 1 P 0
L 62.43999958 -35.9599992 62.43999958 -24.45999934 1 P 0
L 62.43999958 -42.96000044 62.43999958 -35.9599992 1 P 0
L 62.93999858 -43.45999944 62.93999858 -23.96000034 1 P 0
P -2.20000068 -2.69999968 0 P 0 0 ;0=0,1=0,2
P -2.37499906 43.52500058 0 P 0 0 ;0=0,1=0,2
P 0 0 2 P 0 0 ;0=1,1=0
P 0 40.64 2 P 0 0 ;0=1,1=0
P 2.0779994 43.3299997 2 P 0 0 ;0=1,1=0
P 4.8300005 7.63999996 6 P 0 0 ;0=5,1=0
P 4.8300005 7.63999996 4 P 0 0 ;0=3,1=0
P 4.8300005 12.71999996 6 P 0 0 ;0=5,1=0
P 4.8300005 12.71999996 4 P 0 0 ;0=3,1=0
P 4.8300005 17.79999996 6 P 0 0 ;0=5,1=0
P 4.8300005 17.79999996 4 P 0 0 ;0=3,1=0
P 4.8300005 33.03999996 6 P 0 0 ;0=5,1=0
P 4.8300005 33.03999996 4 P 0 0 ;0=3,1=0
P 5.1259994 43.3299997 2 P 0 0 ;0=1,1=0
P 8.1739994 43.3299997 2 P 0 0 ;0=1,1=0
P 11.2219994 43.3299997 2 P 0 0 ;0=1,1=0
P 14.2699994 43.3299997 2 P 0 0 ;0=1,1=0
P 20.24000016 42.13999954 3 P 0 0 ;0=2,1=0
P 20.43999976 -1.26000002 3 P 0 0 ;0=2,1=0
P 37.8500005 7.63999996 6 P 0 0 ;0=5,1=0
P 37.8500005 7.63999996 5 P 0 0 ;0=4,1=0
P 37.8500005 12.71999996 6 P 0 0 ;0=5,1=0
P 37.8500005 12.71999996 5 P 0 0 ;0=4,1=0
P 37.8500005 17.79999996 6 P 0 0 ;0=5,1=0
P 37.8500005 17.79999996 5 P 0 0 ;0=4,1=0
P 37.8500005 22.87999996 5 P 0 0 ;0=4,1=0
P 37.8500005 22.87999996 6 P 0 0 ;0=5,1=0
P 37.8500005 33.03999996 5 P 0 0 ;0=4,1=0
P 37.8500005 33.03999996 6 P 0 0 ;0=5,1=0
P 40.64 0 2 P 0 0 ;0=1,1=0
P 40.64 40.64 2 P 0 0 ;0=1,1=0
P 40.67999992 20.33999996 2 P 0 0 ;0=1,1=0
P 43.12499884 43.52500058 0 P 0 0 ;0=0,1=0,2
S P 0
OB 23.88064312 44.95700432 I
OS 23.8844455 44.95573686
OS 23.919942 44.9544694
OS 23.92374438 44.95320194
OS 23.92881676 44.95193448
OS 23.93515152 44.94939702
OS 23.9402239 44.94812956
OS 23.95797088 44.94559464
OS 23.97128048 44.94242726
OS 23.9820577 44.93672242
OS 23.988395 44.9341875
OS 23.99663222 44.93101758
OS 24.0010696 44.9278502
OS 24.00740944 44.92404528
OS 24.01374674 44.92151036
OS 24.0219865 44.91834044
OS 24.02388896 44.91644052
OS 24.02642388 44.91517306
OS 24.04036848 44.90883322
OS 24.04924324 44.90376338
OS 24.055578 44.899961
OS 24.06191784 44.89742354
OS 24.06698768 44.89615608
OS 24.07395998 44.89045124
OS 24.07839736 44.8860164
OS 24.08093228 44.88474894
OS 24.08663712 44.87904664
OS 24.08790458 44.87650918
OS 24.08980704 44.87460926
OS 24.09234196 44.8733418
OS 24.09931426 44.8663695
OS 24.10058172 44.86383204
OS 24.10248418 44.86193212
OS 24.1050191 44.86066466
OS 24.11198886 44.85369236
OS 24.11325632 44.8511549
OS 24.11515878 44.84925498
OS 24.1176937 44.84798752
OS 24.12339854 44.84228268
OS 24.124666 44.83974776
OS 24.12783592 44.83657784
OS 24.13037084 44.83531038
OS 24.13480822 44.830873
OS 24.13607568 44.82833808
OS 24.14368044 44.82073332
OS 24.14621536 44.81439602
OS 24.14938528 44.80615626
OS 24.1525552 44.80171888
OS 24.1588925 44.79537904
OS 24.16269742 44.78904174
OS 24.16903472 44.7827019
OS 24.17346956 44.77065976
OS 24.17537202 44.76622238
OS 24.18170932 44.7560827
OS 24.18297678 44.74721048
OS 24.18424424 44.7421381
OS 24.1855117 44.73453334
OS 24.19438646 44.71551636
OS 24.19628892 44.70347676
OS 24.20135876 44.69079962
OS 24.20262622 44.68572978
OS 24.20389368 44.67812248
OS 24.20516114 44.65023328
OS 24.2064286 44.61600678
OS 24.20769606 44.53994902
OS 24.20833106 41.48175092
OS 24.20833106 41.48048346
OS 24.20769606 38.81145654
OS 24.20833106 38.80701916
OS 24.2070636 38.80321678
OS 24.20769606 38.78229988
OS 24.2070636 38.76265298
OS 24.20833106 38.75884806
OS 24.2070636 38.75377822
OS 24.20579614 38.74490346
OS 24.2070636 38.73983362
OS 24.20769606 38.73286132
OS 24.2064286 38.72652402
OS 24.20516114 38.72145164
OS 24.20389368 38.68849514
OS 24.20135876 38.6821553
OS 24.192484 38.67328308
OS 24.1861467 38.67074562
OS 24.15065274 38.66947816
OS 24.14685036 38.6682107
OS 24.14178052 38.66694324
OS 24.12973584 38.6688457
OS 24.12656592 38.66947816
OS 24.12276354 38.6682107
OS 24.11389132 38.66694324
OS 24.10121672 38.6682107
OS 24.08853958 38.66694324
OS 24.0625503 38.66757824
OS 24.05304308 38.66694324
OS 24.04924324 38.6682107
OS 24.04227094 38.6688457
OS 24.03466364 38.66757824
OS 24.02769134 38.66694324
OS 24.02388896 38.6682107
OS 24.01374674 38.67074562
OS 23.9820577 38.67201562
OS 23.9750854 38.67771792
OS 23.97001302 38.6827903
OS 23.9674781 38.6891276
OS 23.96621064 38.72462156
OS 23.96494318 38.72842394
OS 23.96367572 38.7372987
OS 23.96494318 38.74110108
OS 23.96621064 38.74870838
OS 23.96494318 38.75251076
OS 23.96367572 38.76138552
OS 23.96494318 38.76645282
OS 23.96430818 38.78863718
OS 23.96494318 38.80321678
OS 23.96367572 38.80701916
OS 23.96430818 38.82413368
OS 23.96304072 44.54755378
OS 23.96240826 44.55199116
OS 23.96367572 44.55579354
OS 23.96240826 44.57734544
OS 23.9611408 44.58114782
OS 23.9598708 44.62171162
OS 23.95733588 44.62805146
OS 23.9535335 44.63692368
OS 23.95226604 44.64199606
OS 23.9471962 44.65086828
OS 23.94212382 44.65593812
OS 23.94085636 44.65847304
OS 23.93515152 44.66544534
OS 23.9326166 44.6667128
OS 23.9269143 44.67241764
OS 23.92564684 44.67495256
OS 23.92247692 44.67812248
OS 23.919942 44.67938994
OS 23.9129697 44.68509478
OS 23.90979978 44.6882647
OS 23.90346248 44.69079962
OS 23.89649018 44.69270208
OS 23.88064312 44.70094184
OS 23.87557328 44.7022093
OS 23.8654336 44.70347676
OS 23.86163122 44.70474168
OS 23.85275646 44.70854406
OS 23.84768662 44.70981152
OS 23.83120456 44.71108152
OS 23.80141798 44.71298144
OS 23.74944196 44.7142489
OS 23.25759636 44.71551636
OS 23.2493566 44.71615136
OS 23.24555422 44.7148839
OS 23.22273486 44.71615136
OS 23.21893248 44.7148839
OS 23.20372296 44.71615136
OS 23.19991804 44.71741882
OS 23.16949392 44.71868628
OS 23.16315662 44.72248866
OS 23.15618432 44.7281935
OS 23.15491686 44.73073096
OS 23.1523794 44.73706826
OS 23.15174694 44.75798516
OS 23.1523794 44.76495492
OS 23.15111194 44.7687573
OS 23.14921456 44.77699706
OS 23.14857956 44.78650682
OS 23.14984448 44.7903092
OS 23.14921456 44.81376102
OS 23.14984448 44.8245357
OS 23.14857956 44.82833808
OS 23.14921456 44.8593972
OS 23.14857956 44.87017188
OS 23.14984448 44.87397426
OS 23.14921456 44.89615608
OS 23.15047948 44.90122846
OS 23.15174694 44.90756576
OS 23.1523794 44.91453806
OS 23.15111194 44.91707298
OS 23.1523794 44.9208779
OS 23.15364686 44.9411598
OS 23.15808424 44.9468621
OS 23.16061916 44.94812956
OS 23.16315662 44.95193448
OS 23.16949392 44.9544694
OS 23.20435542 44.95636932
OS 23.2094278 44.95763678
OS 23.2214674 44.95827178
OS 23.22526978 44.95700432
OS 23.24808914 44.95827178
OS 23.25189152 44.95700432
OS 23.26837104 44.95827178
OS 23.88064312 44.95700432
OE
SE
S P 0
OB 24.62982374 40.45559092 I
OS 24.65961286 40.453691
OS 24.67229 40.45242354
OS 24.6786273 40.45115608
OS 24.68496714 40.44861862
OS 24.6932069 40.44545124
OS 24.70207912 40.44418632
OS 24.7071515 40.44291632
OS 24.71538872 40.43974894
OS 24.72299348 40.43467656
OS 24.73693808 40.42960672
OS 24.74137546 40.4264368
OS 24.7477153 40.4200995
OS 24.75025022 40.41883204
OS 24.7686322 40.40045006
OS 24.76989712 40.39791514
OS 24.7743345 40.39474522
OS 24.7813068 40.38777292
OS 24.78257426 40.385238
OS 24.78701164 40.38207062
OS 24.80539362 40.36368864
OS 24.80666108 40.36115372
OS 24.81299838 40.35481388
OS 24.81426584 40.35227896
OS 24.81680076 40.34594166
OS 24.81997068 40.3377019
OS 24.82567552 40.32819214
OS 24.82821044 40.318055
OS 24.83011036 40.30727778
OS 24.83264528 40.30094048
OS 24.8358152 40.29270072
OS 24.83708266 40.28382596
OS 24.83835012 40.26734644
OS 24.83961758 40.25467184
OS 24.84088504 40.22298026
OS 24.83961758 40.21917534
OS 24.83835012 40.18368392
OS 24.83708266 40.179879
OS 24.8358152 40.16720186
OS 24.83074282 40.15579472
OS 24.82821044 40.1456525
OS 24.82694298 40.13678028
OS 24.82187314 40.12790552
OS 24.81680076 40.11649838
OS 24.81363338 40.10825862
OS 24.80539362 40.10001632
OS 24.80412362 40.0974814
OS 24.79968878 40.09177656
OS 24.79715132 40.0905091
OS 24.77877188 40.07212966
OS 24.77750188 40.06959474
OS 24.77560196 40.06769482
OS 24.77306704 40.06642482
OS 24.76736474 40.06071998
OS 24.76609728 40.05818506
OS 24.76292736 40.05501768
OS 24.76039244 40.05374768
OS 24.75342014 40.04804538
OS 24.75025022 40.04487546
OS 24.74391038 40.04234054
OS 24.73567062 40.03917062
OS 24.73123324 40.0360007
OS 24.71475372 40.02839594
OS 24.6932069 40.01825626
OS 24.68179722 40.0169888
OS 24.67799484 40.01572134
OS 24.66912008 40.01191642
OS 24.66024532 40.0093815
OS 24.6513731 40.00811404
OS 24.62665382 40.00621158
OS 24.60573692 40.00557912
OS 24.60193454 40.00684658
OS 24.57341288 40.00874904
OS 24.56707558 40.0100165
OS 24.55693336 40.01381888
OS 24.54615868 40.0169888
OS 24.5410863 40.01825626
OS 24.53157908 40.02015618
OS 24.51573456 40.02839594
OS 24.5074948 40.03156332
OS 24.50305742 40.03346578
OS 24.49989004 40.0366357
OS 24.49925504 40.03853562
OS 24.49672012 40.03980308
OS 24.4941852 40.04234054
OS 24.49165028 40.043608
OS 24.48594544 40.04931284
OS 24.48467798 40.05184776
OS 24.48277552 40.05374768
OS 24.4802406 40.05501768
OS 24.47453576 40.06071998
OS 24.4732683 40.06325744
OS 24.47009838 40.06642482
OS 24.467566 40.06769482
OS 24.46312862 40.07212966
OS 24.46186116 40.07466712
OS 24.45869124 40.0778345
OS 24.45615632 40.07910196
OS 24.45045148 40.08480426
OS 24.44918402 40.08734172
OS 24.4460141 40.0905091
OS 24.44347918 40.09177656
OS 24.4390418 40.09621394
OS 24.43777434 40.09874886
OS 24.43016958 40.10635616
OS 24.42889958 40.10889108
OS 24.42636466 40.11523092
OS 24.42319728 40.12347068
OS 24.42129482 40.1253706
OS 24.42002736 40.12790552
OS 24.41749244 40.13044298
OS 24.41305506 40.14248512
OS 24.41052014 40.14882242
OS 24.40481784 40.15832964
OS 24.40228038 40.16720186
OS 24.40038046 40.17924654
OS 24.39340816 40.19636106
OS 24.38960578 40.2343874
OS 24.39087324 40.23819232
OS 24.39277316 40.26164414
OS 24.39404062 40.26671144
OS 24.39784554 40.27685366
OS 24.40101292 40.28509342
OS 24.40291538 40.2971381
OS 24.40418284 40.30220794
OS 24.41368752 40.32058992
OS 24.41685744 40.32882714
OS 24.42129482 40.33579944
OS 24.42763212 40.34974404
OS 24.43397196 40.36115372
OS 24.4390418 40.3725634
OS 24.44411418 40.38143562
OS 24.44918402 40.38650546
OS 24.45045148 40.38904038
OS 24.4536214 40.39347776
OS 24.45615632 40.39474522
OS 24.45869124 40.39728014
OS 24.46122616 40.3985476
OS 24.46629854 40.4061549
OS 24.46883346 40.40742236
OS 24.47580322 40.4131272
OS 24.4802406 40.41756458
OS 24.49608512 40.42326942
OS 24.49925504 40.4264368
OS 24.50178996 40.42770426
OS 24.50242496 40.42833926
OS 24.50305742 40.42897172
OS 24.5151021 40.4334091
OS 24.5214394 40.43594402
OS 24.5290467 40.4410164
OS 24.53601646 40.44291632
OS 24.54489122 40.44418632
OS 24.55693336 40.44861862
OS 24.56770804 40.45178854
OS 24.57278042 40.453056
OS 24.60003208 40.45495846
OS 24.61524414 40.45622592
OS 24.62602136 40.45686092
OS 24.62982374 40.45559092
OE
SE
S P 0
OB 24.63235866 41.19716678 I
OS 24.6583454 41.19526432
OS 24.6646827 41.19399686
OS 24.67482492 41.19019448
OS 24.6855996 41.18702456
OS 24.69066944 41.1857571
OS 24.69827674 41.18448964
OS 24.7071515 41.17941726
OS 24.71855864 41.17434742
OS 24.72489594 41.1718125
OS 24.72743086 41.17054504
OS 24.73630562 41.16420774
OS 24.74137546 41.16294028
OS 24.74961522 41.15977036
OS 24.75658752 41.15279806
OS 24.75912498 41.1515306
OS 24.7616599 41.14899568
OS 24.76419482 41.14772822
OS 24.7686322 41.14329084
OS 24.76989712 41.14075592
OS 24.77306704 41.137586
OS 24.77560196 41.13631854
OS 24.78003934 41.13188116
OS 24.7813068 41.12934624
OS 24.78574418 41.12490886
OS 24.7882791 41.1236414
OS 24.79144648 41.12047402
OS 24.79271648 41.11793656
OS 24.7952514 41.11540164
OS 24.79651886 41.11286672
OS 24.8015887 41.10779688
OS 24.80412362 41.10145958
OS 24.80539362 41.09638974
OS 24.81109592 41.08941744
OS 24.8155333 41.08498006
OS 24.82060568 41.0761053
OS 24.82567552 41.07103546
OS 24.82821044 41.0621607
OS 24.82947536 41.05075102
OS 24.83454774 41.03934388
OS 24.8358152 41.03427404
OS 24.83708266 41.02539928
OS 24.83835012 41.01272214
OS 24.83961758 40.98863786
OS 24.84088504 40.96835596
OS 24.83961758 40.95567882
OS 24.83771512 40.9258897
OS 24.83644766 40.91448256
OS 24.8351802 40.90941018
OS 24.83264528 40.90307288
OS 24.82947536 40.89483312
OS 24.82821044 40.88976074
OS 24.82821044 40.88849328
OS 24.82694298 40.87835106
OS 24.82123814 40.87137876
OS 24.81173092 40.8580717
OS 24.80792854 40.85426932
OS 24.80666108 40.85173186
OS 24.8015887 40.83905726
OS 24.79588386 40.83208242
OS 24.79271648 40.82891504
OS 24.79144648 40.82638012
OS 24.78574418 40.82067528
OS 24.78320672 40.81940782
OS 24.78003934 40.8162379
OS 24.77877188 40.81370298
OS 24.77306704 40.80799814
OS 24.77052958 40.80673068
OS 24.76736474 40.8035633
OS 24.76609728 40.80102838
OS 24.7616599 40.796591
OS 24.75912498 40.79532354
OS 24.75151768 40.78771624
OS 24.74518038 40.78518132
OS 24.73693808 40.7820114
OS 24.72933332 40.7756741
OS 24.7261634 40.77250418
OS 24.71728864 40.76743434
OS 24.7122188 40.76236196
OS 24.69700928 40.75982704
OS 24.68496714 40.75538966
OS 24.6792623 40.75348974
OS 24.67418992 40.75222228
OS 24.6653177 40.75095228
OS 24.64123342 40.74968482
OS 24.63235866 40.74841736
OS 24.58545756 40.74968482
OS 24.58165264 40.75095228
OS 24.56517312 40.75222228
OS 24.55629836 40.75602466
OS 24.54996106 40.75855958
OS 24.54489122 40.75982704
OS 24.534114 40.7617295
OS 24.52777924 40.76426442
OS 24.51827202 40.76996926
OS 24.50622734 40.77440664
OS 24.50178996 40.77757402
OS 24.49672012 40.7826464
OS 24.4941852 40.78391386
OS 24.4872129 40.7896187
OS 24.48277552 40.79405608
OS 24.466931 40.79976092
OS 24.46439608 40.80229584
OS 24.46312862 40.80482822
OS 24.45552132 40.80989806
OS 24.45045148 40.81497044
OS 24.44918402 40.81750536
OS 24.44157672 40.82511012
OS 24.4390418 40.83144996
OS 24.43714188 40.83842226
OS 24.43523942 40.84032472
OS 24.43397196 40.84285964
OS 24.42763212 40.84919694
OS 24.42636466 40.85173186
OS 24.42065982 40.85870416
OS 24.41622498 40.86314154
OS 24.41052014 40.87898606
OS 24.40481784 40.88849328
OS 24.40355038 40.89736804
OS 24.40228038 40.90243788
OS 24.40038046 40.91828494
OS 24.399113 40.92335478
OS 24.39594308 40.93032454
OS 24.39340816 40.9391993
OS 24.3921407 40.94807406
OS 24.39087324 40.9607512
OS 24.3921407 40.98990532
OS 24.39340816 40.9937077
OS 24.39467562 41.001315
OS 24.39974546 41.01272214
OS 24.40101292 41.01779452
OS 24.40228038 41.03047166
OS 24.40418284 41.0425138
OS 24.40735276 41.05075102
OS 24.41242006 41.0621607
OS 24.41368752 41.06723308
OS 24.41495498 41.0761053
OS 24.41622498 41.08117768
OS 24.42192728 41.08814998
OS 24.42382974 41.0900499
OS 24.4250972 41.09258482
OS 24.43080204 41.09955712
OS 24.43460442 41.10336204
OS 24.43650688 41.1039945
OS 24.43777434 41.10652688
OS 24.4460141 41.11476918
OS 24.44854902 41.11603664
OS 24.45488886 41.1236414
OS 24.45869124 41.12744632
OS 24.4605937 41.12807878
OS 24.46186116 41.1306137
OS 24.47009838 41.13885346
OS 24.4726333 41.14012092
OS 24.47580322 41.1445583
OS 24.48150806 41.15026314
OS 24.48404298 41.1515306
OS 24.49165028 41.1591379
OS 24.49798758 41.16167282
OS 24.50622734 41.1648402
OS 24.51066472 41.16801012
OS 24.51573456 41.17307996
OS 24.51827202 41.17434742
OS 24.52524432 41.18005226
OS 24.534749 41.1857571
OS 24.54742614 41.18702456
OS 24.55122852 41.18829202
OS 24.56010328 41.1920944
OS 24.5689755 41.19463186
OS 24.57785026 41.19589932
OS 24.60129954 41.19779924
OS 24.62855628 41.19843424
OS 24.63235866 41.19716678
OE
SE
S P 0
OB 24.6386985 41.9387401 I
OS 24.65200556 41.93683764
OS 24.6570754 41.93557018
OS 24.6640477 41.93240026
OS 24.67292246 41.92986534
OS 24.68750206 41.92796542
OS 24.69510682 41.92669796
OS 24.7001792 41.92542796
OS 24.71348626 41.91845566
OS 24.72553094 41.91402082
OS 24.73250324 41.90958344
OS 24.73503816 41.90704852
OS 24.75088268 41.90134368
OS 24.75912498 41.89310392
OS 24.7616599 41.89183392
OS 24.76482728 41.889934
OS 24.76609728 41.88739908
OS 24.79271648 41.86077988
OS 24.79398394 41.85824242
OS 24.8015887 41.85063766
OS 24.80602608 41.83859552
OS 24.81236592 41.8284533
OS 24.8155333 41.82148354
OS 24.81870322 41.81324378
OS 24.82504052 41.80310156
OS 24.82947536 41.79232688
OS 24.83264528 41.78408458
OS 24.8358152 41.77711228
OS 24.83708266 41.76824006
OS 24.83961758 41.73401356
OS 24.84088504 41.70739182
OS 24.83961758 41.70359198
OS 24.83771512 41.66619556
OS 24.8351802 41.6509835
OS 24.83074282 41.64020882
OS 24.82821044 41.6300666
OS 24.82694298 41.62119438
OS 24.82187314 41.61231962
OS 24.81680076 41.60090994
OS 24.81363338 41.59267018
OS 24.80539362 41.58443042
OS 24.80412362 41.58189804
OS 24.79841878 41.57492574
OS 24.7952514 41.57175582
OS 24.79144648 41.56288106
OS 24.79017902 41.55781122
OS 24.78447418 41.55083892
OS 24.78193926 41.54957146
OS 24.77877188 41.54640154
OS 24.77750188 41.54386662
OS 24.77560196 41.54196416
OS 24.76926212 41.53942924
OS 24.7610249 41.53625932
OS 24.75658752 41.53309194
OS 24.75025022 41.5267521
OS 24.7477153 41.52548464
OS 24.740743 41.51978234
OS 24.73757308 41.51661242
OS 24.72172602 41.51091012
OS 24.7198261 41.50900766
OS 24.70841896 41.50393782
OS 24.70334658 41.50266782
OS 24.6925719 41.5007679
OS 24.6862346 41.49823298
OS 24.67799484 41.49506306
OS 24.6653177 41.4937956
OS 24.66024532 41.49252814
OS 24.62538636 41.49062568
OS 24.60700438 41.48999322
OS 24.603202 41.49126068
OS 24.5689755 41.49252814
OS 24.56517312 41.4937956
OS 24.55249598 41.49506306
OS 24.53855138 41.50140036
OS 24.53031162 41.50457028
OS 24.52334186 41.50900766
OS 24.50939726 41.51534496
OS 24.49798758 41.5216848
OS 24.4865779 41.5267521
OS 24.47770568 41.53182448
OS 24.4726333 41.53689432
OS 24.47009838 41.53816178
OS 24.46312862 41.54386662
OS 24.46186116 41.54640154
OS 24.45615632 41.55210638
OS 24.4536214 41.55337384
OS 24.45171894 41.5552763
OS 24.45045148 41.55781122
OS 24.44474664 41.56351606
OS 24.44221172 41.56478352
OS 24.4390418 41.56795344
OS 24.43777434 41.57048836
OS 24.4320695 41.57746066
OS 24.42889958 41.58063058
OS 24.42636466 41.58696534
OS 24.4250972 41.59203772
OS 24.42002736 41.60090994
OS 24.41495498 41.61231962
OS 24.41242006 41.62753168
OS 24.40355038 41.64654612
OS 24.40228038 41.65541834
OS 24.39974546 41.66556056
OS 24.39467562 41.67697024
OS 24.39340816 41.68204008
OS 24.3921407 41.69091484
OS 24.38960578 41.7188015
OS 24.39087324 41.72260388
OS 24.39277316 41.74605824
OS 24.39404062 41.75239554
OS 24.398478 41.76317022
OS 24.40101292 41.76950752
OS 24.40228038 41.77838228
OS 24.40418284 41.78662204
OS 24.41368752 41.80500148
OS 24.41685744 41.81324378
OS 24.42129482 41.82021608
OS 24.42636466 41.83162322
OS 24.43143704 41.84049544
OS 24.43523942 41.84429782
OS 24.43650688 41.84683528
OS 24.4390418 41.8493702
OS 24.44030926 41.85190512
OS 24.44221172 41.85380758
OS 24.44474664 41.85507504
OS 24.45171894 41.86204734
OS 24.4529864 41.86458226
OS 24.45488886 41.86648472
OS 24.45742378 41.86775218
OS 24.46439608 41.87472448
OS 24.46566354 41.8772594
OS 24.467566 41.87915932
OS 24.47009838 41.88042932
OS 24.47580322 41.88613162
OS 24.47707068 41.88866654
OS 24.4802406 41.89183392
OS 24.48277552 41.89310392
OS 24.48974782 41.89880876
OS 24.49291774 41.90197614
OS 24.49925504 41.90451106
OS 24.50432742 41.90578106
OS 24.51827202 41.91465328
OS 24.53031162 41.91909066
OS 24.53601646 41.92226058
OS 24.53728392 41.92226058
OS 24.5486936 41.92733042
OS 24.56137074 41.92859788
OS 24.57278042 41.92986534
OS 24.58165264 41.93367026
OS 24.58799248 41.93620518
OS 24.59305978 41.93747264
OS 24.60763938 41.93937256
OS 24.63489358 41.94000756
OS 24.6386985 41.9387401
OE
SE
S P 0
OB 24.66785262 42.6689012 I
OS 24.671655 42.66763374
OS 24.68940198 42.66636628
OS 24.70334658 42.66003152
OS 24.70968388 42.65749406
OS 24.72109356 42.65115676
OS 24.73250324 42.64608692
OS 24.74391038 42.63974708
OS 24.75532006 42.63467724
OS 24.76672974 42.6283374
OS 24.76926212 42.62453502
OS 24.77179958 42.62326756
OS 24.77877188 42.61756272
OS 24.78447418 42.60932296
OS 24.78701164 42.6080555
OS 24.78891156 42.60615304
OS 24.79144648 42.59981828
OS 24.79334894 42.59284598
OS 24.79651886 42.5884086
OS 24.80285616 42.58206876
OS 24.80412362 42.57953384
OS 24.80982846 42.57256154
OS 24.81299838 42.56939162
OS 24.81426584 42.5668567
OS 24.81680076 42.5605194
OS 24.81997068 42.55227964
OS 24.82567552 42.54277242
OS 24.82821044 42.53263274
OS 24.83011036 42.52185552
OS 24.8358152 42.50727846
OS 24.83835012 42.48953148
OS 24.84025258 42.45340252
OS 24.84088504 42.44009292
OS 24.83961758 42.43629054
OS 24.83835012 42.40079658
OS 24.83708266 42.3969942
OS 24.8358152 42.3830496
OS 24.82947536 42.369105
OS 24.82631052 42.36086524
OS 24.82187314 42.35389294
OS 24.8155333 42.33994834
OS 24.809196 42.3285412
OS 24.80412362 42.31713152
OS 24.79905378 42.30825676
OS 24.79398394 42.30318946
OS 24.79271648 42.300652
OS 24.78701164 42.2936797
OS 24.78447418 42.29241224
OS 24.78003934 42.28797486
OS 24.77877188 42.28543994
OS 24.7743345 42.28100256
OS 24.7679972 42.27720018
OS 24.7616599 42.27086288
OS 24.75658752 42.26959542
OS 24.74834776 42.2664255
OS 24.740108 42.25818574
OS 24.73123324 42.25311336
OS 24.7261634 42.24804352
OS 24.7198261 42.2455086
OS 24.71538872 42.2448736
OS 24.71475372 42.24424368
OS 24.70334658 42.24297622
OS 24.68686706 42.23536892
OS 24.67672484 42.232834
OS 24.65897786 42.23156654
OS 24.65264056 42.22903162
OS 24.6444008 42.2258617
OS 24.6374285 42.22395924
OS 24.63235866 42.22269178
OS 24.6234839 42.22142432
OS 24.61841406 42.22015686
OS 24.60193454 42.22142432
OS 24.59813216 42.22269178
OS 24.58988986 42.22459424
OS 24.5835551 42.22712916
OS 24.5689755 42.23156654
OS 24.55629836 42.232834
OS 24.54615868 42.23410146
OS 24.52460932 42.24424368
OS 24.51636956 42.24741106
OS 24.5144671 42.24931098
OS 24.51193218 42.25057844
OS 24.50432742 42.25565082
OS 24.49735512 42.25755074
OS 24.49291774 42.2594532
OS 24.48594544 42.26515804
OS 24.48277552 42.26832796
OS 24.4802406 42.26959542
OS 24.47453576 42.27530026
OS 24.4732683 42.27783518
OS 24.47009838 42.28100256
OS 24.467566 42.28227256
OS 24.46312862 42.2867074
OS 24.46186116 42.28924486
OS 24.45869124 42.29241224
OS 24.45615632 42.2936797
OS 24.45045148 42.29938454
OS 24.44918402 42.30191946
OS 24.4460141 42.30508684
OS 24.44347918 42.3063543
OS 24.4390418 42.31079168
OS 24.43777434 42.3133266
OS 24.43016958 42.3209339
OS 24.42889958 42.32346882
OS 24.42636466 42.32980866
OS 24.4250972 42.3348785
OS 24.41622498 42.34755564
OS 24.41432252 42.35452794
OS 24.4117876 42.36086524
OS 24.4060853 42.37163992
OS 24.40355038 42.38051214
OS 24.399113 42.40776888
OS 24.39721054 42.41220626
OS 24.39467562 42.41854356
OS 24.39340816 42.42361594
OS 24.3921407 42.43248562
OS 24.39087324 42.44516276
OS 24.3921407 42.47431942
OS 24.39340816 42.47812434
OS 24.39467562 42.48699402
OS 24.40101292 42.50093862
OS 24.40228038 42.51742068
OS 24.4054503 42.53073028
OS 24.41242006 42.54404242
OS 24.41558998 42.55227964
OS 24.4181249 42.55861694
OS 24.42129482 42.56178686
OS 24.42256228 42.56432178
OS 24.42636466 42.57319654
OS 24.42953458 42.5814363
OS 24.43777434 42.58967606
OS 24.4390418 42.59221098
OS 24.45742378 42.61059042
OS 24.4599587 42.61185788
OS 24.46186116 42.61376034
OS 24.46312862 42.61629526
OS 24.48277552 42.6359447
OS 24.48531044 42.63721216
OS 24.49165028 42.64354946
OS 24.49798758 42.64608692
OS 24.50622734 42.6492543
OS 24.51953948 42.6562266
OS 24.52967916 42.65876406
OS 24.53918638 42.66066398
OS 24.54996106 42.66509882
OS 24.5550309 42.66636628
OS 24.56770804 42.66763374
OS 24.58418756 42.6689012
OS 24.61207676 42.6701712
OS 24.66785262 42.6689012
OE
SE
S P 0
OB 31.31665568 44.95700432 I
OS 31.3204606 44.95573686
OS 31.3546871 44.9544694
OS 31.35848948 44.95320194
OS 31.36482932 44.95193448
OS 31.37116408 44.94939702
OS 31.37623646 44.94812956
OS 31.39398344 44.94559464
OS 31.40729304 44.94242726
OS 31.4231401 44.93545496
OS 31.43201232 44.9341875
OS 31.43708216 44.93292004
OS 31.44532192 44.92975012
OS 31.44722438 44.9278502
OS 31.4497593 44.92658274
OS 31.45863406 44.92277782
OS 31.46687382 44.91961044
OS 31.47384612 44.91517306
OS 31.48778818 44.90883322
OS 31.49412548 44.90503084
OS 31.49919786 44.899961
OS 31.50173278 44.89869354
OS 31.51124 44.89172124
OS 31.511875 44.88981878
OS 31.51440992 44.88855132
OS 31.52708706 44.88348148
OS 31.52962198 44.88221402
OS 31.53722928 44.87460926
OS 31.5397642 44.8733418
OS 31.54420158 44.87017188
OS 31.54546904 44.86763696
OS 31.54800142 44.86510204
OS 31.54863642 44.86319958
OS 31.55117134 44.86193212
OS 31.60757966 44.80552126
OS 31.60884966 44.80298634
OS 31.61645442 44.79537904
OS 31.61898934 44.78904174
OS 31.6202568 44.7839719
OS 31.62913156 44.77002476
OS 31.63039902 44.76495492
OS 31.63927378 44.74847794
OS 31.64307616 44.73960318
OS 31.64561108 44.73326588
OS 31.65068346 44.72439112
OS 31.65448584 44.71551636
OS 31.6563883 44.70347676
OS 31.66019068 44.69333454
OS 31.6633606 44.68636224
OS 31.66462806 44.6812924
OS 31.66589552 44.67241764
OS 31.66716298 44.6673478
OS 31.6690629 44.64516344
OS 31.67033036 44.6400936
OS 31.6760352 44.62171162
OS 31.67793512 44.6058671
OS 31.67920258 44.58305028
OS 31.67983758 44.57988036
OS 31.67857012 44.57607798
OS 31.67730266 44.54692132
OS 31.6760352 44.54311894
OS 31.6747652 44.53424418
OS 31.67223028 44.52790434
OS 31.66969536 44.51903466
OS 31.6684279 44.51396228
OS 31.66652798 44.49177792
OS 31.66526052 44.48417316
OS 31.66399306 44.47783332
OS 31.66145814 44.47149602
OS 31.65828822 44.46452372
OS 31.6557533 44.4556515
OS 31.65385084 44.44487682
OS 31.65131592 44.43853698
OS 31.649416 44.43663706
OS 31.64307616 44.42269246
OS 31.63990624 44.41445016
OS 31.63546886 44.40874786
OS 31.6342014 44.4062104
OS 31.63166648 44.39987564
OS 31.62849656 44.39163588
OS 31.62152426 44.38466358
OS 31.6202568 44.38212866
OS 31.61138458 44.37071898
OS 31.60884966 44.36818406
OS 31.60441482 44.35613938
OS 31.6012449 44.351702
OS 31.59617506 44.34663216
OS 31.59490506 44.34409724
OS 31.59237014 44.34156232
OS 31.59173768 44.3396624
OS 31.58920276 44.33839494
OS 31.5258196 44.27501178
OS 31.52328468 44.27374432
OS 31.51694484 44.26740448
OS 31.51060754 44.26486956
OS 31.50236778 44.26170218
OS 31.49666294 44.25599734
OS 31.49412548 44.25472988
OS 31.49159056 44.25219242
OS 31.4852558 44.24839004
OS 31.47891596 44.24205274
OS 31.46307144 44.2363479
OS 31.46116898 44.23444544
OS 31.45863406 44.23317798
OS 31.4497593 44.2293756
OS 31.44088708 44.22810814
OS 31.4358147 44.22684068
OS 31.42757748 44.2236733
OS 31.41933772 44.21923592
OS 31.41046296 44.216701
OS 31.40159074 44.21543354
OS 31.38954606 44.21099616
OS 31.38384122 44.2090937
OS 31.374969 44.20782624
OS 31.3267979 44.20529132
OS 31.22665586 44.20402386
OS 30.5471957 44.2027564
OS 30.54339332 44.20148894
OS 30.50155952 44.20021894
OS 30.49775714 44.19895148
OS 30.48761492 44.19768402
OS 30.4787427 44.19388164
OS 30.46860048 44.19134672
OS 30.46099572 44.19007926
OS 30.4445162 44.18247196
OS 30.43564398 44.17993704
OS 30.42676922 44.17866958
OS 30.41852946 44.17549966
OS 30.40902224 44.16979482
OS 30.3969801 44.16535744
OS 30.3900078 44.16092514
OS 30.3760632 44.1545853
OS 30.36465352 44.148248
OS 30.35324384 44.14317562
OS 30.34437416 44.13810578
OS 30.34183924 44.13557086
OS 30.33930178 44.1343034
OS 30.3354994 44.13049848
OS 30.33296448 44.12923102
OS 30.3285271 44.12479364
OS 30.32725964 44.12225872
OS 30.32408972 44.1190888
OS 30.3215548 44.11782134
OS 30.31584996 44.1121165
OS 30.3145825 44.10958158
OS 30.31268004 44.10768166
OS 30.31014512 44.1064142
OS 30.30444028 44.1007119
OS 30.30317282 44.09817444
OS 30.3000029 44.09500706
OS 30.29746798 44.0937396
OS 30.29176314 44.08803476
OS 30.29049568 44.0854973
OS 30.2873283 44.08232992
OS 30.28479338 44.08106246
OS 30.280356 44.07662508
OS 30.27908854 44.07409016
OS 30.27528616 44.07028524
OS 30.2740187 44.06775032
OS 30.27021632 44.06394794
OS 30.26577894 44.05190326
OS 30.26134156 44.04493096
OS 30.25500426 44.0309889
OS 30.2524668 44.0246516
OS 30.2461295 44.01577684
OS 30.24169212 44.0037347
OS 30.23535482 43.99359248
OS 30.2321849 43.98662018
OS 30.22901498 43.97838296
OS 30.2264826 43.97204312
OS 30.22458014 43.9701432
OS 30.22331268 43.96760828
OS 30.22077776 43.96126844
OS 30.2195103 43.95239622
OS 30.21824284 43.94732384
OS 30.21507292 43.93908408
OS 30.211903 43.9283094
OS 30.21063554 43.9156348
OS 30.20936808 43.89915528
OS 30.20746816 43.87570092
OS 30.20683316 43.86239386
OS 30.20810062 43.85858894
OS 30.21000308 43.82879982
OS 30.21127054 43.81485522
OS 30.212538 43.80724792
OS 30.21634038 43.79710824
OS 30.21824284 43.79013594
OS 30.2195103 43.7850661
OS 30.22141276 43.77555888
OS 30.22394768 43.76921904
OS 30.23091744 43.75337452
OS 30.23345236 43.738165
OS 30.2385222 43.72929024
OS 30.24232712 43.72041548
OS 30.24486204 43.71407818
OS 30.24866442 43.70773834
OS 30.25500426 43.70140104
OS 30.25880664 43.6950612
OS 30.26514394 43.6887239
OS 30.2676814 43.6823866
OS 30.27084878 43.67414684
OS 30.2740187 43.66970946
OS 30.27908854 43.66463962
OS 30.280356 43.6621047
OS 30.29873544 43.64372272
OS 30.3012729 43.64245526
OS 30.30317282 43.6405528
OS 30.30444028 43.63801788
OS 30.31141258 43.63104558
OS 30.31395004 43.62977812
OS 30.31584996 43.62787566
OS 30.31711742 43.62534074
OS 30.32408972 43.61837098
OS 30.32662464 43.61710352
OS 30.3285271 43.61520106
OS 30.32979456 43.61266614
OS 30.3354994 43.6069613
OS 30.33803432 43.60569384
OS 30.34437416 43.59935654
OS 30.34690908 43.59808908
OS 30.35324384 43.59555162
OS 30.35831622 43.59428416
OS 30.36528852 43.58857932
OS 30.3697259 43.58414448
OS 30.37226082 43.58287448
OS 30.37923312 43.57717218
OS 30.38240304 43.57400226
OS 30.38874034 43.57146734
OS 30.40078248 43.56702996
OS 30.40268494 43.5651275
OS 30.40521986 43.56386258
OS 30.41409208 43.5600602
OS 30.42296684 43.55879274
OS 30.42993914 43.55689028
OS 30.43627644 43.55435536
OS 30.4521235 43.54738306
OS 30.46416564 43.5454806
OS 30.48254508 43.53977576
OS 30.49522222 43.5385083
OS 30.53008118 43.53660838
OS 30.58078974 43.53533838
OS 34.74500544 43.53407092
OS 34.794444 43.53280346
OS 34.81726336 43.531536
OS 34.84198264 43.52963608
OS 34.8483174 43.52709862
OS 34.85719216 43.5245637
OS 34.86606692 43.52329624
OS 34.88571636 43.52139378
OS 34.89332112 43.52012632
OS 34.8983935 43.51885886
OS 34.9047308 43.51632394
OS 34.91170056 43.51315402
OS 34.92184278 43.5106191
OS 34.93135 43.50871664
OS 34.93768984 43.50618172
OS 34.93958976 43.5042818
OS 34.95353436 43.4979445
OS 34.96177412 43.49477458
OS 34.96367658 43.49287466
OS 34.9662115 43.4916072
OS 34.98015356 43.48526736
OS 34.99156324 43.47893006
OS 34.99409816 43.47639514
OS 35.00107046 43.47449268
OS 35.0074103 43.47195776
OS 35.01184768 43.46878784
OS 35.01691752 43.463718
OS 35.01945244 43.46245054
OS 35.02198736 43.45991308
OS 35.02452482 43.45864562
OS 35.02768966 43.45420824
OS 35.0333945 43.44850594
OS 35.03592942 43.44723594
OS 35.04226926 43.44090118
OS 35.04480418 43.43963372
OS 35.05114402 43.4370988
OS 35.05621386 43.4358288
OS 35.06318616 43.4301265
OS 35.06762354 43.42568912
OS 35.07015846 43.42442166
OS 35.0758633 43.41871682
OS 35.07713076 43.4161819
OS 35.08030068 43.41174452
OS 35.0828356 43.41047706
OS 35.08600552 43.40477222
OS 35.09043782 43.39272754
OS 35.09741266 43.38575524
OS 35.09868012 43.38322286
OS 35.10691988 43.3749831
OS 35.1094548 43.37371564
OS 35.11452464 43.36610834
OS 35.12149694 43.35913604
OS 35.12720178 43.34329152
OS 35.1303717 43.3401216
OS 35.13163916 43.33758668
OS 35.136709 43.326177
OS 35.13924646 43.3198397
OS 35.14558376 43.31096748
OS 35.14684868 43.3058951
OS 35.1493836 43.2995578
OS 35.15825836 43.28054082
OS 35.16079328 43.26279638
OS 35.16269574 43.2520217
OS 35.16713312 43.2374421
OS 35.16840058 43.22856988
OS 35.1703005 43.20511552
OS 35.1715705 43.17215902
OS 35.17220296 43.13349514
OS 35.1709355 43.12969276
OS 35.16966804 43.0865915
OS 35.16840058 43.08279166
OS 35.16713312 43.06250722
OS 35.1645982 43.05616992
OS 35.16206074 43.04729516
OS 35.15952582 43.02954818
OS 35.15762336 43.0200435
OS 35.15508844 43.01370366
OS 35.15318852 43.0118012
OS 35.14811614 42.99912406
OS 35.14494876 42.9908843
OS 35.14304884 42.98898438
OS 35.14178138 42.98644946
OS 35.13924646 42.983912
OS 35.13290662 42.96743248
OS 35.12530186 42.95983026
OS 35.12403186 42.9572928
OS 35.11832956 42.9503205
OS 35.1164271 42.94842058
OS 35.11515964 42.94588312
OS 35.11135726 42.9370109
OS 35.10628488 42.92813614
OS 35.09994758 42.92179884
OS 35.09868012 42.91926392
OS 35.07903322 42.89961702
OS 35.07713076 42.89898202
OS 35.0758633 42.8964471
OS 35.06762354 42.88820734
OS 35.06572108 42.88757234
OS 35.06445362 42.88503742
OS 35.04353672 42.86412052
OS 35.0410018 42.86285306
OS 35.03783188 42.85841568
OS 35.03212704 42.85271084
OS 35.02959212 42.85144338
OS 35.02198736 42.84383862
OS 35.01565006 42.8413037
OS 35.0074103 42.83813378
OS 34.999803 42.83306394
OS 34.9928307 42.82989402
OS 34.98459094 42.82672664
OS 34.97761864 42.82228926
OS 34.9662115 42.81721688
OS 34.9522669 42.80961212
OS 34.9383223 42.80327228
OS 34.91930786 42.79440006
OS 34.90156088 42.79186514
OS 34.8907862 42.78996268
OS 34.8762066 42.7855253
OS 34.87113676 42.78425784
OS 34.83754526 42.78235792
OS 34.78557178 42.78109046
OS 32.1349243 42.779823
OS 32.1342893 42.77919054
OS 32.13048692 42.780458
OS 32.11020248 42.77919054
OS 32.04682186 42.77792054
OS 32.04301694 42.77665308
OS 32.01386282 42.77538562
OS 32.01006044 42.77411816
OS 32.0037206 42.77158324
OS 31.99484838 42.76904832
OS 31.98217124 42.76778086
OS 31.97709886 42.7665134
OS 31.96696172 42.76524594
OS 31.95047966 42.75763864
OS 31.94540982 42.75637118
OS 31.93463514 42.75446872
OS 31.92639538 42.75130134
OS 31.91245078 42.7449615
OS 31.90738094 42.74369404
OS 31.89723872 42.74242658
OS 31.88583158 42.73608674
OS 31.87695682 42.73228436
OS 31.86871706 42.72911444
OS 31.86110976 42.72277968
OS 31.85920984 42.72087722
OS 31.85667492 42.71960976
OS 31.85413746 42.71707484
OS 31.85223754 42.71643984
OS 31.85097008 42.71390492
OS 31.84273032 42.70566516
OS 31.8401954 42.7043977
OS 31.8338581 42.6980604
OS 31.82751826 42.69552294
OS 31.8192785 42.69235556
OS 31.81484112 42.68918564
OS 31.80850382 42.6828458
OS 31.8059689 42.68157834
OS 31.7989966 42.67460604
OS 31.79772914 42.67207112
OS 31.79329176 42.6689012
OS 31.78885438 42.66446636
OS 31.78758692 42.66193144
OS 31.78378708 42.65812906
OS 31.78315208 42.6562266
OS 31.78124962 42.65559414
OS 31.77998216 42.65305922
OS 31.77744724 42.64671938
OS 31.77427732 42.63847962
OS 31.76603756 42.63023986
OS 31.7647701 42.62770494
OS 31.75906526 42.62073264
OS 31.75589534 42.61756272
OS 31.75336042 42.61122542
OS 31.75019304 42.60298566
OS 31.74512066 42.5953809
OS 31.73941582 42.58206876
OS 31.73434598 42.57319654
OS 31.72674122 42.55671702
OS 31.72040392 42.54277242
OS 31.71913646 42.53770258
OS 31.717234 42.52185552
OS 31.71469908 42.49650378
OS 31.71343162 42.48889648
OS 31.71216416 42.48255918
OS 31.7108967 42.47748934
OS 31.70899424 42.47051704
OS 31.70772678 42.4654472
OS 31.70519186 42.45023514
OS 31.7039244 42.437558
OS 31.70519186 42.42868324
OS 31.70709178 42.41664364
OS 31.70835924 42.4103038
OS 31.70962924 42.40523396
OS 31.71279662 42.39445674
OS 31.71406408 42.3893869
OS 31.71533154 42.38051214
OS 31.71660154 42.367835
OS 31.71850146 42.3557954
OS 31.71976892 42.35072556
OS 31.72357384 42.34058334
OS 31.72674122 42.33234358
OS 31.72800614 42.3272712
OS 31.7299086 42.31649652
OS 31.73244352 42.31015922
OS 31.73434598 42.30825676
OS 31.73814836 42.29938454
OS 31.74131828 42.29114478
OS 31.74322074 42.2867074
OS 31.74955804 42.2803701
OS 31.7508255 42.27783518
OS 31.75336042 42.27530026
OS 31.75716534 42.26896042
OS 31.75906526 42.26705796
OS 31.76096772 42.2664255
OS 31.76223518 42.26389058
OS 31.7647701 42.25755074
OS 31.76794002 42.24931098
OS 31.77491232 42.24234122
OS 31.77617978 42.2398063
OS 31.7913893 42.22459424
OS 31.7920243 42.22269178
OS 31.79455922 42.22142432
OS 31.81547612 42.20050742
OS 31.81610858 42.19860496
OS 31.81864604 42.1973375
OS 31.8338581 42.18212798
OS 31.83639302 42.18086052
OS 31.84273032 42.17452322
OS 31.85667492 42.16945084
OS 31.86427968 42.16184608
OS 31.8668146 42.16057608
OS 31.87822428 42.15170386
OS 31.88963396 42.14663148
OS 31.90104364 42.14029418
OS 31.90357856 42.13775926
OS 31.90864586 42.1364918
OS 31.9149857 42.13395688
OS 31.93653506 42.1238172
OS 31.94794474 42.12254974
OS 31.95428458 42.12001228
OS 31.96696172 42.1162099
OS 31.97202902 42.11494244
OS 32.01259536 42.11367498
OS 32.01639774 42.11240752
OS 32.058864 42.11177252
OS 32.06203392 42.11240752
OS 32.0658363 42.11114006
OS 33.016571 42.1098726
OS 33.02037338 42.10860514
OS 33.05840226 42.10733768
OS 33.06220464 42.10606768
OS 33.06917694 42.10416776
OS 33.0774167 42.10099784
OS 33.09516622 42.09846292
OS 33.1053059 42.09719546
OS 33.1116432 42.09466054
OS 33.1255878 42.0883207
OS 33.13446256 42.08705324
OS 33.14270232 42.08515078
OS 33.14903962 42.08261586
OS 33.15094208 42.08071594
OS 33.153477 42.07944594
OS 33.16488668 42.0743761
OS 33.1731239 42.07120618
OS 33.17502636 42.06930626
OS 33.17756128 42.0680388
OS 33.18389858 42.06423642
OS 33.19214088 42.06106904
OS 33.19847818 42.05853158
OS 33.2016481 42.0553642
OS 33.20418302 42.05409674
OS 33.21305778 42.05029182
OS 33.21939508 42.0477569
OS 33.22636738 42.04205206
OS 33.22953476 42.03888214
OS 33.23206968 42.03761468
OS 33.23777452 42.03190984
OS 33.23904198 42.02937492
OS 33.2422119 42.026205
OS 33.24474682 42.02493754
OS 33.25171912 42.0192327
OS 33.25488904 42.01606532
OS 33.26883364 42.01099294
OS 33.28467816 41.99515096
OS 33.28658062 41.98817866
OS 33.289113 41.98183882
OS 33.2960853 41.97486652
OS 33.29735276 41.9723316
OS 33.3030576 41.9653593
OS 33.30559252 41.96409184
OS 33.31256482 41.95711954
OS 33.31319982 41.95521708
OS 33.31573474 41.95394962
OS 33.32270704 41.94697732
OS 33.3239745 41.9444424
OS 33.3315818 41.93683764
OS 33.33411672 41.93050034
OS 33.33728664 41.92226058
OS 33.34045656 41.9178232
OS 33.34679386 41.91148336
OS 33.3505937 41.90514606
OS 33.35629854 41.89817376
OS 33.358201 41.89246892
OS 33.35946846 41.8835967
OS 33.36073592 41.87599194
OS 33.36707576 41.86711718
OS 33.37024314 41.85887742
OS 33.37404806 41.8487352
OS 33.37658298 41.8423979
OS 33.3784829 41.83669306
OS 33.37975036 41.83162322
OS 33.38165282 41.79676172
OS 33.38355528 41.72133642
OS 33.38228782 41.71753404
OS 33.38165282 41.68394254
OS 33.38228782 41.6719004
OS 33.38102036 41.66809548
OS 33.3791179 41.63323652
OS 33.37785044 41.62689922
OS 33.37531552 41.62055938
OS 33.3721456 41.6097847
OS 33.37087814 41.60471486
OS 33.36961068 41.5958401
OS 33.3645383 41.58696534
OS 33.35946846 41.5755582
OS 33.35186116 41.5616136
OS 33.34679386 41.55020646
OS 33.33918656 41.53625932
OS 33.33538418 41.5273871
OS 33.32904688 41.51597996
OS 33.32270704 41.50964012
OS 33.32143958 41.5071052
OS 33.31446728 41.5001329
OS 33.31193236 41.49886544
OS 33.30876244 41.49442806
OS 33.30432506 41.48999322
OS 33.30179014 41.48872322
OS 33.29862022 41.48555584
OS 33.29735276 41.48302092
OS 33.29164792 41.47731608
OS 33.289113 41.47604862
OS 33.28721308 41.47414616
OS 33.28594562 41.47161124
OS 33.27897332 41.46463894
OS 33.2764384 41.46337148
OS 33.27453848 41.46147156
OS 33.27327102 41.45893664
OS 33.25488904 41.44055466
OS 33.25235158 41.4392872
OS 33.25045166 41.43738474
OS 33.2491842 41.43484982
OS 33.24347936 41.42914498
OS 33.24094444 41.42787752
OS 33.23333714 41.42027022
OS 33.22700238 41.4177353
OS 33.21876008 41.41456538
OS 33.21432524 41.411398
OS 33.21305778 41.40886308
OS 33.21052032 41.40759308
OS 33.19911318 41.3987234
OS 33.19530826 41.39491848
OS 33.17946374 41.38921364
OS 33.17756128 41.38731372
OS 33.16615414 41.38224134
OS 33.1610843 41.38097388
OS 33.14903962 41.37907396
OS 33.13065764 41.36956674
OS 33.1179805 41.36449436
OS 33.1065759 41.35942452
OS 33.09072884 41.35752206
OS 33.07678424 41.3562546
OS 33.06537456 41.35498714
OS 33.04889504 41.35245222
OS 33.0438252 41.35118476
OS 33.03812036 41.3492823
OS 33.02544576 41.34801484
OS 32.97727466 41.34547992
OS 32.93100348 41.34484492
OS 32.92910102 41.34547992
OS 32.92530118 41.344215
OS 31.374334 41.34358
OS 31.37116408 41.344215
OS 31.36736424 41.34294754
OS 31.31158584 41.34167754
OS 31.30778346 41.34041008
OS 31.28243172 41.33914262
OS 31.27102204 41.33407278
OS 31.2646822 41.33153786
OS 31.25327506 41.32519802
OS 31.24186792 41.32012818
OS 31.22792332 41.31252088
OS 31.21651364 41.30745104
OS 31.20256904 41.29984374
OS 31.19369428 41.29604136
OS 31.18228714 41.28970406
OS 31.1772173 41.28463168
OS 31.17468238 41.28336676
OS 31.170245 41.28019684
OS 31.16897754 41.27766192
OS 31.16200524 41.27068962
OS 31.15947032 41.26942216
OS 31.15186302 41.2618174
OS 31.14552318 41.25927994
OS 31.13728342 41.25611256
OS 31.12651128 41.24533534
OS 31.12460882 41.24470288
OS 31.12334136 41.24216796
OS 31.11953898 41.2332932
OS 31.11446914 41.22442098
OS 31.1081293 41.21808368
OS 31.10432692 41.21174384
OS 31.09798708 41.20540654
OS 31.09291724 41.19146194
OS 31.08847986 41.1857571
OS 31.08657994 41.1851221
OS 31.08531248 41.18258718
OS 31.07643772 41.1711775
OS 31.0739028 41.16864258
OS 31.07136534 41.16230782
OS 31.06819796 41.15406552
OS 31.0612282 41.14075592
OS 31.05996074 41.13568608
OS 31.05869074 41.12681132
OS 31.0542559 41.11476918
OS 31.04855106 41.10145958
OS 31.0466486 41.08434506
OS 31.04538114 41.0767403
OS 31.04411368 41.07166792
OS 31.0403113 41.06152824
OS 31.03904384 41.05645586
OS 31.03777384 41.0488511
OS 31.03523892 41.01842698
OS 31.03460646 41.01399214
OS 31.03587392 41.01018722
OS 31.03777384 40.98293556
OS 31.03904384 40.97532826
OS 31.0403113 40.97025842
OS 31.04284622 40.96391858
OS 31.04474614 40.95694628
OS 31.04601614 40.95187644
OS 31.0472836 40.9391993
OS 31.04855106 40.93412946
OS 31.04981852 40.9252547
OS 31.05742328 40.90877772
OS 31.06186066 40.88912828
OS 31.07009788 40.87328122
OS 31.0732678 40.86504146
OS 31.07643772 40.86060662
OS 31.07897264 40.8580717
OS 31.0802401 40.85553678
OS 31.08277502 40.85300186
OS 31.08404248 40.8504644
OS 31.08657994 40.84792948
OS 31.0878474 40.84539456
OS 31.0941847 40.83905726
OS 31.09608716 40.83208242
OS 31.09862208 40.82574512
OS 31.10559438 40.81877282
OS 31.10686184 40.8162379
OS 31.10939676 40.81370298
OS 31.11066422 40.81116552
OS 31.1151016 40.80799814
OS 31.1220739 40.80102838
OS 31.1227089 40.79912592
OS 31.12524382 40.79785846
OS 31.14615818 40.77694156
OS 31.14742564 40.77440664
OS 31.15186302 40.77123672
OS 31.15883532 40.76426442
OS 31.15947032 40.76236196
OS 31.16200524 40.7610945
OS 31.170245 40.75285474
OS 31.17087746 40.75095228
OS 31.17341492 40.74968482
OS 31.1772173 40.74588244
OS 31.17975222 40.74461498
OS 31.18608952 40.73827768
OS 31.20193404 40.73257538
OS 31.2038365 40.73067292
OS 31.20637142 40.72940546
OS 31.20890634 40.72687054
OS 31.21397872 40.72560308
OS 31.22285094 40.72179816
OS 31.23552808 40.7141934
OS 31.24186792 40.71165848
OS 31.25010514 40.70848856
OS 31.26341474 40.70151626
OS 31.26848712 40.7002488
OS 31.2792618 40.69834634
OS 31.28940402 40.69454396
OS 31.30398108 40.69010658
OS 31.3128533 40.68883912
OS 31.3407425 40.68757166
OS 31.34454488 40.6863042
OS 31.36292686 40.68440428
OS 31.37053162 40.68313682
OS 31.38067384 40.6806019
OS 31.39461844 40.67933444
OS 31.45102676 40.67616452
OS 31.57018578 40.67489706
OS 32.48796398 40.6736296
OS 32.49176636 40.67236214
OS 32.52599032 40.67109214
OS 32.53233016 40.66855722
OS 32.54120238 40.66475484
OS 32.55007714 40.66348738
OS 32.55514952 40.66221992
OS 32.56212182 40.66031746
OS 32.57669634 40.65334516
OS 32.5855711 40.65081024
OS 32.59571332 40.64954278
OS 32.60458554 40.64447294
OS 32.61853014 40.6381331
OS 32.62486998 40.63559818
OS 32.63373966 40.62925834
OS 32.64578434 40.6248235
OS 32.65212164 40.62102112
OS 32.6533891 40.6184862
OS 32.65909394 40.61404882
OS 32.66162886 40.61278136
OS 32.66606624 40.60834398
OS 32.6673337 40.60580906
OS 32.67050362 40.60263914
OS 32.67303854 40.60137168
OS 32.68001084 40.59566684
OS 32.68444822 40.591232
OS 32.6939529 40.58932954
OS 32.69839028 40.58742708
OS 32.70029274 40.58552716
OS 32.7015602 40.58045478
OS 32.70346266 40.57221502
OS 32.70663004 40.56777764
OS 32.71360234 40.56587772
OS 32.71994218 40.5646128
OS 32.72437956 40.56144288
OS 32.72691448 40.55256812
OS 32.72818194 40.54749828
OS 32.7357867 40.53989098
OS 32.7370567 40.53735606
OS 32.742759 40.53038376
OS 32.7497313 40.52467892
OS 32.7554336 40.51643916
OS 32.75797106 40.5151717
OS 32.75987098 40.51326924
OS 32.7624059 40.50693194
OS 32.7636759 40.5018621
OS 32.76874574 40.49298988
OS 32.77128066 40.49045496
OS 32.77381558 40.48411512
OS 32.7769855 40.47587536
OS 32.78332534 40.46573314
OS 32.78649272 40.45876084
OS 32.7909301 40.4467187
OS 32.79283256 40.44481624
OS 32.7979024 40.4334091
OS 32.79916986 40.42453688
OS 32.80043732 40.4194645
OS 32.80677716 40.40298498
OS 32.80804208 40.39791514
OS 32.80994454 40.38080316
OS 32.811212 40.37066094
OS 32.81247946 40.35291396
OS 32.81374692 40.3377019
OS 32.81501438 40.33136206
OS 32.81881676 40.32122238
OS 32.82135168 40.31488508
OS 32.82325414 40.30791278
OS 32.82198668 40.29396818
OS 32.81691684 40.2825585
OS 32.81311192 40.26734644
OS 32.811212 40.23755732
OS 32.80867454 40.21727542
OS 32.80740708 40.20586574
OS 32.80043732 40.18875376
OS 32.79916986 40.179879
OS 32.7979024 40.17480916
OS 32.79473248 40.1665694
OS 32.78776018 40.15072234
OS 32.78586026 40.13868274
OS 32.78332534 40.1323429
OS 32.7776205 40.12283568
OS 32.77254812 40.10889108
OS 32.76684328 40.10191878
OS 32.7636759 40.09874886
OS 32.7624059 40.09621394
OS 32.7567036 40.08924164
OS 32.75353368 40.08607172
OS 32.75099876 40.07973696
OS 32.74782884 40.0714972
OS 32.73959162 40.06325744
OS 32.7357867 40.0569176
OS 32.73388678 40.05501768
OS 32.73135186 40.05374768
OS 32.72564702 40.04804538
OS 32.72437956 40.04550792
OS 32.7224771 40.043608
OS 32.71994218 40.04234054
OS 32.71170242 40.03410078
OS 32.71106742 40.03219832
OS 32.7085325 40.03093086
OS 32.69902528 40.02142618
OS 32.69839028 40.01952372
OS 32.69585536 40.01825626
OS 32.68888306 40.01128396
OS 32.6876156 40.00874904
OS 32.68571568 40.00684658
OS 32.68318076 40.00557912
OS 32.67747592 39.99987428
OS 32.67620846 39.99733936
OS 32.67303854 39.99416944
OS 32.67050362 39.99290198
OS 32.66479878 39.98719714
OS 32.66353132 39.98466222
OS 32.6603614 39.9814923
OS 32.65782648 39.98022484
OS 32.65085418 39.97452
OS 32.64768426 39.97135008
OS 32.63564212 39.96691524
OS 32.63120474 39.96501278
OS 32.62866982 39.9624804
OS 32.62613744 39.96121294
OS 32.61726268 39.95740802
OS 32.61092538 39.9548731
OS 32.60205062 39.94980326
OS 32.59317586 39.94599834
OS 32.58430364 39.94473088
OS 32.57733134 39.94283096
OS 32.5709915 39.94029604
OS 32.5652892 39.93839358
OS 32.56021936 39.93712612
OS 32.54373984 39.93585866
OS 32.5044435 39.9345912
OS 32.47274938 39.93332374
OS 28.7338262 39.93268874
OS 28.7281239 39.93332374
OS 28.72432152 39.93205374
OS 28.70340462 39.93268874
OS 28.68122026 39.93205374
OS 28.67868534 39.93332374
OS 28.67488042 39.93205374
OS 28.6254444 39.92825136
OS 28.6178371 39.9269839
OS 28.61023234 39.92191406
OS 28.60769742 39.9206466
OS 28.60072512 39.91494176
OS 28.59312036 39.89846224
OS 28.5912179 39.86867312
OS 28.58995044 39.8509236
OS 28.58931544 39.8312767
OS 28.59058544 39.82874178
OS 28.58931544 39.8249394
OS 28.58868298 39.7634587
OS 28.58931544 39.51183106
OS 28.58804798 39.50802614
OS 28.58678052 39.40154426
OS 28.58551306 39.39774188
OS 28.5842456 39.3660503
OS 28.5779083 39.35210824
OS 28.57473838 39.34386848
OS 28.57220346 39.3387961
OS 28.56966854 39.33752864
OS 28.56269624 39.33055634
OS 28.56142624 39.32802142
OS 28.55445394 39.3248515
OS 28.54241434 39.32041412
OS 28.53544204 39.31724674
OS 28.52656728 39.31597928
OS 28.49170578 39.31407682
OS 28.4397323 39.31280936
OS 27.58217242 39.31217436
OS 27.57837004 39.31344182
OS 27.50991704 39.31470928
OS 27.50611212 39.31597928
OS 27.48456276 39.31724674
OS 27.47061816 39.32358404
OS 27.4623784 39.32675396
OS 27.4554061 39.33372626
OS 27.45287118 39.33499372
OS 27.44589888 39.34069856
OS 27.44082904 39.34830332
OS 27.43956158 39.35084078
OS 27.4357592 39.359713
OS 27.4351242 39.3793599
OS 27.4357592 39.38886712
OS 27.4344892 39.39267204
OS 27.43322174 39.39774188
OS 27.43385674 39.41739132
OS 27.43195428 39.43070092
OS 27.43322174 39.4345033
OS 27.43258928 39.45668766
OS 27.43322174 39.47253472
OS 27.43195428 39.4763371
OS 27.43322174 39.495349
OS 27.43195428 39.49915392
OS 27.43068682 39.64112976
OS 27.42941936 39.64493468
OS 27.4281519 39.68169356
OS 27.42308206 39.69310324
OS 27.4205446 39.69944308
OS 27.41927714 39.70451292
OS 27.41293984 39.71338768
OS 27.40343516 39.7228949
OS 27.39836278 39.72416236
OS 27.39519286 39.72479482
OS 27.39012302 39.72352736
OS 27.38251826 39.71719006
OS 27.37491096 39.70958276
OS 27.37237604 39.70324546
OS 27.36793866 39.69120078
OS 27.36476874 39.68296102
OS 27.36350128 39.67789118
OS 27.36223382 39.63859484
OS 27.36096636 39.63479246
OS 27.3596989 39.53464788
OS 27.3590639 39.43513576
OS 27.3596989 39.42436362
OS 27.35843144 39.42056124
OS 27.3590639 39.39964434
OS 27.35779644 39.3933045
OS 27.35652898 39.3730226
OS 27.35526152 39.35654562
OS 27.34575684 39.34069856
OS 27.34131946 39.33626118
OS 27.33878454 39.33499372
OS 27.33117724 39.32738642
OS 27.32483994 39.3248515
OS 27.31279526 39.32041412
OS 27.30582296 39.31724674
OS 27.30075312 39.31597928
OS 27.26082178 39.31407682
OS 27.2101183 39.31280936
OS 26.86468338 39.31217436
OS 26.860881 39.31344182
OS 26.79116054 39.31470928
OS 26.78735816 39.31597928
OS 26.76707372 39.31724674
OS 26.75566404 39.32231658
OS 26.74742682 39.3254865
OS 26.74045452 39.32992388
OS 26.73538468 39.33499372
OS 26.73284976 39.33626118
OS 26.72587746 39.34323348
OS 26.72461 39.3457684
OS 26.71953762 39.3533757
OS 26.71827016 39.35844554
OS 26.7163677 39.39203704
OS 26.71510024 39.39837688
OS 26.71446778 39.4078841
OS 26.71573524 39.41168648
OS 26.71446778 39.4345033
OS 26.71573524 39.43830568
OS 26.71446778 39.45859012
OS 26.71383278 39.77106346
OS 26.71446778 39.78564052
OS 26.71320032 39.7894429
OS 26.71446778 39.8109948
OS 26.71320032 39.81479718
OS 26.71193286 39.82367194
OS 26.7100304 39.85979836
OS 26.70876294 39.86740566
OS 26.70559302 39.87437796
OS 26.69988818 39.89022248
OS 26.69798826 39.89212494
OS 26.69671826 39.89465986
OS 26.69038096 39.9009997
OS 26.6891135 39.90353462
OS 26.6834112 39.90923692
OS 26.67707136 39.9130393
OS 26.67326898 39.91684168
OS 26.66693168 39.9193766
OS 26.6485497 39.92254652
OS 26.64411232 39.92571644
OS 26.63270264 39.93078628
OS 26.6212955 39.92951882
OS 26.61242328 39.92318152
OS 26.60608344 39.9206466
OS 26.59784368 39.91747668
OS 26.59213884 39.91177184
OS 26.58960392 39.91050438
OS 26.587069 39.90796946
OS 26.58453408 39.906702
OS 26.5800967 39.90226716
OS 26.57882924 39.8997297
OS 26.57565932 39.89656232
OS 26.5731244 39.89529486
OS 26.56868956 39.89085748
OS 26.56361718 39.88198272
OS 26.56108226 39.87564542
OS 26.5598148 39.87057304
OS 26.56108226 39.8655032
OS 26.5598148 39.85282606
OS 26.55727988 39.82113702
OS 26.55601242 39.8173321
OS 26.55727988 39.80845988
OS 26.55664488 39.78754298
OS 26.55727988 39.77296592
OS 26.55601242 39.76916354
OS 26.55664488 39.75331648
OS 26.55537742 39.67091888
OS 26.55474496 39.6664815
OS 26.55601242 39.66268166
OS 26.55474496 39.64620214
OS 26.5528425 39.59612858
OS 26.55157504 39.5859889
OS 26.54904012 39.57964906
OS 26.54460274 39.56887438
OS 26.54333528 39.563802
OS 26.53763044 39.5568297
OS 26.53446052 39.55366232
OS 26.53319306 39.5511274
OS 26.52748822 39.5441551
OS 26.51608108 39.53528288
OS 26.49326426 39.52514066
OS 26.48312204 39.52260574
OS 26.44192324 39.52070328
OS 26.4374884 39.52007082
OS 26.43368348 39.52133828
OS 26.41720396 39.52007082
OS 26.28663526 39.51880336
OS 26.25494622 39.52007082
OS 26.21374488 39.52070328
OS 26.20804258 39.52007082
OS 26.2042402 39.52133828
OS 26.1630414 39.5232382
OS 26.15796902 39.5245082
OS 26.14466196 39.5302105
OS 26.1364222 39.53338042
OS 26.13451974 39.53528288
OS 26.13198482 39.53655034
OS 26.12564498 39.54288764
OS 26.12311006 39.5441551
OS 26.11740522 39.5498574
OS 26.11613776 39.55239486
OS 26.10980046 39.55873216
OS 26.108533 39.56126708
OS 26.10472808 39.57014184
OS 26.1015607 39.5783816
OS 26.09839078 39.5853539
OS 26.09712332 39.59803104
OS 26.0945884 39.68296102
OS 26.09332094 39.80212004
OS 26.09205094 39.91494176
OS 26.08761864 39.9193766
OS 26.07937634 39.92127906
OS 26.06923666 39.92508144
OS 26.06226436 39.92825136
OS 26.02867286 39.93015382
OS 26.00838842 39.93142128
OS 25.93106066 39.93268874
OS 25.39294642 39.93332374
OS 25.38914404 39.93205374
OS 25.29533676 39.93078628
OS 25.29153438 39.92951882
OS 25.26047526 39.9276189
OS 25.25413796 39.92508144
OS 25.2471682 39.92191406
OS 25.23892844 39.9200116
OS 25.23449106 39.91810914
OS 25.23132114 39.91494176
OS 25.23005368 39.906067
OS 25.22942122 39.54795748
OS 25.23005368 39.53211296
OS 25.22878622 39.52831058
OS 25.23005368 39.5092936
OS 25.22878622 39.50549122
OS 25.22942122 39.48457686
OS 25.22815376 39.47950702
OS 25.22688376 39.47189972
OS 25.2262513 39.46619488
OS 25.22751876 39.46365996
OS 25.2262513 39.45985758
OS 25.22498384 39.43957314
OS 25.219279 39.43260084
OS 25.21420662 39.427531
OS 25.2053344 39.42499608
OS 25.17301036 39.42309616
OS 25.16667052 39.4218287
OS 25.16096822 39.4211937
OS 25.1571633 39.42246116
OS 25.14892354 39.42309616
OS 25.13878132 39.4218287
OS 25.1368814 39.4211937
OS 25.13307648 39.42246116
OS 25.1096272 39.4218287
OS 25.09251268 39.42246116
OS 25.0887103 39.4211937
OS 25.07223078 39.42246116
OS 25.06843094 39.4211937
OS 24.5151021 39.4218287
OS 24.50432742 39.4211937
OS 24.5005225 39.42246116
OS 24.4796056 39.4218287
OS 24.4599587 39.42246116
OS 24.45742378 39.4211937
OS 24.4536214 39.42246116
OS 24.44538164 39.42309616
OS 24.43523942 39.4218287
OS 24.42953458 39.4211937
OS 24.4257322 39.42246116
OS 24.41685744 39.42372862
OS 24.38706832 39.42562854
OS 24.38073102 39.42816346
OS 24.37185626 39.43703822
OS 24.36932134 39.44337806
OS 24.36805388 39.47887202
OS 24.36678642 39.4826744
OS 24.36551896 39.48774424
OS 24.36678642 39.50422376
OS 24.36551896 39.5169009
OS 24.36678642 39.52577566
OS 24.36551896 39.54225518
OS 24.36678642 39.55239486
OS 24.36551896 39.55619724
OS 24.36551896 39.73239958
OS 24.36551896 39.73366704
OS 24.36615142 39.81923456
OS 24.36551896 39.83381416
OS 24.36678642 39.83761654
OS 24.36551896 39.8578959
OS 24.36678642 39.86170082
OS 24.36615142 39.88261772
OS 24.36741888 39.88768756
OS 24.36868634 39.8940274
OS 24.36995634 39.92571644
OS 24.37629364 39.93585866
OS 24.38073102 39.94283096
OS 24.38263094 39.94473088
OS 24.3915057 39.94980326
OS 24.40038046 39.95360564
OS 24.42256228 39.95424064
OS 24.42699966 39.95360564
OS 24.43080204 39.9548731
OS 24.44030926 39.95677556
OS 24.44981648 39.95740802
OS 24.4536214 39.95614056
OS 24.47643822 39.95740802
OS 24.4802406 39.95614056
OS 24.5005225 39.95740802
OS 24.5074948 39.95677556
OS 24.89285852 39.95804302
OS 24.8972959 39.95994294
OS 24.89919836 39.9618454
OS 24.90046582 39.96691524
OS 24.90173328 39.97578746
OS 24.90046582 40.50946686
OS 24.89602844 40.5151717
OS 24.88715622 40.51643916
OS 24.51763702 40.51707416
OS 24.50305742 40.51643916
OS 24.49925504 40.51770662
OS 24.47833814 40.51707416
OS 24.46249362 40.51770662
OS 24.45869124 40.51643916
OS 24.44981648 40.51770662
OS 24.42889958 40.51707416
OS 24.42256228 40.51834162
OS 24.40101292 40.51960908
OS 24.38580086 40.52087654
OS 24.37882856 40.52531392
OS 24.3705888 40.53355368
OS 24.36932134 40.5424259
OS 24.36678642 40.57918732
OS 24.36551896 40.5829897
OS 24.36678642 40.60834398
OS 24.36551896 40.6121489
OS 24.36678642 40.63242826
OS 24.36805388 40.63623064
OS 24.36995634 40.66855722
OS 24.37312372 40.6729946
OS 24.37502618 40.67616452
OS 24.3775611 40.67743198
OS 24.38136348 40.68123436
OS 24.38770332 40.68376928
OS 24.42129482 40.6856692
OS 24.42636466 40.68693666
OS 24.43714188 40.68757166
OS 24.44094426 40.6863042
OS 24.46312862 40.68693666
OS 24.47516822 40.6863042
OS 24.47897314 40.68757166
OS 24.49101528 40.68693666
OS 24.49291774 40.68757166
OS 24.4941852 40.6863042
OS 24.49798758 40.68757166
OS 24.89476098 40.68883912
OS 24.89919836 40.69200904
OS 24.90173328 40.70214872
OS 24.90046582 41.2396305
OS 24.89602844 41.24533534
OS 24.88715622 41.2466028
OS 24.5011575 41.2472378
OS 24.48911282 41.2466028
OS 24.48531044 41.24787026
OS 24.46566354 41.2472378
OS 24.45805878 41.24850526
OS 24.45742378 41.24914026
OS 24.4536214 41.24787026
OS 24.44094426 41.2466028
OS 24.43714188 41.24787026
OS 24.42699966 41.25040772
OS 24.39530808 41.25167518
OS 24.39277316 41.2542101
OS 24.39023824 41.25547756
OS 24.37946356 41.26244986
OS 24.3781961 41.26498478
OS 24.37185626 41.27385954
OS 24.36932134 41.28019684
OS 24.36741888 41.31378834
OS 24.36615142 41.32139564
OS 24.36551896 41.3372427
OS 24.36678642 41.34104508
OS 24.36551896 41.36639682
OS 24.36678642 41.3701992
OS 24.36805388 41.38667872
OS 24.3705888 41.41329792
OS 24.38136348 41.42407514
OS 24.3915057 41.42661006
OS 24.398478 41.42597506
OS 24.42002736 41.42724252
OS 24.4250972 41.42850998
OS 24.4396768 41.42914498
OS 24.44347918 41.42787752
OS 24.4599587 41.42914498
OS 24.89349352 41.43041244
OS 24.89919836 41.43484982
OS 24.90046582 41.43991966
OS 24.90173328 41.44879442
OS 24.90046582 41.98247382
OS 24.89792836 41.98500874
OS 24.8972959 41.9869112
OS 24.88842368 41.98944612
OS 24.4796056 41.99007858
OS 24.46376362 41.98944612
OS 24.4599587 41.99071358
OS 24.43840934 41.98944612
OS 24.4320695 41.99198104
OS 24.39657808 41.9932485
OS 24.38770332 41.9995858
OS 24.38136348 42.00339072
OS 24.3781961 42.0065581
OS 24.37692864 42.00909302
OS 24.3705888 42.0192327
OS 24.36932134 42.02430508
OS 24.36741888 42.05029182
OS 24.36615142 42.06296896
OS 24.36551896 42.09022316
OS 24.36678642 42.09402554
OS 24.36805388 42.12698458
OS 24.36932134 42.13078696
OS 24.3705888 42.1434641
OS 24.37692864 42.1574087
OS 24.37882856 42.16564846
OS 24.38073102 42.16754838
OS 24.38136348 42.16945084
OS 24.38770332 42.17198576
OS 24.89602844 42.17325322
OS 24.89919836 42.17642314
OS 24.90046582 42.18149552
OS 24.90173328 42.1903652
OS 24.90046582 42.72404714
OS 24.89602844 42.72974944
OS 24.89095606 42.7310169
OS 24.4872129 42.7316519
OS 24.47897314 42.7310169
OS 24.47516822 42.73228436
OS 24.45425386 42.7316519
OS 24.44791656 42.73291936
OS 24.44347918 42.73355182
OS 24.4396768 42.73228436
OS 24.43080204 42.7310169
OS 24.41558998 42.73481928
OS 24.38263094 42.73608674
OS 24.3705888 42.74813142
OS 24.36932134 42.75700364
OS 24.36805388 42.78869522
OS 24.36678642 42.7924976
OS 24.36551896 42.79756744
OS 24.36678642 42.8140495
OS 24.36551896 42.82672664
OS 24.36678642 42.83559886
OS 24.36551896 42.85207838
OS 24.36678642 42.86348552
OS 24.36551896 42.86729044
OS 24.36678642 44.8803141
OS 24.36805388 44.88411394
OS 24.36995634 44.92531528
OS 24.3712238 44.93038512
OS 24.37565864 44.9411598
OS 24.3781961 44.95003202
OS 24.38199848 44.95636932
OS 24.38897078 44.95827178
OS 31.31665568 44.95700432
OE
OB 27.75076746 44.47149602 H
OS 27.74696508 44.47022856
OS 27.71273858 44.4689611
OS 27.70893366 44.4676911
OS 27.67977954 44.46642364
OS 27.67597716 44.46515618
OS 27.67090732 44.46388872
OS 27.65442526 44.4626238
OS 27.64935542 44.46135634
OS 27.62210122 44.45945388
OS 27.61766638 44.45882142
OS 27.61386146 44.46008888
OS 27.60879162 44.45882142
OS 27.57520012 44.45691896
OS 27.55745314 44.4556515
OS 27.54984584 44.45438404
OS 27.54350854 44.45311658
OS 27.53843616 44.45184912
OS 27.52132418 44.44994666
OS 27.51625434 44.4486792
OS 27.48900014 44.44550928
OS 27.47125062 44.44424182
OS 27.46491586 44.44297436
OS 27.45984348 44.4417069
OS 27.45287118 44.43980444
OS 27.44780134 44.43853698
OS 27.4211796 44.4347346
OS 27.40470262 44.43346714
OS 27.4008977 44.43219968
OS 27.38885556 44.43029722
OS 27.38378572 44.42902976
OS 27.3730085 44.42585984
OS 27.3596989 44.42395992
OS 27.34258692 44.42205746
OS 27.32103502 44.41952254
OS 27.31406272 44.41762008
OS 27.29948566 44.41191524
OS 27.29441582 44.41064778
OS 27.28110622 44.40747786
OS 27.27413392 44.40431048
OS 27.26779408 44.40177556
OS 27.25955432 44.39987564
OS 27.25321702 44.39860818
OS 27.23800496 44.39607326
OS 27.23293258 44.39480326
OS 27.22279544 44.39100088
OS 27.21455568 44.38783096
OS 27.20187854 44.3865635
OS 27.19300378 44.38529604
OS 27.18793394 44.38402858
OS 27.17969164 44.38085866
OS 27.17335434 44.37832374
OS 27.16511712 44.37515636
OS 27.16004474 44.37388636
OS 27.15053752 44.37198644
OS 27.14420022 44.36945152
OS 27.13722792 44.3662816
OS 27.13088808 44.36374668
OS 27.12581824 44.36247922
OS 27.1125061 44.3593093
OS 27.10617134 44.35677438
OS 27.0928592 44.35106954
OS 27.08778936 44.34980208
OS 27.07828214 44.34789962
OS 27.065605 44.34283232
OS 27.0586327 44.3396624
OS 27.04975794 44.33712748
OS 27.0389858 44.33522502
OS 27.02567366 44.32825272
OS 27.01680144 44.32445034
OS 26.99524954 44.31430812
OS 26.98637732 44.31304066
OS 26.97940502 44.3111382
OS 26.95341828 44.29909606
OS 26.94454352 44.29402622
OS 26.93059892 44.28768638
OS 26.91919432 44.28134908
OS 26.90524718 44.27501178
OS 26.88369782 44.26486956
OS 26.87165568 44.26296964
OS 26.86531838 44.26043218
OS 26.8545437 44.25472988
OS 26.84820386 44.25219242
OS 26.8063726 44.23064306
OS 26.79369546 44.22557068
OS 26.78672316 44.21986838
OS 26.78355324 44.216701
OS 26.78101832 44.21543354
OS 26.76580626 44.20529132
OS 26.76073642 44.20402386
OS 26.74869428 44.2021214
OS 26.74172198 44.19768402
OS 26.7379196 44.19388164
OS 26.72904484 44.1888118
OS 26.723975 44.18373942
OS 26.72144008 44.18247196
OS 26.7100304 44.17740212
OS 26.69862072 44.17106228
OS 26.68721358 44.16599244
OS 26.68087628 44.1621926
OS 26.6758039 44.15712022
OS 26.67326898 44.15585276
OS 26.67073406 44.15331784
OS 26.66819914 44.15205038
OS 26.66439676 44.148248
OS 26.6618593 44.14698054
OS 26.65932438 44.14444308
OS 26.65425454 44.14317562
OS 26.64284486 44.13683832
OS 26.63777502 44.13176594
OS 26.63523756 44.13049848
OS 26.63143518 44.1266961
OS 26.62890026 44.12542864
OS 26.62510042 44.12162626
OS 26.62256296 44.1203588
OS 26.61622566 44.11782134
OS 26.61115582 44.11655388
OS 26.60354852 44.10894912
OS 26.6010136 44.10768166
OS 26.58960392 44.09880944
OS 26.587069 44.09627452
OS 26.58072916 44.0937396
OS 26.57565932 44.0924696
OS 26.56868956 44.0867673
OS 26.56551964 44.08359738
OS 26.56298472 44.08232992
OS 26.5465052 44.06584786
OS 26.54397028 44.0645804
OS 26.54016536 44.06077802
OS 26.53382806 44.0582431
OS 26.5255883 44.05507318
OS 26.52241838 44.05190326
OS 26.51988346 44.0506358
OS 26.51481108 44.04556596
OS 26.51227616 44.0442985
OS 26.50847632 44.04049866
OS 26.5059414 44.03922866
OS 26.50213648 44.03542628
OS 26.48819188 44.03035644
OS 26.48058712 44.02274914
OS 26.4780522 44.02148168
OS 26.4710799 44.01577684
OS 26.46981244 44.01324192
OS 26.4641076 44.00753708
OS 26.46157014 44.00626962
OS 26.45840276 44.00183224
OS 26.45143046 43.99485994
OS 26.44889554 43.99359248
OS 26.4438257 43.98852264
OS 26.44129078 43.98725518
OS 26.43495094 43.98471772
OS 26.42671118 43.98155288
OS 26.41847142 43.97331312
OS 26.4159365 43.97204312
OS 26.41276658 43.9701432
OS 26.41149912 43.96760828
OS 26.37347024 43.92957686
OS 26.37220278 43.92704194
OS 26.3690354 43.92387202
OS 26.36649794 43.9226071
OS 26.35952564 43.91690226
OS 26.35635826 43.91373234
OS 26.34241366 43.9086625
OS 26.33734128 43.90359012
OS 26.33480636 43.90232266
OS 26.33227144 43.89978774
OS 26.32973652 43.89852028
OS 26.32530168 43.8940829
OS 26.32403422 43.89154798
OS 26.31959684 43.8871106
OS 26.31706192 43.88584314
OS 26.31262454 43.88140576
OS 26.31135708 43.87887084
OS 26.30818716 43.87570092
OS 26.30565224 43.87443346
OS 26.2999474 43.86872862
OS 26.29867994 43.8661937
OS 26.29551002 43.86302632
OS 26.2929751 43.86175886
OS 26.28853772 43.85732148
OS 26.28727026 43.85478656
OS 26.28410034 43.85161664
OS 26.28156542 43.85034918
OS 26.27586058 43.84464434
OS 26.27459312 43.84210942
OS 26.2714232 43.83894204
OS 26.26888828 43.83767204
OS 26.26445344 43.8332372
OS 26.26318598 43.83069974
OS 26.26001606 43.82753236
OS 26.25748114 43.8262649
OS 26.2517763 43.82056006
OS 26.25050884 43.81802514
OS 26.24733892 43.81485522
OS 26.244804 43.81358776
OS 26.23909916 43.80788292
OS 26.2378317 43.805348
OS 26.23529678 43.80281308
OS 26.23402932 43.80027816
OS 26.23022694 43.79647578
OS 26.22578956 43.7844311
OS 26.22261964 43.77999626
OS 26.2175498 43.77492388
OS 26.21628234 43.77238896
OS 26.21311242 43.76795158
OS 26.2105775 43.76668412
OS 26.20107028 43.7571769
OS 26.20043782 43.75527444
OS 26.1979029 43.75400698
OS 26.17571854 43.73182516
OS 26.17445108 43.72929024
OS 26.17191362 43.7229504
OS 26.17508354 43.71851556
OS 26.1839583 43.71724556
OS 26.19409798 43.71851556
OS 26.20107028 43.7242204
OS 26.20297274 43.72612032
OS 26.21184496 43.7311927
OS 26.21501488 43.73436008
OS 26.21628234 43.736895
OS 26.22198718 43.74259984
OS 26.2245221 43.7438673
OS 26.22769202 43.74703468
OS 26.22895948 43.7495696
OS 26.23466432 43.7565419
OS 26.2378317 43.75971182
OS 26.23973416 43.76668412
OS 26.24226908 43.77302396
OS 26.24924138 43.77999626
OS 26.25050884 43.78253118
OS 26.25621368 43.78950348
OS 26.2587486 43.79077094
OS 26.2657209 43.79774324
OS 26.26698836 43.80027816
OS 26.2714232 43.80344808
OS 26.2783955 43.81041784
OS 26.2790305 43.8123203
OS 26.28156542 43.81358776
OS 26.28980518 43.82182752
OS 26.29107264 43.82436244
OS 26.2929751 43.8262649
OS 26.29551002 43.82753236
OS 26.30121486 43.8332372
OS 26.30248232 43.83577212
OS 26.30438478 43.83767204
OS 26.3069197 43.83894204
OS 26.313892 43.84591434
OS 26.31515946 43.84844926
OS 26.31706192 43.85034918
OS 26.31959684 43.85161664
OS 26.32656914 43.85858894
OS 26.3272016 43.8604914
OS 26.32973652 43.86175886
OS 26.33924374 43.87126608
OS 26.3398762 43.873166
OS 26.34241366 43.87443346
OS 26.35065342 43.88267322
OS 26.35192088 43.88521068
OS 26.3538208 43.8871106
OS 26.35635826 43.88837806
OS 26.35889318 43.89091298
OS 26.3614281 43.89218298
OS 26.36649794 43.89725282
OS 26.37283778 43.89978774
OS 26.38107754 43.90295766
OS 26.38678238 43.9086625
OS 26.38931476 43.90992996
OS 26.39184968 43.91246488
OS 26.3943846 43.91373234
OS 26.39755452 43.91690226
OS 26.39882198 43.91943718
OS 26.40325936 43.92387202
OS 26.40579428 43.92513948
OS 26.41023166 43.92957686
OS 26.41149912 43.93211178
OS 26.4159365 43.93654916
OS 26.41847142 43.93781662
OS 26.42164134 43.94098654
OS 26.4229088 43.94352146
OS 26.42861364 43.9492263
OS 26.43114856 43.95049376
OS 26.43431848 43.95366368
OS 26.43558594 43.9561986
OS 26.44129078 43.96190344
OS 26.44319324 43.9625359
OS 26.4438257 43.96443836
OS 26.44572816 43.96507082
OS 26.44699562 43.96760828
OS 26.45396538 43.97458058
OS 26.4565003 43.97584804
OS 26.46157014 43.98091788
OS 26.4641076 43.98218534
OS 26.47678474 43.98725518
OS 26.48375704 43.99296002
OS 26.48692442 43.9961274
OS 26.48945934 43.99739486
OS 26.518616 44.02655406
OS 26.52115092 44.02782152
OS 26.52368584 44.03035644
OS 26.52622076 44.0316239
OS 26.5325606 44.03415882
OS 26.54143282 44.03922866
OS 26.54397028 44.04176612
OS 26.5465052 44.04303358
OS 26.55030758 44.04683342
OS 26.5528425 44.04810088
OS 26.55664488 44.05190326
OS 26.55918234 44.05317326
OS 26.56171726 44.05570818
OS 26.56805456 44.0582431
OS 26.5731244 44.05951056
OS 26.5800967 44.0652154
OS 26.58326662 44.06838532
OS 26.58580154 44.06965278
OS 26.58833646 44.0721877
OS 26.59087138 44.07345516
OS 26.59594122 44.078525
OS 26.59847868 44.079795
OS 26.61115582 44.08486484
OS 26.61369074 44.08739976
OS 26.61622566 44.08866722
OS 26.6212955 44.0937396
OS 26.62383042 44.09500706
OS 26.63080272 44.10197936
OS 26.63207018 44.10451174
OS 26.63523756 44.10768166
OS 26.63777502 44.10894912
OS 26.6415774 44.1127515
OS 26.64411232 44.11401896
OS 26.64664724 44.11655388
OS 26.65298708 44.1190888
OS 26.66122684 44.12225872
OS 26.6688316 44.1273311
OS 26.6758039 44.13049848
OS 26.68404366 44.1336684
OS 26.69164842 44.1400057
OS 26.69481834 44.14317562
OS 26.69735326 44.14444308
OS 26.70432556 44.15014792
OS 26.70622802 44.15205038
OS 26.71510024 44.15585276
OS 26.7315823 44.16472498
OS 26.74045452 44.16852736
OS 26.74679436 44.17106228
OS 26.75566404 44.17740212
OS 26.76200388 44.17993704
OS 26.76707372 44.1812045
OS 26.77594848 44.18627434
OS 26.78989308 44.19261418
OS 26.79623038 44.19641656
OS 26.80130276 44.20148894
OS 26.80383768 44.2027564
OS 26.8063726 44.20529132
OS 26.80890498 44.20655878
OS 26.81397736 44.21162862
OS 26.81651228 44.21289608
OS 26.82792196 44.21796846
OS 26.83679418 44.2230383
OS 26.85327624 44.23064306
OS 26.87228814 44.23951528
OS 26.87735798 44.24078528
OS 26.88686774 44.2426852
OS 26.89320504 44.24522012
OS 26.9014448 44.2496575
OS 26.91412194 44.25472988
OS 26.91665686 44.25599734
OS 26.92679908 44.26233464
OS 26.93313638 44.26486956
OS 26.99524954 44.29529368
OS 27.00158938 44.29909606
OS 27.00665922 44.30036352
OS 27.01553398 44.30163098
OS 27.02060382 44.30289844
OS 27.03708334 44.31050574
OS 27.0459581 44.31304066
OS 27.05926516 44.31621058
OS 27.0732123 44.32254788
OS 27.08398698 44.3257178
OS 27.0934942 44.32761772
OS 27.0998315 44.33015518
OS 27.1131411 44.33586002
OS 27.12328332 44.33839494
OS 27.13152308 44.34029486
OS 27.14546768 44.34663216
OS 27.15624236 44.34980208
OS 27.16955196 44.35296946
OS 27.17652426 44.35613938
OS 27.18539648 44.35994176
OS 27.1955387 44.36247922
OS 27.20377846 44.36437914
OS 27.2101183 44.36691406
OS 27.21835806 44.37008398
OS 27.22850028 44.3726189
OS 27.2430748 44.37452136
OS 27.26716162 44.37832374
OS 27.27730384 44.38212866
OS 27.28427614 44.38402858
OS 27.29441582 44.3865635
OS 27.31026034 44.38846596
OS 27.31533272 44.38973342
OS 27.32167002 44.39226834
OS 27.32990978 44.39543826
OS 27.340052 44.39797318
OS 27.35779644 44.4005081
OS 27.36286882 44.40177556
OS 27.37491096 44.4062104
OS 27.38124826 44.40747786
OS 27.39265794 44.40874786
OS 27.39899778 44.41001532
OS 27.40913746 44.41128278
OS 27.4218146 44.41255024
OS 27.43702666 44.41508516
OS 27.44336396 44.41635262
OS 27.45413864 44.41952254
OS 27.47885792 44.42142246
OS 27.49913982 44.42395992
OS 27.51688934 44.42522738
OS 27.53399878 44.4271273
OS 27.544141 44.42966476
OS 27.55681814 44.43093222
OS 27.57329766 44.43219968
OS 27.63668082 44.4347346
OS 27.70069644 44.4353696
OS 27.83443252 44.4347346
OS 27.8382349 44.43600206
OS 27.90795536 44.4347346
OS 27.95929638 44.43283214
OS 27.9821132 44.43156468
OS 27.99986272 44.43029722
OS 28.00620002 44.42902976
OS 28.0163397 44.42649484
OS 28.0505662 44.42269246
OS 28.0708481 44.420155
OS 28.0847927 44.41888754
OS 28.09049754 44.41698762
OS 28.09936976 44.41445016
OS 28.10951198 44.41191524
OS 28.12852642 44.41064778
OS 28.1323288 44.40938032
OS 28.1399361 44.40811286
OS 28.14373848 44.4068454
OS 28.15768308 44.40304556
OS 28.1665553 44.4005081
OS 28.18303736 44.39924064
OS 28.19190704 44.39797318
OS 28.20014934 44.39607326
OS 28.20521918 44.39480326
OS 28.2153614 44.39100088
OS 28.2223337 44.38910096
OS 28.22740354 44.38783096
OS 28.2432506 44.38593104
OS 28.25338774 44.38339612
OS 28.25972758 44.38085866
OS 28.27050226 44.37769128
OS 28.27557464 44.37642382
OS 28.29141916 44.37452136
OS 28.29902646 44.3732539
OS 28.30916614 44.37198644
OS 28.31423598 44.37071898
OS 28.3243782 44.36691406
OS 28.33261796 44.36374668
OS 28.3376878 44.36247922
OS 28.34719502 44.36057676
OS 28.35353486 44.35804184
OS 28.36684446 44.352337
OS 28.3719143 44.35106954
OS 28.38142152 44.34916708
OS 28.39156374 44.3453647
OS 28.40487334 44.3396624
OS 28.40994572 44.33839494
OS 28.41945294 44.33649248
OS 28.42579024 44.33395756
OS 28.44290222 44.32698526
OS 28.45177698 44.3257178
OS 28.46381912 44.32128042
OS 28.47713126 44.31557558
OS 28.4822011 44.31430812
OS 28.4955107 44.3111382
OS 28.52149744 44.29909606
OS 28.54051188 44.2902213
OS 28.55255402 44.28832138
OS 28.55889132 44.28578392
OS 28.56966854 44.28008162
OS 28.57854076 44.27627924
OS 28.60009266 44.26613702
OS 28.6051625 44.26486956
OS 28.61530218 44.2636021
OS 28.63685408 44.25345988
OS 28.65079868 44.24585512
OS 28.66474328 44.23951528
OS 28.6672782 44.23824782
OS 28.67424796 44.23254298
OS 28.67868534 44.2293756
OS 28.68565764 44.2236733
OS 28.68882502 44.22050338
OS 28.69136248 44.21923592
OS 28.7002347 44.21543354
OS 28.70847446 44.21226362
OS 28.71608176 44.20719124
OS 28.72305406 44.20529132
OS 28.7281239 44.20402386
OS 28.73699612 44.2027564
OS 28.75854802 44.19261418
OS 28.76742024 44.18754434
OS 28.77439254 44.1818395
OS 28.776295 44.17993704
OS 28.77882992 44.17866958
OS 28.78580222 44.17296474
OS 28.7889696 44.16979482
OS 28.8029142 44.16472498
OS 28.81051896 44.15965514
OS 28.81939372 44.15585276
OS 28.8308034 44.14951546
OS 28.83587324 44.14444308
OS 28.8384107 44.14317562
OS 28.845383 44.13747078
OS 28.84854784 44.1343034
OS 28.85488768 44.13176594
OS 28.86312744 44.12859856
OS 28.8650299 44.1266961
OS 28.88150942 44.1190888
OS 28.89038164 44.11401896
OS 28.8929191 44.11148404
OS 28.89545402 44.11021658
OS 28.911931 44.0937396
OS 28.91446592 44.0924696
OS 28.92207322 44.08486484
OS 28.93411536 44.08042746
OS 28.93855274 44.07725754
OS 28.94552504 44.0715527
OS 28.95313234 44.06648286
OS 28.95883464 44.06077802
OS 28.96517448 44.0582431
OS 28.97024178 44.05697564
OS 28.98165146 44.04810088
OS 28.98862376 44.04239858
OS 28.99052622 44.04049866
OS 28.99306114 44.03922866
OS 28.99686352 44.03542628
OS 29.00383582 44.03352636
OS 29.01397804 44.02718652
OS 29.01714796 44.0240166
OS 29.01968288 44.02274914
OS 29.04630208 43.9961274
OS 29.048837 43.99485994
OS 29.0564443 43.98725518
OS 29.06531652 43.98471772
OS 29.07165636 43.98091788
OS 29.07862866 43.97521304
OS 29.08306604 43.97204312
OS 29.08876834 43.96634082
OS 29.0900358 43.96380336
OS 29.09320572 43.96063598
OS 29.09574064 43.95936852
OS 29.09890802 43.9561986
OS 29.10017802 43.95366368
OS 29.10588286 43.94795884
OS 29.10841778 43.94669138
OS 29.11539008 43.94098654
OS 29.11855746 43.93781662
OS 29.12679976 43.93591416
OS 29.13377206 43.93147678
OS 29.13757444 43.9276744
OS 29.14010936 43.92640694
OS 29.14264428 43.92387202
OS 29.1451792 43.9226071
OS 29.14708166 43.92070464
OS 29.14834658 43.91816972
OS 29.17053094 43.89598536
OS 29.1724334 43.89535036
OS 29.17370086 43.89281544
OS 29.23011172 43.83640458
OS 29.23201164 43.83577212
OS 29.2332791 43.8332372
OS 29.27828028 43.78823602
OS 29.28018274 43.78760102
OS 29.2814502 43.7850661
OS 29.30109964 43.76541666
OS 29.30363456 43.7641492
OS 29.30680448 43.76097928
OS 29.30807194 43.75844436
OS 29.31377678 43.75273952
OS 29.3163117 43.75147206
OS 29.31948162 43.74830214
OS 29.32074908 43.74576722
OS 29.32645392 43.73879746
OS 29.32835384 43.736895
OS 29.33088876 43.7305577
OS 29.33405868 43.72231794
OS 29.33976098 43.7166131
OS 29.34103098 43.71407818
OS 29.3435659 43.71154326
OS 29.34483336 43.7090058
OS 29.34927074 43.70457096
OS 29.35180566 43.70330096
OS 29.35624304 43.69886612
OS 29.3575105 43.69632866
OS 29.36194788 43.69189382
OS 29.3644828 43.69062636
OS 29.36892018 43.68618898
OS 29.37018764 43.68365406
OS 29.37399002 43.67985168
OS 29.37525748 43.67731676
OS 29.3777924 43.67478184
OS 29.38222978 43.66273716
OS 29.3853997 43.65830232
OS 29.390467 43.65322994
OS 29.39173446 43.65069502
OS 29.4183562 43.62407328
OS 29.41962366 43.6215409
OS 29.42469604 43.61646852
OS 29.4259635 43.6139336
OS 29.42849842 43.6075963
OS 29.43356826 43.59872154
OS 29.4392731 43.59174924
OS 29.44117556 43.58984932
OS 29.44244302 43.58731186
OS 29.4462454 43.58350948
OS 29.44751286 43.58097456
OS 29.45131524 43.57717218
OS 29.45321516 43.57019988
OS 29.45575262 43.56386258
OS 29.46272492 43.55689028
OS 29.46399238 43.55435536
OS 29.4728646 43.54294568
OS 29.47540206 43.54041076
OS 29.47666952 43.53533838
OS 29.48300682 43.52393124
OS 29.48807666 43.51885886
OS 29.48934666 43.51632394
OS 29.49885388 43.50681672
OS 29.5007538 43.50618172
OS 29.50202126 43.50364934
OS 29.50582618 43.49984696
OS 29.50709364 43.49731204
OS 29.51089348 43.49350712
OS 29.5134284 43.48716982
OS 29.51659832 43.47893006
OS 29.52166816 43.47132276
OS 29.52610554 43.46054808
OS 29.53117792 43.45167332
OS 29.53624776 43.44660348
OS 29.53751522 43.44406856
OS 29.54005014 43.44153364
OS 29.5413176 43.43899872
OS 29.54638998 43.43392888
OS 29.54765744 43.43139396
OS 29.55145982 43.4225192
OS 29.55906712 43.4085746
OS 29.5628695 43.39969984
OS 29.56793934 43.39082762
OS 29.57300918 43.38575524
OS 29.57427664 43.38322286
OS 29.57998148 43.37625056
OS 29.5831514 43.37181318
OS 29.58568632 43.36927826
OS 29.5888537 43.3610385
OS 29.59139116 43.35469866
OS 29.597096 43.34519144
OS 29.60026338 43.33695168
OS 29.60216584 43.3325143
OS 29.60723568 43.32490954
OS 29.6110406 43.31603732
OS 29.61357552 43.30970002
OS 29.61991282 43.2995578
OS 29.62371774 43.29068304
OS 29.64526456 43.24885178
OS 29.64906694 43.23997702
OS 29.65223686 43.23173726
OS 29.65413932 43.22983734
OS 29.6579417 43.22096258
OS 29.65920916 43.21208782
OS 29.66047662 43.20701798
OS 29.66364654 43.19878076
OS 29.66935138 43.18927354
OS 29.67061884 43.18420116
OS 29.69470312 43.13476514
OS 29.69597058 43.12969276
OS 29.69723804 43.11955054
OS 29.7061128 43.1005361
OS 29.70864772 43.09039388
OS 29.70991518 43.08279166
OS 29.71498502 43.07138198
OS 29.71878994 43.06250722
OS 29.72132486 43.052365
OS 29.72259232 43.04476024
OS 29.72892962 43.03081564
OS 29.73146708 43.0244758
OS 29.73273454 43.0194085
OS 29.73463446 43.00863382
OS 29.7409743 42.99468922
OS 29.74414422 42.98644946
OS 29.74541168 42.98137708
OS 29.74667914 42.97250486
OS 29.7530139 42.95856026
OS 29.75554882 42.95222296
OS 29.75871874 42.93764336
OS 29.76252112 42.92750368
OS 29.76569104 42.91926392
OS 29.7669585 42.91419154
OS 29.76886096 42.89961702
OS 29.77139588 42.87933258
OS 29.7739308 42.86919036
OS 29.77710072 42.8609506
OS 29.7809031 42.84827346
OS 29.78280556 42.83243148
OS 29.78407302 42.82609164
OS 29.7878754 42.81594942
OS 29.79168032 42.80200482
OS 29.79294778 42.79440006
OS 29.7954827 42.77158324
OS 29.79801762 42.76144102
OS 29.80118754 42.75066634
OS 29.80372246 42.74052412
OS 29.80498992 42.7316519
OS 29.80625738 42.72657952
OS 29.80752484 42.70883508
OS 29.80878976 42.7050327
OS 29.81386214 42.68728318
OS 29.81703206 42.6562266
OS 29.81829952 42.64608692
OS 29.81956698 42.62580248
OS 29.8214669 42.60868796
OS 29.82463682 42.59411344
OS 29.82653928 42.57699892
OS 29.8284392 42.54467234
OS 29.82970666 42.49650378
OS 29.83097666 42.42298094
OS 29.83414404 42.41854356
OS 29.8360465 42.41664364
OS 29.84111634 42.41537364
OS 29.86013332 42.41664364
OS 29.86456816 42.42107848
OS 29.86583816 42.42614832
OS 29.86456816 42.44262784
OS 29.85949832 42.45403752
OS 29.85823086 42.46291228
OS 29.8563284 42.48762902
OS 29.85506094 42.50157362
OS 29.85252602 42.55481456
OS 29.85125856 42.57636392
OS 29.8499911 42.59411344
OS 29.84872364 42.60425312
OS 29.84745618 42.61059042
OS 29.84618872 42.61566026
OS 29.84492126 42.6220001
OS 29.8423838 42.63721216
OS 29.83984888 42.66256644
OS 29.83731396 42.67777596
OS 29.8360465 42.6828458
OS 29.83414404 42.68855064
OS 29.83287658 42.69362302
OS 29.83160912 42.70630016
OS 29.83034166 42.71137
OS 29.82780674 42.73672174
OS 29.82653928 42.74179158
OS 29.82527182 42.7519338
OS 29.82273436 42.75827364
OS 29.81893198 42.7734857
OS 29.81766452 42.7861603
OS 29.81639706 42.79123014
OS 29.8151296 42.80390728
OS 29.81386214 42.80770966
OS 29.81259468 42.81278204
OS 29.80878976 42.82545918
OS 29.80752484 42.83052902
OS 29.80498992 42.84827346
OS 29.80308746 42.86412052
OS 29.80182 42.86919036
OS 29.79801762 42.87933258
OS 29.7948477 42.88757234
OS 29.79231278 42.89771456
OS 29.79104532 42.90531932
OS 29.78470802 42.91926392
OS 29.78217056 42.92813614
OS 29.78027064 42.9439832
OS 29.77900318 42.9503205
OS 29.7739308 42.96426256
OS 29.77076342 42.97250486
OS 29.76822596 42.98264454
OS 29.76632604 42.98961684
OS 29.76315612 42.9978566
OS 29.75935374 43.00673136
OS 29.75681882 43.01560612
OS 29.7536489 43.02891318
OS 29.74667914 43.04476024
OS 29.74414422 43.05490246
OS 29.74224176 43.06187476
OS 29.73843938 43.07201444
OS 29.734002 43.08279166
OS 29.73146708 43.09293134
OS 29.73019708 43.1005361
OS 29.72385978 43.11067832
OS 29.72259232 43.11574816
OS 29.70864772 43.14490228
OS 29.70738026 43.15757942
OS 29.69470312 43.18420116
OS 29.68836328 43.19561084
OS 29.68202852 43.2095529
OS 29.67568868 43.22096258
OS 29.66935138 43.23490718
OS 29.66047662 43.25392162
OS 29.6585767 43.26596376
OS 29.65603924 43.27230106
OS 29.63955972 43.30526264
OS 29.62752012 43.32997938
OS 29.61611044 43.35153128
OS 29.6110406 43.35660112
OS 29.60977314 43.35913604
OS 29.6040683 43.36610834
OS 29.59963092 43.3743481
OS 29.59836346 43.38322286
OS 29.597096 43.39082762
OS 29.59329108 43.39716492
OS 29.5894887 43.4009673
OS 29.58822124 43.40350476
OS 29.57934648 43.4149119
OS 29.57427664 43.4225192
OS 29.57237418 43.4294915
OS 29.56603942 43.43963372
OS 29.5628695 43.44660348
OS 29.55969958 43.45484324
OS 29.55336228 43.46245054
OS 29.55145982 43.46435046
OS 29.55019236 43.46688538
OS 29.54448752 43.47385768
OS 29.5413176 43.4770276
OS 29.54005014 43.47956252
OS 29.53751522 43.48590236
OS 29.53117792 43.49731204
OS 29.52483808 43.50364934
OS 29.52357062 43.50618172
OS 29.51976824 43.50998664
OS 29.51850078 43.51252156
OS 29.51596586 43.51505648
OS 29.5134284 43.52139378
OS 29.51026102 43.52963608
OS 29.50329126 43.53660838
OS 29.50202126 43.5391433
OS 29.49631896 43.5461156
OS 29.49314904 43.54928298
OS 29.48934666 43.55689028
OS 29.48934666 43.55815774
OS 29.48300682 43.56956488
OS 29.47793698 43.57463472
OS 29.47666952 43.57717218
OS 29.46018746 43.5936517
OS 29.45892 43.59618662
OS 29.45511762 43.599989
OS 29.4525827 43.60632884
OS 29.44941278 43.6145686
OS 29.44371048 43.62027344
OS 29.44244302 43.62280836
OS 29.43864064 43.6266082
OS 29.43737318 43.62914312
OS 29.4329358 43.63231304
OS 29.42723096 43.63801788
OS 29.4259635 43.6405528
OS 29.42216112 43.64435772
OS 29.42089112 43.64689264
OS 29.4183562 43.64942756
OS 29.41582128 43.65576486
OS 29.41265136 43.66400716
OS 29.40567906 43.67097946
OS 29.4044116 43.67351438
OS 29.38919954 43.6887239
OS 29.38793462 43.69125882
OS 29.38286478 43.69632866
OS 29.38159478 43.69886612
OS 29.37905986 43.70520342
OS 29.3777924 43.71027326
OS 29.37208756 43.71724556
OS 29.36892018 43.72041548
OS 29.36765018 43.7229504
OS 29.35941042 43.7311927
OS 29.3568755 43.73246016
OS 29.35370558 43.736895
OS 29.33786106 43.75273952
OS 29.33532614 43.75400698
OS 29.33215622 43.7571769
OS 29.33088876 43.75971182
OS 29.32518646 43.76541666
OS 29.32265154 43.76668412
OS 29.31948162 43.76985404
OS 29.31821416 43.77238896
OS 29.31441178 43.77619134
OS 29.31314178 43.7787288
OS 29.30807194 43.78379864
OS 29.30553702 43.7926734
OS 29.30173464 43.7990107
OS 29.29666226 43.80408054
OS 29.2953948 43.80661546
OS 29.28968996 43.81358776
OS 29.28271766 43.8192926
OS 29.2814502 43.82182752
OS 29.27701282 43.8262649
OS 29.2744779 43.82753236
OS 29.27004052 43.83196974
OS 29.26877306 43.83450466
OS 29.26433822 43.83894204
OS 29.2618033 43.8402095
OS 29.25863338 43.84337688
OS 29.25736592 43.84591434
OS 29.25292854 43.85034918
OS 29.25039362 43.85161664
OS 29.24595624 43.85605402
OS 29.24468878 43.85858894
OS 29.2402514 43.86302632
OS 29.23771648 43.86429124
OS 29.2332791 43.86872862
OS 29.23201164 43.87126608
OS 29.2275768 43.87570092
OS 29.22503934 43.87696838
OS 29.22187196 43.8801383
OS 29.2206045 43.88267322
OS 29.21616712 43.8871106
OS 29.2136322 43.88837806
OS 29.2066599 43.8940829
OS 29.20349252 43.89725282
OS 29.18954792 43.90232266
OS 29.18447554 43.90739504
OS 29.18194062 43.9086625
OS 29.1794057 43.91119742
OS 29.17687078 43.91246488
OS 29.1724334 43.91690226
OS 29.17116594 43.91943718
OS 29.16799602 43.9226071
OS 29.1654611 43.92387202
OS 29.16102372 43.9283094
OS 29.15975626 43.93084432
OS 29.15531888 43.9352817
OS 29.15278396 43.93654916
OS 29.14708166 43.942254
OS 29.1458142 43.94478892
OS 29.12996714 43.96063598
OS 29.12743222 43.96190344
OS 29.12552976 43.96380336
OS 29.1242623 43.96634082
OS 29.11729 43.97331312
OS 29.11475508 43.97458058
OS 29.10841778 43.98091788
OS 29.10588286 43.98218534
OS 29.09954302 43.98471772
OS 29.09447318 43.98598772
OS 29.08750342 43.99169002
OS 29.0843335 43.99485994
OS 29.08179858 43.9961274
OS 29.06658652 44.01133946
OS 29.06404906 44.01260946
OS 29.05771176 44.01894676
OS 29.05264192 44.02021422
OS 29.04439962 44.02338414
OS 29.03869732 44.02908898
OS 29.03615986 44.03035644
OS 29.03362494 44.03289136
OS 29.03109002 44.03415882
OS 29.02412026 44.04113112
OS 29.0228528 44.04366604
OS 29.01841542 44.04683342
OS 29.01461304 44.0506358
OS 29.01207558 44.05190326
OS 29.00954066 44.05444072
OS 29.00700574 44.05570818
OS 29.00066844 44.0582431
OS 28.99179368 44.06331294
OS 28.98925876 44.06584786
OS 28.98672384 44.06711786
OS 28.97151178 44.08232992
OS 28.96897432 44.08359738
OS 28.9613721 44.09120214
OS 28.95503226 44.0937396
OS 28.94996242 44.09500706
OS 28.92714306 44.1127515
OS 28.92334068 44.11655388
OS 28.91827084 44.11782134
OS 28.91002854 44.12099126
OS 28.9068637 44.12416118
OS 28.90432624 44.12542864
OS 28.8992564 44.13049848
OS 28.89672148 44.13176594
OS 28.89038164 44.13810578
OS 28.88784672 44.13937324
OS 28.8789745 44.14317562
OS 28.87009974 44.148248
OS 28.8650299 44.15331784
OS 28.86249244 44.1545853
OS 28.85995752 44.15712022
OS 28.8574226 44.15838768
OS 28.8510853 44.16472498
OS 28.844748 44.1672599
OS 28.83650824 44.17042982
OS 28.82700102 44.17613466
OS 28.82066118 44.17866958
OS 28.8092515 44.18500688
OS 28.80544912 44.1888118
OS 28.8029142 44.19007926
OS 28.7959419 44.1957841
OS 28.79150452 44.20021894
OS 28.78516976 44.2027564
OS 28.77692746 44.20592378
OS 28.7693227 44.21099616
OS 28.7623504 44.21416354
OS 28.75347564 44.21796846
OS 28.75094072 44.21923592
OS 28.74333342 44.22430322
OS 28.7344612 44.22810814
OS 28.72622398 44.23127552
OS 28.72432152 44.23317798
OS 28.7217866 44.23444544
OS 28.707842 44.24078528
OS 28.69643232 44.24712258
OS 28.68248772 44.25345988
OS 28.66093836 44.2636021
OS 28.65586852 44.26486956
OS 28.6457263 44.26613702
OS 28.63685408 44.2712094
OS 28.62797932 44.27501178
OS 28.61973956 44.2781817
OS 28.61213226 44.28325154
OS 28.58995044 44.29402622
OS 28.55572394 44.31050574
OS 28.54685172 44.31304066
OS 28.53797696 44.31430812
OS 28.51135522 44.32698526
OS 28.49234078 44.33586002
OS 28.48346856 44.33712748
OS 28.47142642 44.34156232
OS 28.46508658 44.34409724
OS 28.45811428 44.34726462
OS 28.45304444 44.34853462
OS 28.4397323 44.351702
OS 28.433395 44.35423692
OS 28.42642524 44.35740684
OS 28.4200854 44.35994176
OS 28.41501556 44.36121176
OS 28.40550834 44.36311168
OS 28.39536612 44.36691406
OS 28.38839382 44.37008398
OS 28.38205652 44.3726189
OS 28.37318176 44.37388636
OS 28.36113962 44.37832374
OS 28.35289986 44.38149366
OS 28.34656256 44.38402858
OS 28.3376878 44.38529604
OS 28.33261796 44.3865635
OS 28.31867336 44.38783096
OS 28.30726622 44.39290334
OS 28.30092638 44.39543826
OS 28.2907867 44.39797318
OS 28.2831794 44.39924064
OS 28.27176972 44.40431048
OS 28.26543242 44.4068454
OS 28.25655766 44.40938032
OS 28.24071314 44.41128278
OS 28.23437584 44.41255024
OS 28.22423362 44.41635262
OS 28.21726132 44.41825508
OS 28.21219148 44.41952254
OS 28.19634442 44.42142246
OS 28.18240236 44.42269246
OS 28.159583 44.42649484
OS 28.15451316 44.4277623
OS 28.14754086 44.42966476
OS 28.14247102 44.43093222
OS 28.12472404 44.43346714
OS 28.10761206 44.4353696
OS 28.10000476 44.43663706
OS 28.08986254 44.43790452
OS 28.08352524 44.43917198
OS 28.07845286 44.44043944
OS 28.07148056 44.4423419
OS 28.05627104 44.44487682
OS 28.02394446 44.4480442
OS 28.00683502 44.44994666
OS 27.99796026 44.45121412
OS 27.99098796 44.45311658
OS 27.98464812 44.45438404
OS 27.96753614 44.4562865
OS 27.94345186 44.45755396
OS 27.92697234 44.45882142
OS 27.91746258 44.45945388
OS 27.91176028 44.45882142
OS 27.90795536 44.46008888
OS 27.88197116 44.4619888
OS 27.86929402 44.4632588
OS 27.85534942 44.46579118
OS 27.8452072 44.46705864
OS 27.82239038 44.4683261
OS 27.80844578 44.46959356
OS 27.7843615 44.47086102
OS 27.75076746 44.47149602
OE
OB 27.45921102 43.58287448 H
OS 26.72841238 43.58224202
OS 26.71383278 43.58287448
OS 26.7100304 43.58160702
OS 26.69735326 43.58033956
OS 26.66122684 43.57843964
OS 26.65678946 43.57653718
OS 26.64728224 43.56702996
OS 26.64601478 43.56196012
OS 26.64411232 43.52329624
OS 26.64220986 43.50618172
OS 26.6415774 42.46227728
OS 26.64284486 42.44706522
OS 26.64601478 42.44262784
OS 26.6479147 42.44072538
OS 26.65298708 42.43945792
OS 26.90271226 42.44072538
OS 26.90714964 42.44516276
OS 26.9084171 42.45023514
OS 26.9090521 42.52566044
OS 26.9084171 42.53009782
OS 26.90968456 42.5339002
OS 26.9084171 42.5465748
OS 26.90968456 42.58587368
OS 26.9090521 43.31033248
OS 26.91031956 43.32174216
OS 26.91285448 43.325542
OS 26.91919432 43.32807946
OS 27.12201586 43.32680946
OS 27.1264507 43.32364462
OS 27.1277207 43.31857224
OS 27.12835316 43.31159994
OS 27.1277207 43.30462764
OS 27.12898816 43.30082526
OS 27.12835316 43.23934456
OS 27.12898816 43.23237226
OS 27.1277207 43.22856988
OS 27.12835316 43.20638298
OS 27.1277207 43.19307592
OS 27.12898816 43.18927354
OS 27.12835316 43.17089156
OS 27.12898816 42.5529121
OS 27.12898816 42.55164464
OS 27.13025562 42.49967116
OS 27.13152308 42.49586878
OS 27.13279054 42.45910736
OS 27.13912784 42.45023514
OS 27.14229776 42.44706522
OS 27.14483268 42.44579776
OS 27.15117252 42.44326284
OS 27.19427124 42.44199284
OS 27.19807362 42.44072538
OS 27.20694838 42.43945792
OS 27.22596282 42.44072538
OS 27.2297652 42.43945792
OS 27.36413628 42.44072538
OS 27.36984112 42.44516276
OS 27.37110858 42.45023514
OS 27.37237604 43.32110716
OS 27.37681342 43.32680946
OS 27.38568564 43.32807946
OS 27.43639166 43.32934692
OS 27.44019404 43.33061438
OS 27.45033626 43.33188184
OS 27.45287118 43.33441676
OS 27.4554061 43.33568422
OS 27.46111094 43.34138906
OS 27.4623784 43.34392398
OS 27.46491586 43.35026382
OS 27.46681578 43.39272754
OS 27.46808324 43.39906738
OS 27.4687157 43.4149119
OS 27.46745078 43.41871682
OS 27.4687157 43.43139396
OS 27.46745078 43.57717218
OS 27.46554832 43.58033956
OS 27.45921102 43.58287448
OE
OB 28.81812626 43.58287448 H
OS 28.81432388 43.58160702
OS 28.80164674 43.58287448
OS 28.26163004 43.58160702
OS 28.25782512 43.58033956
OS 28.21916378 43.57843964
OS 28.20902156 43.57463472
OS 28.19507696 43.56956488
OS 28.19063958 43.56639496
OS 28.1881072 43.56386258
OS 28.18557228 43.56259512
OS 28.18303736 43.5600602
OS 28.1804999 43.55879274
OS 28.1747976 43.5530879
OS 28.1735276 43.55055298
OS 28.17036022 43.54738306
OS 28.1678253 43.5461156
OS 28.160853 43.5391433
OS 28.159583 43.53660838
OS 28.15768308 43.53470592
OS 28.15514816 43.53343846
OS 28.14944332 43.52773362
OS 28.14817586 43.5251987
OS 28.1462734 43.52329624
OS 28.14373848 43.52202878
OS 28.13676618 43.51505648
OS 28.13549872 43.51252156
OS 28.13106134 43.50935164
OS 28.12535904 43.50364934
OS 28.12409158 43.50111442
OS 28.12218912 43.49921196
OS 28.1196542 43.4979445
OS 28.11394936 43.49223966
OS 28.1126819 43.48970474
OS 28.10951198 43.48653482
OS 28.10697706 43.48526736
OS 28.10000476 43.47829506
OS 28.0987373 43.47576014
OS 28.09683484 43.47385768
OS 28.09429992 43.47259022
OS 28.08859508 43.46688538
OS 28.08732762 43.46435046
OS 28.08542516 43.46245054
OS 28.08289024 43.46118054
OS 28.0771854 43.45547824
OS 28.07591794 43.45294078
OS 28.07275056 43.4497734
OS 28.0702131 43.44850594
OS 28.0645108 43.44280364
OS 28.06324334 43.44026618
OS 28.06134342 43.43836626
OS 28.05880596 43.4370988
OS 28.05310366 43.43139396
OS 28.05183366 43.4288565
OS 28.0442289 43.41744936
OS 28.04169398 43.40730714
OS 28.04042652 43.39082762
OS 28.03915652 43.3870227
OS 28.03788906 43.3819554
OS 28.03535414 43.3756181
OS 28.03408668 43.37054572
OS 28.03281922 43.35786858
OS 28.03091676 43.325542
OS 28.0296493 43.28751312
OS 28.02901684 42.72277968
OS 28.0302843 42.7189773
OS 28.03155176 42.66700128
OS 28.03281922 42.6631989
OS 28.03408668 42.63784716
OS 28.03915652 42.62643748
OS 28.04105898 42.61819772
OS 28.04296144 42.60615304
OS 28.04929874 42.59601336
OS 28.05183366 42.58967606
OS 28.05563858 42.57953384
OS 28.06134342 42.57256154
OS 28.0645108 42.56939162
OS 28.06577826 42.5668567
OS 28.07275056 42.5598844
OS 28.07528548 42.55861694
OS 28.08162278 42.55227964
OS 28.08796262 42.54974472
OS 28.09620238 42.5465748
OS 28.10063976 42.54340742
OS 28.10380714 42.53897004
OS 28.10697706 42.53580012
OS 28.10951198 42.53453266
OS 28.11141444 42.53263274
OS 28.11394936 42.5262929
OS 28.11585182 42.5193206
OS 28.11775174 42.51742068
OS 28.1190192 42.51488322
OS 28.12218912 42.51171584
OS 28.12472404 42.51044838
OS 28.12789396 42.506011
OS 28.13106134 42.50284108
OS 28.1469084 42.49713624
OS 28.14944332 42.49460132
OS 28.15071078 42.4920664
OS 28.15514816 42.48762902
OS 28.15768308 42.48636156
OS 28.159583 42.4844591
OS 28.16212046 42.47812434
OS 28.16528784 42.46988458
OS 28.16845776 42.4654472
OS 28.17289514 42.46227728
OS 28.1747976 42.46037482
OS 28.17606506 42.4578399
OS 28.17923244 42.45466998
OS 28.18557228 42.45213506
OS 28.19761188 42.44769768
OS 28.20585164 42.4445303
OS 28.2223337 42.44326284
OS 28.25465774 42.44136038
OS 28.30789868 42.44009292
OS 28.66474328 42.43945792
OS 28.66601074 42.43945792
OS 28.8992564 42.44072538
OS 28.90242632 42.4438953
OS 28.90496124 42.45403752
OS 28.90369378 42.66446636
OS 28.8992564 42.6689012
OS 28.89418656 42.6701712
OS 28.44860706 42.67080366
OS 28.43276 42.6701712
OS 28.42895762 42.67143866
OS 28.40804326 42.67080366
OS 28.39346366 42.67143866
OS 28.38966128 42.6701712
OS 28.37761914 42.67207112
OS 28.37444922 42.67270612
OS 28.37064684 42.67143866
OS 28.36050716 42.6701712
OS 28.35670478 42.67143866
OS 28.34656256 42.67397358
OS 28.31360098 42.67524104
OS 28.30156138 42.68728318
OS 28.30029392 42.69235556
OS 28.29902646 42.70122778
OS 28.297759 42.7303819
OS 28.29649154 42.73418682
OS 28.297759 42.75573618
OS 28.29649154 42.7595411
OS 28.297124 42.84003624
OS 28.29649154 42.85334584
OS 28.297759 42.85714822
OS 28.29902646 42.86602298
OS 28.30029392 42.89391218
OS 28.30663122 42.9027844
OS 28.31233352 42.9084867
OS 28.32247574 42.91102162
OS 28.35416732 42.91229162
OS 28.35797224 42.91355908
OS 28.3788866 42.91292408
OS 28.80608412 42.91419154
OS 28.81368888 42.915459
OS 28.81749126 42.91926392
OS 28.82002872 42.92813614
OS 28.81939372 43.02131096
OS 28.82002872 43.03335056
OS 28.81876126 43.03715294
OS 28.81749126 43.053635
OS 28.8162238 43.0663096
OS 28.81559134 43.0808892
OS 28.8162238 43.08532404
OS 28.81495634 43.08912642
OS 28.81115396 43.09546626
OS 28.80418166 43.10243856
OS 28.7953069 43.10497348
OS 28.75347564 43.10624094
OS 28.74967326 43.1075084
OS 28.7407985 43.10877586
OS 28.72432152 43.1075084
OS 28.71544676 43.10877586
OS 28.69960224 43.1081434
OS 28.3040963 43.10941086
OS 28.29965892 43.11131078
OS 28.29649154 43.11828308
OS 28.297124 43.25075424
OS 28.29649154 43.26532876
OS 28.297759 43.26913368
OS 28.297124 43.29005058
OS 28.29839146 43.29638788
OS 28.29965892 43.31793978
OS 28.30092638 43.33441676
OS 28.30282884 43.33631922
OS 28.3040963 43.33885414
OS 28.31106606 43.34582644
OS 28.31360098 43.3470939
OS 28.3174059 43.34836136
OS 28.3522674 43.35026382
OS 28.35733724 43.35153128
OS 28.36937938 43.35216374
OS 28.37318176 43.35089628
OS 28.39600112 43.35216374
OS 28.3998035 43.35089628
OS 28.41248064 43.35216374
OS 28.89798894 43.3534312
OS 28.90242632 43.35660112
OS 28.90496124 43.36547588
OS 28.90432624 43.4700553
OS 28.90496124 43.4846349
OS 28.90369378 43.48843728
OS 28.90496124 43.50998664
OS 28.90369378 43.51378902
OS 28.90242632 43.51885886
OS 28.90052386 43.56259512
OS 28.89862394 43.56702996
OS 28.89608648 43.56956488
OS 28.89481902 43.5720998
OS 28.8929191 43.57400226
OS 28.89038164 43.57526972
OS 28.88784672 43.57780464
OS 28.88277688 43.5790721
OS 28.84031062 43.58097456
OS 28.83397332 43.58224202
OS 28.81812626 43.58287448
OE
OB 26.0191631 43.58287448 H
OS 26.01536072 43.58160702
OS 26.00268358 43.58287448
OS 25.23575852 43.58160702
OS 25.23132114 43.57717218
OS 25.23005368 43.56829742
OS 25.23068868 43.41427944
OS 25.23005368 43.4009673
OS 25.23132114 43.39716492
OS 25.2325886 43.3882927
OS 25.23449106 43.34836136
OS 25.23639352 43.34392398
OS 25.24146336 43.33885414
OS 25.24209836 43.33695168
OS 25.24463328 43.33568422
OS 25.2471682 43.3331493
OS 25.25604042 43.33188184
OS 25.2947043 43.32997938
OS 25.3010416 43.32871192
OS 25.31688612 43.32807946
OS 25.3206885 43.32934692
OS 25.33336564 43.32807946
OS 25.4113284 43.32744446
OS 25.42210308 43.32807946
OS 25.42590546 43.32680946
OS 25.44681982 43.32744446
OS 25.46266688 43.32680946
OS 25.46646926 43.32807946
OS 25.47724648 43.326177
OS 25.51717528 43.32300962
OS 25.52921742 43.31096748
OS 25.53048742 43.3058951
OS 25.53048742 43.29448542
OS 25.53048742 43.29321796
OS 25.53175488 43.28434574
OS 25.53302234 43.26532876
OS 25.5342898 43.26152892
OS 25.53302234 43.24885178
OS 25.5342898 43.22983734
OS 25.53302234 43.22603242
OS 25.5342898 43.20448306
OS 25.53302234 43.20068068
OS 25.5342898 43.18800608
OS 25.53555726 42.44516276
OS 25.53872718 42.44199284
OS 25.54379702 42.44072538
OS 25.55266924 42.43945792
OS 25.68894024 42.44009292
OS 25.70351984 42.43945792
OS 25.70732222 42.44072538
OS 25.72760666 42.43945792
OS 25.7314065 42.44072538
OS 25.74028126 42.44199284
OS 25.7802126 42.4438953
OS 25.78655244 42.44643022
OS 25.79542212 42.45530498
OS 25.79795958 42.46417974
OS 25.79922704 42.50474354
OS 25.8004945 42.50854592
OS 25.80176196 42.52122306
OS 25.8004945 42.5339002
OS 25.80176196 42.54277242
OS 25.80112696 42.55861694
OS 25.80239442 43.22032758
OS 25.80302942 43.22729988
OS 25.80176196 43.2311048
OS 25.80302942 43.25392162
OS 25.80176196 43.25772654
OS 25.80302942 43.2716686
OS 25.80429688 43.27547098
OS 25.80493188 43.30019026
OS 25.80429688 43.30082526
OS 25.80556434 43.30462764
OS 25.8068318 43.31096748
OS 25.81887648 43.32300962
OS 25.8277487 43.32427454
OS 25.84739814 43.32490954
OS 25.85056552 43.32427454
OS 25.8543679 43.325542
OS 25.86514512 43.32744446
OS 25.87211742 43.32807946
OS 25.8759198 43.32680946
OS 25.89937162 43.32744446
OS 25.91141122 43.32680946
OS 25.91521614 43.32807946
OS 25.93232812 43.32744446
OS 25.9982462 43.32871192
OS 26.0052185 43.32934692
OS 26.00902342 43.32807946
OS 26.02803786 43.32934692
OS 26.0318377 43.33061438
OS 26.0743065 43.3325143
OS 26.09015102 43.34202406
OS 26.09332094 43.34519144
OS 26.09839078 43.3540662
OS 26.10219316 43.36294096
OS 26.10409562 43.40667214
OS 26.10536308 43.41301198
OS 26.10599554 43.42505412
OS 26.10472808 43.4288565
OS 26.10599554 43.45420824
OS 26.10472808 43.45801316
OS 26.10599554 43.47449268
OS 26.10472808 43.49731204
OS 26.10599554 43.50111442
OS 26.10472808 43.51505648
OS 26.10346062 43.51885886
OS 26.1015607 43.56259512
OS 26.09965824 43.56702996
OS 26.0939534 43.57400226
OS 26.08634864 43.5790721
OS 26.04134746 43.58097456
OS 26.03500762 43.58224202
OS 26.0191631 43.58287448
OE
OB 26.4565003 43.58287448 H
OS 26.24987638 43.58287448
OS 26.22198718 43.58160702
OS 26.2175498 43.57843964
OS 26.21628234 43.57336726
OS 26.21564734 43.56892988
OS 26.21628234 43.56069266
OS 26.21501488 43.55689028
OS 26.21628234 43.54801552
OS 26.2175498 42.44516276
OS 26.22198718 42.44072538
OS 26.23466432 42.43945792
OS 26.4641076 42.44072538
OS 26.46854244 42.4438953
OS 26.4710799 42.45277006
OS 26.46981244 43.57717218
OS 26.46537506 43.58160702
OS 26.4565003 43.58287448
OE
OB 29.68519844 42.2936797 H
OS 29.68139352 42.29241224
OS 29.66237908 42.2936797
OS 29.6585767 42.29241224
OS 29.6376598 42.29304724
OS 29.6300525 42.29177978
OS 29.61230806 42.29051232
OS 29.60787068 42.28987732
OS 29.60660322 42.28987732
OS 29.59202362 42.28924486
OS 29.58505132 42.28987732
OS 29.58124894 42.28860986
OS 29.57871402 42.2873424
OS 29.5749091 42.28354002
OS 29.57237418 42.28227256
OS 29.57047426 42.2803701
OS 29.5692068 42.27783518
OS 29.56667188 42.27149534
OS 29.56477196 42.23410146
OS 29.5635045 42.22395924
OS 29.5622345 41.1781498
OS 29.56160204 41.16991004
OS 29.5628695 41.16610766
OS 29.56413696 41.15470052
OS 29.56730688 41.1515306
OS 29.5761791 41.15026314
OS 30.28922822 41.15089814
OS 30.30634274 41.15026314
OS 30.31014512 41.1515306
OS 30.32282226 41.15279806
OS 30.35894868 41.15470052
OS 30.36845844 41.16040536
OS 30.37099336 41.16167282
OS 30.37543074 41.1648402
OS 30.3766982 41.16737512
OS 30.4996596 41.29033652
OS 30.50092706 41.29287144
OS 30.50853182 41.30047874
OS 30.51106928 41.30681604
OS 30.51550666 41.31886072
OS 30.51740658 41.32456556
OS 30.51867404 41.3296354
OS 30.5205765 41.35942452
OS 30.52247896 41.39682094
OS 30.52374642 41.50837266
OS 30.52311142 42.026205
OS 30.52374642 42.0344473
OS 30.52247896 42.03824968
OS 30.52311142 42.06043404
OS 30.52184396 42.06677134
OS 30.51930904 42.10099784
OS 30.51867404 42.10670268
OS 30.5199415 42.11050506
OS 30.51867404 42.11557744
OS 30.51233674 42.12698458
OS 30.5066319 42.13395688
OS 30.4996596 42.13965918
OS 30.49839214 42.14219664
OS 30.4926873 42.14790148
OS 30.49015238 42.14916894
OS 30.48698246 42.15233632
OS 30.485715 42.15487378
OS 30.48001016 42.16057608
OS 30.47747524 42.16184608
OS 30.47557278 42.163746
OS 30.47430532 42.16628092
OS 30.46860048 42.17198576
OS 30.4660681 42.17325322
OS 30.46289818 42.17642314
OS 30.46163072 42.17895806
OS 30.45592588 42.18466036
OS 30.45339096 42.18592782
OS 30.4514885 42.18783028
OS 30.45022104 42.1903652
OS 30.4445162 42.19607004
OS 30.44198128 42.1973375
OS 30.43881136 42.20050742
OS 30.4375439 42.20304234
OS 30.43183906 42.20874718
OS 30.42930414 42.21001464
OS 30.42613422 42.21318456
OS 30.42486676 42.21571948
OS 30.41916192 42.22142432
OS 30.416627 42.22269178
OS 30.41472708 42.22459424
OS 30.41345708 42.22712916
OS 30.40775478 42.232834
OS 30.40521986 42.23410146
OS 30.40205248 42.23727138
OS 30.40078248 42.2398063
OS 30.39508018 42.2455086
OS 30.39254272 42.24677606
OS 30.3906428 42.24867852
OS 30.38937534 42.25121344
OS 30.3836705 42.25691828
OS 30.38113558 42.25818574
OS 30.37796566 42.26135566
OS 30.3766982 42.26389058
OS 30.37099336 42.26959542
OS 30.36845844 42.27086288
OS 30.3621186 42.27720018
OS 30.35958368 42.27846764
OS 30.35070892 42.28227256
OS 30.3424717 42.28543994
OS 30.3361344 42.28797486
OS 30.3285271 42.28924486
OS 30.32535718 42.28987732
OS 30.3215548 42.28860986
OS 30.31775242 42.28987732
OS 30.28289346 42.29177978
OS 30.22711506 42.29304724
OS 29.68519844 42.2936797
OE
OB 27.03454842 42.2936797 H
OS 27.03074604 42.29241224
OS 27.00602676 42.29304724
OS 27.00539176 42.29241224
OS 26.9698978 42.2936797
OS 26.48185458 42.29241224
OS 26.4780522 42.29114478
OS 26.44192324 42.28924486
OS 26.42797864 42.28797486
OS 26.42164134 42.28543994
OS 26.41149912 42.28163756
OS 26.40516182 42.27910264
OS 26.40072444 42.27593272
OS 26.39692206 42.27213034
OS 26.3943846 42.27086288
OS 26.39184968 42.26832796
OS 26.38931476 42.26705796
OS 26.38741484 42.26515804
OS 26.38614738 42.26262312
OS 26.38044254 42.25691828
OS 26.37790762 42.25565082
OS 26.3747377 42.2524809
OS 26.37347024 42.24994598
OS 26.3677654 42.24424368
OS 26.36523048 42.24297622
OS 26.3620631 42.2398063
OS 26.3607931 42.23727138
OS 26.35508826 42.23156654
OS 26.35255334 42.23029908
OS 26.35065342 42.22839662
OS 26.34938596 42.2258617
OS 26.34241366 42.2188894
OS 26.3398762 42.21762194
OS 26.33797628 42.21571948
OS 26.33670882 42.21318456
OS 26.33100398 42.20747972
OS 26.32846906 42.20621226
OS 26.32530168 42.20304234
OS 26.32403422 42.20050742
OS 26.31832938 42.19480258
OS 26.31579446 42.19353512
OS 26.313892 42.19163266
OS 26.31262454 42.18909774
OS 26.3069197 42.18339544
OS 26.30438478 42.18212798
OS 26.30121486 42.17895806
OS 26.2999474 42.17642314
OS 26.29551002 42.17198576
OS 26.2929751 42.1707183
OS 26.28980518 42.16754838
OS 26.28853772 42.16501346
OS 26.28283288 42.15930862
OS 26.28029796 42.15804116
OS 26.27712804 42.15487378
OS 26.27586058 42.15233632
OS 26.2714232 42.14790148
OS 26.26888828 42.14663148
OS 26.26445344 42.14219664
OS 26.26065106 42.1358568
OS 26.25431122 42.12698458
OS 26.25304376 42.12191474
OS 26.25114384 42.1098726
OS 26.24733892 42.09973038
OS 26.245439 42.09275808
OS 26.24417154 42.08768824
OS 26.24226908 42.05155928
OS 26.24100162 42.01606532
OS 26.24036662 41.41583538
OS 26.24163662 41.41203046
OS 26.24290408 41.35878952
OS 26.24417154 41.35498714
OS 26.245439 41.33597524
OS 26.2517763 41.3220281
OS 26.25304376 41.31695826
OS 26.2593836 41.3080835
OS 26.26318598 41.30428112
OS 26.26445344 41.3017462
OS 26.2714232 41.2947739
OS 26.27395812 41.29350644
OS 26.27586058 41.29160398
OS 26.27712804 41.28906906
OS 26.28410034 41.2820993
OS 26.28663526 41.28083184
OS 26.28980518 41.27639446
OS 26.29551002 41.27068962
OS 26.29804494 41.26942216
OS 26.2999474 41.2675197
OS 26.30121486 41.26498478
OS 26.30818716 41.25801248
OS 26.31072208 41.25674502
OS 26.31262454 41.25484256
OS 26.313892 41.25230764
OS 26.3208643 41.24533534
OS 26.32339922 41.24406788
OS 26.32656914 41.2396305
OS 26.33227144 41.23392566
OS 26.33480636 41.2326582
OS 26.33797628 41.22822336
OS 26.34494858 41.22125106
OS 26.3474835 41.2199836
OS 26.35065342 41.21554876
OS 26.35635826 41.20984392
OS 26.35889318 41.20857646
OS 26.3607931 41.206674
OS 26.3620631 41.20413908
OS 26.3690354 41.19716678
OS 26.37157032 41.19589932
OS 26.37347024 41.19399686
OS 26.3747377 41.19146194
OS 26.38171 41.18448964
OS 26.38424746 41.18322218
OS 26.38741484 41.1787848
OS 26.39311714 41.17307996
OS 26.3956546 41.1718125
OS 26.39755452 41.16991004
OS 26.39882198 41.16737512
OS 26.40072444 41.16420774
OS 26.40325936 41.16294028
OS 26.41720396 41.15406552
OS 26.46093768 41.1521656
OS 26.46854244 41.15089814
OS 26.48565696 41.15026314
OS 26.48945934 41.1515306
OS 26.4983341 41.15026314
OS 27.11060618 41.1515306
OS 27.1137761 41.15470052
OS 27.11631102 41.1648402
OS 27.11567602 41.28083184
OS 27.11631102 41.29160398
OS 27.11504356 41.2954089
OS 27.11567602 41.31759326
OS 27.11440856 41.32519802
OS 27.1131411 41.34294754
OS 27.11187364 41.35942452
OS 27.11123864 41.3638619
OS 27.1125061 41.36766428
OS 27.11123864 41.37273412
OS 27.10997118 41.37653904
OS 27.10426888 41.38351134
OS 27.10173396 41.38604626
OS 27.09539666 41.38858118
OS 27.05419532 41.39048364
OS 27.03708334 41.39238356
OS 27.02250628 41.3917511
OS 26.67897382 41.39301856
OS 26.60418352 41.39428602
OS 26.56995448 41.39555348
OS 26.54206782 41.39682094
OS 26.53699798 41.3980884
OS 26.53065814 41.40062332
OS 26.52241838 41.40379324
OS 26.51734854 41.40505816
OS 26.50910878 41.40949554
OS 26.50784132 41.41456538
OS 26.50847632 41.96282438
OS 26.50784132 41.97740144
OS 26.50910878 41.98120636
OS 26.51037624 41.9862762
OS 26.5116437 42.0192327
OS 26.51734854 42.026205
OS 26.52368584 42.03254484
OS 26.53382806 42.03507976
OS 26.5667871 42.03634722
OS 26.57058948 42.03761468
OS 26.59150638 42.03698222
OS 26.93376884 42.03824968
OS 27.00856168 42.03951714
OS 27.06180262 42.04331952
OS 27.06687246 42.04458698
OS 27.07764714 42.0477569
OS 27.08271952 42.04902436
OS 27.09539666 42.05029182
OS 27.11060618 42.05155928
OS 27.1137761 42.0547292
OS 27.11631102 42.06486888
OS 27.11567602 42.18086052
OS 27.11631102 42.19290012
OS 27.11504356 42.19670504
OS 27.11567602 42.2188894
OS 27.11440856 42.2252267
OS 27.11187364 42.26072066
OS 27.11123864 42.26515804
OS 27.1125061 42.26896042
OS 27.11123864 42.27403026
OS 27.10997118 42.27656772
OS 27.10426888 42.28354002
OS 27.1004665 42.2873424
OS 27.09159174 42.28987732
OS 27.08271952 42.28860986
OS 27.0789146 42.28987732
OS 27.04786056 42.29177978
OS 27.04025326 42.29304724
OS 27.03454842 42.2936797
OE
OB 28.0296493 42.2936797 H
OS 28.02584692 42.29241224
OS 28.0163397 42.29051232
OS 27.99986272 42.28924486
OS 27.99542534 42.2873424
OS 27.99289042 42.28480748
OS 27.99035296 42.28354002
OS 27.98148074 42.27720018
OS 27.9751409 42.26959542
OS 27.96943606 42.26515804
OS 27.9681686 42.26262312
OS 27.9611963 42.25565082
OS 27.95866138 42.25438336
OS 27.95675892 42.2524809
OS 27.95549146 42.24994598
OS 27.94978662 42.24424368
OS 27.94725424 42.24297622
OS 27.94408432 42.2398063
OS 27.94281686 42.23727138
OS 27.93711202 42.23156654
OS 27.9345771 42.23029908
OS 27.93267718 42.22839662
OS 27.93140718 42.2258617
OS 27.92443488 42.2188894
OS 27.92189996 42.21762194
OS 27.92000004 42.21571948
OS 27.91873258 42.21318456
OS 27.91302774 42.20747972
OS 27.91049028 42.20621226
OS 27.90859036 42.2043098
OS 27.9073229 42.20177488
OS 27.9003506 42.19480258
OS 27.89781314 42.19353512
OS 27.89591322 42.19163266
OS 27.89464576 42.18909774
OS 27.88894092 42.18339544
OS 27.88640854 42.18212798
OS 27.88323862 42.17895806
OS 27.88197116 42.17642314
OS 27.87626632 42.1707183
OS 27.8737314 42.16945084
OS 27.87182894 42.16754838
OS 27.87056148 42.16501346
OS 27.86358918 42.15804116
OS 27.86105426 42.1567737
OS 27.8591518 42.15487378
OS 27.85788434 42.15233632
OS 27.8521795 42.14663148
OS 27.84964458 42.14536402
OS 27.84774212 42.1434641
OS 27.84647466 42.14092918
OS 27.83950236 42.13395688
OS 27.83696744 42.13268688
OS 27.83506498 42.13078696
OS 27.83379752 42.12825204
OS 27.82809522 42.12254974
OS 27.8255603 42.12128228
OS 27.82239038 42.11811236
OS 27.82112292 42.11557744
OS 27.81541808 42.1098726
OS 27.81288316 42.10860514
OS 27.8109807 42.10670268
OS 27.80971324 42.10416776
OS 27.80274094 42.09719546
OS 27.80020602 42.095928
OS 27.7983061 42.09402554
OS 27.7970361 42.09149062
OS 27.7900638 42.08451832
OS 27.78752888 42.08325086
OS 27.77802166 42.06993872
OS 27.78119158 42.06423642
OS 27.7900638 42.06296896
OS 27.79957356 42.0623365
OS 27.8458422 42.06296896
OS 27.84964458 42.0617015
OS 27.8661241 42.06296896
OS 27.9136602 42.06106904
OS 27.92380242 42.0623365
OS 27.92697234 42.06296896
OS 27.93077472 42.0617015
OS 27.94345186 42.06043404
OS 27.97197098 42.05853158
OS 27.97894582 42.05409674
OS 27.98718558 42.04585444
OS 27.98845304 42.0407846
OS 27.99035296 42.0059231
OS 27.99162042 42.0008558
OS 27.99225542 41.98881112
OS 27.99098796 41.98500874
OS 27.99225542 41.96218938
OS 27.99098796 41.958387
OS 27.99225542 41.94951224
OS 27.99162042 41.8347906
OS 27.99225542 41.81894608
OS 27.99098796 41.8151437
OS 27.99225542 41.7948618
OS 27.9897205 41.78852196
OS 27.98781804 41.75239554
OS 27.98148074 41.74225332
OS 27.97640836 41.73464856
OS 27.97387344 41.7333811
OS 27.96373122 41.72704126
OS 27.954859 41.72450634
OS 27.94788924 41.72514134
OS 27.92506988 41.72387134
OS 27.92000004 41.72260388
OS 27.90542044 41.72197142
OS 27.90161806 41.72323888
OS 27.88894092 41.72197142
OS 27.62970852 41.72260388
OS 27.61386146 41.72197142
OS 27.60752416 41.72450634
OS 27.58407488 41.72514134
OS 27.57710258 41.72450634
OS 27.57329766 41.7257738
OS 27.57076274 41.72704126
OS 27.56315798 41.73211364
OS 27.56062052 41.7333811
OS 27.55491568 41.73781594
OS 27.55364822 41.7403534
OS 27.54731092 41.74922562
OS 27.54350854 41.75810038
OS 27.54223854 41.78218466
OS 27.54097108 41.79739672
OS 27.53653624 41.8018341
OS 27.53146386 41.80056664
OS 27.52892894 41.79802918
OS 27.52639656 41.79676172
OS 27.5111845 41.78154966
OS 27.50864704 41.7802822
OS 27.50674712 41.77838228
OS 27.50547966 41.77584482
OS 27.49850736 41.76887252
OS 27.49597244 41.76760506
OS 27.4896326 41.76000284
OS 27.48456276 41.75493046
OS 27.4820253 41.753663
OS 27.47885792 41.74922562
OS 27.47442054 41.74478824
OS 27.47188562 41.74352078
OS 27.4687157 41.73908594
OS 27.4630134 41.7333811
OS 27.46047848 41.73211364
OS 27.45857602 41.73021118
OS 27.45730856 41.72767626
OS 27.45033626 41.72070396
OS 27.44780134 41.7194365
OS 27.44589888 41.71753404
OS 27.44463142 41.71499912
OS 27.43765912 41.70802682
OS 27.4357592 41.70739182
OS 27.4344892 41.7048569
OS 27.42624944 41.69661968
OS 27.42371452 41.69535222
OS 27.4205446 41.6921823
OS 27.41927714 41.68964738
OS 27.41230484 41.68267508
OS 27.41040492 41.68204008
OS 27.40913746 41.67950516
OS 27.4008977 41.6712654
OS 27.39836278 41.66999794
OS 27.39519286 41.66556056
OS 27.38949056 41.65985572
OS 27.3869531 41.65858826
OS 27.38505318 41.6566858
OS 27.38378572 41.65415088
OS 27.37681342 41.64717858
OS 27.37427596 41.64591112
OS 27.37237604 41.6440112
OS 27.37110858 41.64147628
OS 27.36286882 41.63323652
OS 27.36096636 41.63260406
OS 27.3596989 41.6300666
OS 27.35145914 41.62182684
OS 27.34892422 41.62055938
OS 27.34575684 41.616122
OS 27.34131946 41.61168716
OS 27.33878454 41.61041716
OS 27.33688208 41.60851724
OS 27.33561462 41.60598232
OS 27.32864232 41.59901002
OS 27.3261074 41.59774256
OS 27.32420494 41.5958401
OS 27.32293748 41.59330518
OS 27.31596518 41.58633288
OS 27.31343026 41.58506542
OS 27.31026034 41.58063058
OS 27.30328804 41.57365828
OS 27.30075312 41.57239082
OS 27.29885066 41.57048836
OS 27.28997844 41.55147392
OS 27.2912459 41.5413317
OS 27.28997844 41.53752932
OS 27.28807852 41.5077402
OS 27.28681106 41.5001329
OS 27.28617606 41.4931606
OS 27.28744352 41.48935822
OS 27.28681106 41.4659064
OS 27.28744352 41.4525968
OS 27.28617606 41.44879442
OS 27.28681106 41.4316799
OS 27.28617606 41.16357528
OS 27.28744352 41.15977036
OS 27.28871098 41.15470052
OS 27.29187836 41.1515306
OS 27.29695074 41.15026314
OS 27.53653624 41.1515306
OS 27.53970362 41.15470052
OS 27.54223854 41.1648402
OS 27.54287354 41.38984864
OS 27.54223854 41.39935586
OS 27.54350854 41.40316078
OS 27.544776 41.45766918
OS 27.54604346 41.46147156
OS 27.54731092 41.47541362
OS 27.55238076 41.4868233
OS 27.55364822 41.49189314
OS 27.55618568 41.49823298
OS 27.55935306 41.50140036
OS 27.56442544 41.50266782
OS 27.57646758 41.5071052
OS 27.58280488 41.50964012
OS 27.58787726 41.51091012
OS 27.61576392 41.51217758
OS 27.65125788 41.51344504
OS 27.72478072 41.5147125
OS 27.80908078 41.51534496
OS 27.81288316 41.5140775
OS 27.91809758 41.51281004
OS 27.92189996 41.51154258
OS 27.95105408 41.51027512
OS 27.96499868 41.50393782
OS 27.97324098 41.50203536
OS 27.97767582 41.49886544
OS 27.98084574 41.49189314
OS 27.9827482 41.48365338
OS 27.98845304 41.47034378
OS 27.99035296 41.4316799
OS 27.99162042 41.38097388
OS 27.99289042 41.16040536
OS 27.99415788 41.15533552
OS 27.99796026 41.1515306
OS 28.0030301 41.15026314
OS 28.2426156 41.1515306
OS 28.24578552 41.15470052
OS 28.24705298 41.15977036
OS 28.24768544 41.23646312
OS 28.24705298 41.24089796
OS 28.24832044 41.24470288
OS 28.24705298 41.2535751
OS 28.24832044 41.30428112
OS 28.24832044 41.9659943
OS 28.24832044 41.96726176
OS 28.24705298 41.9799389
OS 28.24578552 42.06613634
OS 28.24451806 42.06993872
OS 28.2432506 42.10416776
OS 28.23817822 42.11557744
OS 28.23691076 42.12064728
OS 28.23437584 42.12698458
OS 28.23310838 42.1295195
OS 28.22676854 42.1358568
OS 28.22550108 42.13839172
OS 28.21979624 42.14536402
OS 28.21282394 42.15106886
OS 28.20712164 42.15804116
OS 28.20014934 42.163746
OS 28.1944445 42.1707183
OS 28.18747474 42.17642314
OS 28.1817699 42.18339544
OS 28.17923244 42.18466036
OS 28.1747976 42.18909774
OS 28.1735276 42.19163266
OS 28.16909276 42.19607004
OS 28.1665553 42.1973375
OS 28.16212046 42.20177488
OS 28.160853 42.2043098
OS 28.15768308 42.20747972
OS 28.15514816 42.20874718
OS 28.15071078 42.21318456
OS 28.14944332 42.21571948
OS 28.14500594 42.22015686
OS 28.14247102 42.22142432
OS 28.13803364 42.2258617
OS 28.13676618 42.22839662
OS 28.1323288 42.232834
OS 28.12979388 42.23410146
OS 28.12535904 42.23853884
OS 28.12409158 42.24107376
OS 28.12092166 42.24424368
OS 28.11838674 42.2455086
OS 28.11394936 42.24994598
OS 28.1126819 42.2524809
OS 28.10824452 42.25691828
OS 28.1057096 42.25818574
OS 28.10127222 42.26262312
OS 28.10000476 42.26515804
OS 28.09556738 42.26959542
OS 28.09303246 42.27086288
OS 28.08986254 42.27403026
OS 28.08859508 42.27656772
OS 28.0841577 42.28100256
OS 28.08162278 42.28227256
OS 28.07275056 42.28860986
OS 28.06768072 42.28987732
OS 28.04993374 42.29114478
OS 28.04613136 42.29241224
OS 28.0296493 42.2936797
OE
OB 27.61512892 44.24078528 H
OS 27.61132654 44.23951528
OS 27.60498924 44.2357129
OS 27.60308678 44.2287406
OS 27.60245178 42.5408725
OS 27.60308678 42.52502544
OS 27.60181932 42.52122306
OS 27.60308678 42.50220608
OS 27.60181932 42.4984037
OS 27.60308678 42.47685688
OS 27.60055186 42.47051704
OS 27.59991686 42.46227728
OS 27.60055186 42.45530498
OS 27.5992844 42.4515026
OS 27.59801694 42.43248562
OS 27.5916771 42.42361594
OS 27.58787726 42.4172761
OS 27.5859748 42.41537364
OS 27.58343988 42.41410618
OS 27.57773504 42.40840134
OS 27.57646758 42.40586642
OS 27.57456512 42.4039665
OS 27.5720302 42.40269904
OS 27.56632536 42.3969942
OS 27.5650579 42.39445674
OS 27.56188798 42.39128936
OS 27.55935306 42.3900219
OS 27.55364822 42.38431706
OS 27.55238076 42.3817796
OS 27.54921084 42.37861222
OS 27.54667592 42.37734476
OS 27.54223854 42.37290738
OS 27.54097108 42.37037246
OS 27.5378037 42.36720254
OS 27.53526624 42.36593508
OS 27.52956394 42.36023278
OS 27.52829648 42.35769786
OS 27.5251291 42.35452794
OS 27.52259164 42.35326048
OS 27.51688934 42.34755564
OS 27.51561934 42.34502072
OS 27.51245196 42.3418508
OS 27.50611212 42.33804842
OS 27.49977482 42.33170858
OS 27.49090006 42.32917366
OS 27.48456276 42.32537128
OS 27.47949038 42.3202989
OS 27.47695546 42.31903144
OS 27.46998316 42.3133266
OS 27.46428086 42.3063543
OS 27.45730856 42.300652
OS 27.4560411 42.29811708
OS 27.45033626 42.29241224
OS 27.44780134 42.29114478
OS 27.44463142 42.28797486
OS 27.44336396 42.28543994
OS 27.43892658 42.28100256
OS 27.43639166 42.2797351
OS 27.43322174 42.27656772
OS 27.43195428 42.27403026
OS 27.42624944 42.26832796
OS 27.42371452 42.26705796
OS 27.4205446 42.26389058
OS 27.41927714 42.26135566
OS 27.4148423 42.25691828
OS 27.41230484 42.25565082
OS 27.40913746 42.2524809
OS 27.40787 42.24994598
OS 27.40216516 42.24424368
OS 27.39963024 42.24297622
OS 27.39646286 42.2398063
OS 27.39519286 42.23727138
OS 27.39075802 42.232834
OS 27.38822056 42.23156654
OS 27.38505318 42.22839662
OS 27.38378572 42.2258617
OS 27.37808088 42.22015686
OS 27.37554596 42.2188894
OS 27.37237604 42.21571948
OS 27.37110858 42.21318456
OS 27.3666712 42.20874718
OS 27.36413628 42.20747972
OS 27.3596989 42.20304234
OS 27.35843144 42.20050742
OS 27.35399406 42.19607004
OS 27.35145914 42.19480258
OS 27.34829176 42.19163266
OS 27.3470243 42.18909774
OS 27.34131946 42.18339544
OS 27.33878454 42.18212798
OS 27.33561462 42.17895806
OS 27.33434716 42.17642314
OS 27.32864232 42.1707183
OS 27.3261074 42.16945084
OS 27.32293748 42.16628092
OS 27.32167002 42.163746
OS 27.31723264 42.15930862
OS 27.31469772 42.15804116
OS 27.3115278 42.15487378
OS 27.31026034 42.15233632
OS 27.30582296 42.14790148
OS 27.30328804 42.14663148
OS 27.29885066 42.14219664
OS 27.2975832 42.13965918
OS 27.29314582 42.13522434
OS 27.2906109 42.13395688
OS 27.28744352 42.13078696
OS 27.28617606 42.12825204
OS 27.28047122 42.12254974
OS 27.2779363 42.12128228
OS 27.27476892 42.11811236
OS 27.27349892 42.11557744
OS 27.26779408 42.1098726
OS 27.26525916 42.10860514
OS 27.26335924 42.10670268
OS 27.26209178 42.10416776
OS 27.25638694 42.09846292
OS 27.25384948 42.09719546
OS 27.24941464 42.09275808
OS 27.24814718 42.09022316
OS 27.24497726 42.08705324
OS 27.24244234 42.08578578
OS 27.23800496 42.0813484
OS 27.2367375 42.07881348
OS 27.23230012 42.0743761
OS 27.2297652 42.07310864
OS 27.22659782 42.06993872
OS 27.22533036 42.0674038
OS 27.21962552 42.0617015
OS 27.2170906 42.06043404
OS 27.21392068 42.05726412
OS 27.21265322 42.0547292
OS 27.20694838 42.04902436
OS 27.20441346 42.0477569
OS 27.202511 42.04585444
OS 27.20124354 42.04331952
OS 27.1955387 42.03761468
OS 27.19300378 42.03634722
OS 27.1885664 42.03190984
OS 27.18729894 42.02937492
OS 27.18412902 42.026205
OS 27.1815941 42.02493754
OS 27.17715672 42.0205027
OS 27.17588926 42.01796524
OS 27.17145188 42.0135304
OS 27.16891696 42.0122604
OS 27.16574958 42.00909302
OS 27.16448212 42.0065581
OS 27.15877728 42.0008558
OS 27.15624236 41.9995858
OS 27.15307244 41.99641842
OS 27.15180498 41.9938835
OS 27.14737014 41.98944612
OS 27.14483268 41.98817866
OS 27.14039784 41.98374128
OS 27.13912784 41.98120636
OS 27.134693 41.97676898
OS 27.13215554 41.97550152
OS 27.12898816 41.9723316
OS 27.1277207 41.96979668
OS 27.12201586 41.96409184
OS 27.1194784 41.96282438
OS 27.11757848 41.96092192
OS 27.11631102 41.958387
OS 27.11060618 41.95268216
OS 27.1080738 41.9514147
OS 27.10490388 41.94824478
OS 27.10363642 41.94570986
OS 27.09793158 41.94000756
OS 27.09539666 41.9387401
OS 27.09222674 41.93557018
OS 27.09095928 41.93303526
OS 27.08525444 41.92733042
OS 27.08271952 41.92606296
OS 27.08081706 41.9241605
OS 27.0795496 41.92162558
OS 27.07384476 41.91592074
OS 27.07130984 41.91465328
OS 27.06813992 41.91148336
OS 27.06687246 41.90894844
OS 27.06116762 41.9032436
OS 27.0586327 41.90197614
OS 27.05546278 41.89880876
OS 27.05419532 41.8962713
OS 27.04849302 41.89056646
OS 27.0459581 41.889299
OS 27.04405564 41.88739908
OS 27.04278818 41.88486162
OS 27.04025326 41.88232924
OS 27.0389858 41.87979432
OS 27.03391596 41.87472448
OS 27.03264596 41.87218702
OS 27.03011104 41.86584972
OS 27.02884358 41.86077988
OS 27.02377374 41.8493702
OS 27.02250628 41.83669306
OS 27.02060382 41.79929918
OS 27.01933636 41.75619792
OS 27.01870136 41.72387134
OS 27.01997136 41.72006896
OS 27.02123882 41.65922326
OS 27.02250628 41.65541834
OS 27.02377374 41.6300666
OS 27.02884358 41.61865946
OS 27.03011104 41.61358708
OS 27.03645088 41.6021774
OS 27.04152072 41.59710756
OS 27.04278818 41.59457264
OS 27.04722556 41.5888678
OS 27.04975794 41.58760034
OS 27.05673024 41.58063058
OS 27.05736524 41.57872812
OS 27.05990016 41.57746066
OS 27.06497 41.57239082
OS 27.06750746 41.57112336
OS 27.07004238 41.5685859
OS 27.07511222 41.56731844
OS 27.07764714 41.56985336
OS 27.0801846 41.57112336
OS 27.08398698 41.57492574
OS 27.0865219 41.5761932
OS 27.09095928 41.58063058
OS 27.09222674 41.5831655
OS 27.09666412 41.58760034
OS 27.09919904 41.5888678
OS 27.10363642 41.59330518
OS 27.10490388 41.5958401
OS 27.10933872 41.60027748
OS 27.11187364 41.60154494
OS 27.11631102 41.60598232
OS 27.11757848 41.60851724
OS 27.1207484 41.61168716
OS 27.12328332 41.61295462
OS 27.1277207 41.617392
OS 27.12898816 41.61992692
OS 27.13342554 41.6243643
OS 27.13596046 41.62563176
OS 27.14039784 41.6300666
OS 27.1416653 41.63260406
OS 27.14610014 41.6370389
OS 27.1486376 41.6383089
OS 27.15180498 41.64147628
OS 27.15307244 41.6440112
OS 27.15750982 41.64844604
OS 27.16004474 41.6497135
OS 27.16448212 41.65415088
OS 27.16574958 41.6566858
OS 27.17018442 41.66112318
OS 27.17271934 41.66239064
OS 27.17715672 41.66682802
OS 27.17842418 41.66936294
OS 27.1815941 41.67253286
OS 27.18412902 41.67380032
OS 27.19110132 41.67950516
OS 27.19427124 41.68267508
OS 27.20061108 41.68521
OS 27.20885084 41.68837992
OS 27.21582314 41.69535222
OS 27.21835806 41.69661968
OS 27.22533036 41.70232452
OS 27.22659782 41.7048569
OS 27.23356758 41.7118292
OS 27.2361025 41.71309666
OS 27.23927242 41.71753404
OS 27.24497726 41.72323888
OS 27.24751218 41.72450634
OS 27.24941464 41.7264088
OS 27.2506821 41.72894372
OS 27.25638694 41.73464856
OS 27.25892186 41.73591602
OS 27.26082178 41.73781594
OS 27.26209178 41.7403534
OS 27.26906408 41.7473257
OS 27.271599 41.74859316
OS 27.27349892 41.75049308
OS 27.27476892 41.75303054
OS 27.28047122 41.75873538
OS 27.28300868 41.76000284
OS 27.2849086 41.76190276
OS 27.28617606 41.76443768
OS 27.29314582 41.77140998
OS 27.29568328 41.77267744
OS 27.29885066 41.77711228
OS 27.30582296 41.78408458
OS 27.30772542 41.78471958
OS 27.30899288 41.7872545
OS 27.31723264 41.79549426
OS 27.31976756 41.79676172
OS 27.32167002 41.79866418
OS 27.32293748 41.8011991
OS 27.32990978 41.8081714
OS 27.3324447 41.80943886
OS 27.33434716 41.81134132
OS 27.33561462 41.81387624
OS 27.34258692 41.82084854
OS 27.34512184 41.822116
OS 27.35145914 41.82972076
OS 27.35526152 41.83352314
OS 27.35779644 41.8347906
OS 27.36413628 41.8423979
OS 27.3666712 41.84493282
OS 27.36857366 41.84556782
OS 27.36984112 41.84810274
OS 27.37808088 41.8563425
OS 27.3806158 41.85760996
OS 27.38251826 41.85951242
OS 27.38378572 41.86204734
OS 27.39075802 41.86901964
OS 27.39329294 41.8702871
OS 27.39519286 41.87218702
OS 27.39646286 41.87472448
OS 27.40343516 41.88169678
OS 27.40597008 41.88296424
OS 27.40913746 41.88739908
OS 27.41610976 41.89437138
OS 27.41864468 41.89563884
OS 27.4218146 41.90007622
OS 27.4275169 41.90578106
OS 27.42941936 41.90641352
OS 27.43068682 41.90894844
OS 27.43892658 41.9171882
OS 27.4414615 41.91845566
OS 27.44336396 41.92035812
OS 27.44463142 41.92289304
OS 27.45160372 41.92986534
OS 27.45413864 41.9311328
OS 27.4560411 41.93303526
OS 27.45730856 41.93557018
OS 27.46428086 41.94254248
OS 27.46681578 41.94380994
OS 27.46998316 41.94824478
OS 27.475688 41.95394962
OS 27.47822292 41.95521708
OS 27.48012538 41.95711954
OS 27.48139284 41.95965446
OS 27.48836514 41.96662676
OS 27.49090006 41.96789422
OS 27.4972399 41.97550152
OS 27.49977482 41.97803644
OS 27.50230974 41.9793039
OS 27.5042122 41.98120636
OS 27.50547966 41.98374128
OS 27.51245196 41.99071358
OS 27.51498688 41.99198104
OS 27.51688934 41.9938835
OS 27.5181568 41.99641842
OS 27.5251291 42.00339072
OS 27.52766402 42.00465564
OS 27.5308314 42.00909302
OS 27.53653624 42.01479786
OS 27.53907116 42.01606532
OS 27.54097108 42.01796524
OS 27.54223854 42.0205027
OS 27.54921084 42.027475
OS 27.5517483 42.02874246
OS 27.55491568 42.0331773
OS 27.56062052 42.03888214
OS 27.56315798 42.04015214
OS 27.5650579 42.04205206
OS 27.56632536 42.04458698
OS 27.5720302 42.05029182
OS 27.57456512 42.05155928
OS 27.57773504 42.0547292
OS 27.5790025 42.05726412
OS 27.5859748 42.06423642
OS 27.58787726 42.06486888
OS 27.58914218 42.0674038
OS 27.59738194 42.07564356
OS 27.59991686 42.07691102
OS 27.60181932 42.07881348
OS 27.60308678 42.0813484
OS 27.60879162 42.08705324
OS 27.61132654 42.0883207
OS 27.613229 42.09022316
OS 27.61449646 42.09275808
OS 27.62146876 42.09973038
OS 27.62400368 42.10099784
OS 27.62590614 42.1029003
OS 27.6271736 42.10543522
OS 27.63287844 42.11114006
OS 27.63541336 42.11240752
OS 27.63858328 42.11557744
OS 27.63985074 42.11811236
OS 27.64682304 42.12508212
OS 27.64935542 42.12634958
OS 27.65125788 42.12825204
OS 27.65252534 42.13078696
OS 27.65949764 42.13775926
OS 27.66139756 42.13839172
OS 27.66266502 42.14092918
OS 27.66963732 42.14790148
OS 27.67217478 42.14916894
OS 27.6740747 42.15106886
OS 27.67534216 42.15360378
OS 27.68231446 42.16057608
OS 27.68485192 42.16184608
OS 27.68675184 42.163746
OS 27.6880193 42.16628092
OS 27.6949916 42.17325322
OS 27.69752906 42.17452322
OS 27.69942898 42.17642314
OS 27.70069644 42.17895806
OS 27.70640128 42.18466036
OS 27.70893366 42.18592782
OS 27.71083612 42.18783028
OS 27.71210358 42.1903652
OS 27.71907588 42.1973375
OS 27.7216108 42.19860496
OS 27.72351326 42.20050742
OS 27.72478072 42.20304234
OS 27.73175302 42.21001464
OS 27.73428794 42.2112821
OS 27.73745786 42.21571948
OS 27.7431627 42.22142432
OS 27.74569762 42.22269178
OS 27.74760008 42.22459424
OS 27.74886754 42.22712916
OS 27.75583984 42.23410146
OS 27.75837476 42.23536892
OS 27.76027722 42.23727138
OS 27.76154468 42.2398063
OS 27.76724952 42.2455086
OS 27.7697819 42.24677606
OS 27.77168436 42.24867852
OS 27.77295182 42.25121344
OS 27.77992412 42.25818574
OS 27.78245904 42.2594532
OS 27.7843615 42.26135566
OS 27.78562896 42.26389058
OS 27.79260126 42.27086288
OS 27.79513618 42.27213034
OS 27.80147348 42.2797351
OS 27.8040084 42.28227256
OS 27.80654586 42.28354002
OS 27.80844578 42.28543994
OS 27.80971324 42.28797486
OS 27.81668554 42.29494716
OS 27.819223 42.29621716
OS 27.82112292 42.29811708
OS 27.82239038 42.300652
OS 27.82809522 42.30762176
OS 27.8312626 42.31079168
OS 27.83379752 42.31713152
OS 27.83696744 42.32537128
OS 27.84203728 42.33297604
OS 27.8452072 42.33994834
OS 27.84774212 42.34628818
OS 27.85091204 42.35452794
OS 27.85408196 42.36530008
OS 27.85598188 42.40269904
OS 27.85724934 42.436923
OS 27.85788434 42.44769768
OS 27.85788434 42.44896514
OS 27.85724934 43.99232502
OS 27.85788434 44.010707
OS 27.85661688 44.01450938
OS 27.85534942 44.02338414
OS 27.85344696 44.06331294
OS 27.84774212 44.07282016
OS 27.84647466 44.07535762
OS 27.84203728 44.08106246
OS 27.83950236 44.08232992
OS 27.83379752 44.08803476
OS 27.83253006 44.09056968
OS 27.8306276 44.0924696
OS 27.82809522 44.0937396
OS 27.81985546 44.10197936
OS 27.818588 44.10451174
OS 27.81415062 44.10768166
OS 27.80844578 44.1133865
OS 27.80717832 44.11592142
OS 27.8052784 44.11782134
OS 27.80274094 44.1190888
OS 27.79576864 44.1260611
OS 27.79450118 44.12859856
OS 27.7900638 44.13176594
OS 27.7843615 44.13747078
OS 27.7830915 44.1400057
OS 27.78119158 44.14190816
OS 27.77865666 44.14317562
OS 27.77168436 44.15014792
OS 27.7704169 44.15268284
OS 27.76281214 44.15902268
OS 27.75900976 44.16282506
OS 27.75773976 44.16535744
OS 27.750135 44.17169728
OS 27.74760008 44.1742322
OS 27.74633262 44.17676712
OS 27.74443016 44.17866958
OS 27.74189524 44.17993704
OS 27.73492294 44.18690934
OS 27.73365548 44.18944426
OS 27.7292181 44.19261418
OS 27.72351326 44.19831902
OS 27.7222458 44.20085394
OS 27.72034334 44.2027564
OS 27.71780842 44.20402386
OS 27.71083612 44.21099616
OS 27.70956866 44.21353108
OS 27.70766874 44.21543354
OS 27.70513382 44.216701
OS 27.69816152 44.22240584
OS 27.69625906 44.22430322
OS 27.69372414 44.22557068
OS 27.68738684 44.22810814
OS 27.67534216 44.23254298
OS 27.66836986 44.2357129
OS 27.6601301 44.23761536
OS 27.6537928 44.23888282
OS 27.63858328 44.24015028
OS 27.61512892 44.24078528
OE
OB 29.00320336 42.2936797 H
OS 28.4137481 42.29241224
OS 28.40804326 42.28797486
OS 28.4067758 42.28290502
OS 28.40804326 41.15470052
OS 28.41121318 41.1515306
OS 28.41628302 41.15026314
OS 28.58551306 41.15089814
OS 28.60262758 41.15026314
OS 28.60642996 41.1515306
OS 28.61910456 41.15279806
OS 28.65396606 41.15470052
OS 28.65840344 41.15660298
OS 28.66791066 41.16610766
OS 28.66917558 41.1711775
OS 28.67107804 41.20984392
OS 28.67361296 41.23012328
OS 28.6729805 41.25104018
OS 28.67424796 41.25484256
OS 28.6729805 41.25864748
OS 28.67361296 41.28336676
OS 28.6723455 41.36956674
OS 28.67107804 41.38604626
OS 28.66981058 41.40759308
OS 28.66854312 41.42280768
OS 28.6672782 41.42787752
OS 28.66474328 41.43421482
OS 28.66157336 41.44499204
OS 28.66284082 41.45766918
OS 28.6729805 41.479216
OS 28.67488042 41.49633052
OS 28.67805034 41.5007679
OS 28.68502264 41.50266782
OS 28.81495634 41.50203536
OS 28.8308034 41.50266782
OS 28.83460578 41.50140036
OS 28.85615514 41.50266782
OS 28.86249244 41.5001329
OS 28.89862394 41.49823298
OS 28.9062287 41.4931606
OS 28.90939608 41.48999322
OS 28.911931 41.48872322
OS 28.91510092 41.48555584
OS 28.91763584 41.47668108
OS 28.92270568 41.46780632
OS 28.92904552 41.46147156
OS 28.93031298 41.45893664
OS 28.93601782 41.45196434
OS 28.93918774 41.44879442
OS 28.94172266 41.44245458
OS 28.94299012 41.43738474
OS 28.95186234 41.42344014
OS 28.95629972 41.411398
OS 28.95946964 41.40696062
OS 28.96453948 41.40189078
OS 28.96580948 41.39935586
OS 28.97151178 41.39238356
OS 28.97594662 41.38794618
OS 28.98165146 41.37210166
OS 28.98482138 41.36893174
OS 28.98608884 41.36639682
OS 28.98989122 41.35752206
OS 28.99306114 41.3492823
OS 29.0013009 41.34104508
OS 29.00510328 41.33470524
OS 29.01144312 41.32836794
OS 29.0152455 41.31949318
OS 29.01651296 41.31442334
OS 29.0228528 41.30554858
OS 29.02412026 41.30301366
OS 29.02665518 41.29667636
OS 29.02982256 41.2884366
OS 29.0348924 41.28083184
OS 29.03806232 41.27385954
OS 29.04123224 41.26561978
OS 29.04439962 41.2611824
OS 29.05073946 41.25484256
OS 29.05454184 41.24850526
OS 29.06088168 41.24216796
OS 29.06531652 41.23012328
OS 29.07165636 41.2199836
OS 29.07482628 41.21174384
OS 29.08116358 41.20033416
OS 29.08623342 41.19526432
OS 29.08750342 41.1927294
OS 29.09320572 41.1857571
OS 29.0963731 41.18258718
OS 29.09764056 41.18005226
OS 29.10017802 41.17371242
OS 29.10144548 41.16864258
OS 29.10588286 41.16294028
OS 29.10841778 41.16167282
OS 29.1109527 41.1591379
OS 29.11348762 41.15787044
OS 29.11602254 41.15533552
OS 29.1248973 41.15406552
OS 29.16229118 41.1521656
OS 29.16989848 41.15089814
OS 29.18828046 41.15026314
OS 29.19208284 41.1515306
OS 29.19715268 41.15026314
OS 29.38729962 41.1515306
OS 29.38919954 41.15343306
OS 29.390467 41.1585029
OS 29.38919954 41.16864258
OS 29.38286478 41.17751734
OS 29.38032732 41.18385464
OS 29.37715994 41.1920944
OS 29.37525748 41.19399686
OS 29.37399002 41.19653178
OS 29.36892018 41.20160416
OS 29.36765018 41.20413908
OS 29.36194788 41.21111138
OS 29.3575105 41.21554876
OS 29.35307312 41.22758836
OS 29.3499032 41.23202574
OS 29.34610082 41.23582812
OS 29.34483336 41.23836304
OS 29.33912852 41.2466028
OS 29.33722606 41.2472378
OS 29.3365936 41.24914026
OS 29.33469114 41.24977272
OS 29.33342368 41.25230764
OS 29.33088876 41.25864748
OS 29.32772138 41.26688724
OS 29.32581892 41.2687897
OS 29.32455146 41.27132462
OS 29.32201654 41.27385954
OS 29.3163117 41.28970406
OS 29.3093394 41.29667636
OS 29.30807194 41.29921128
OS 29.29919718 41.31062096
OS 29.29666226 41.31315588
OS 29.29412734 41.31949318
OS 29.29285988 41.32456556
OS 29.28398512 41.33851016
OS 29.27954774 41.35054976
OS 29.27638036 41.35498714
OS 29.27384544 41.3562546
OS 29.27257544 41.35878952
OS 29.27004052 41.36132444
OS 29.26624068 41.36766428
OS 29.25990084 41.37400158
OS 29.255466 41.38604626
OS 29.24912616 41.39618594
OS 29.24595624 41.40442824
OS 29.24342132 41.410763
OS 29.23771648 41.4177353
OS 29.2345491 41.42090522
OS 29.23074418 41.42724252
OS 29.22440688 41.43358236
OS 29.22187196 41.43991966
OS 29.21870204 41.44815942
OS 29.21553212 41.4525968
OS 29.21046228 41.4602041
OS 29.20855982 41.46717386
OS 29.20602744 41.47351116
OS 29.2003226 41.48428838
OS 29.19778768 41.4931606
OS 29.19905514 41.51851488
OS 29.20539244 41.5273871
OS 29.2079299 41.52992202
OS 29.21172974 41.53625932
OS 29.21489966 41.53942924
OS 29.21679958 41.54006424
OS 29.21743458 41.5406967
OS 29.2206045 41.54386662
OS 29.22187196 41.54640154
OS 29.2275768 41.55210638
OS 29.23011172 41.55337384
OS 29.2332791 41.55654376
OS 29.2345491 41.55907868
OS 29.2402514 41.56478352
OS 29.24278886 41.56605098
OS 29.24468878 41.56795344
OS 29.24595624 41.57048836
OS 29.25166108 41.5761932
OS 29.25419854 41.57746066
OS 29.25736592 41.58063058
OS 29.25863338 41.5831655
OS 29.26433822 41.5888678
OS 29.26687314 41.59013526
OS 29.26877306 41.59203772
OS 29.27004052 41.59457264
OS 29.27574536 41.60027748
OS 29.27828028 41.60154494
OS 29.2814502 41.60471486
OS 29.28271766 41.60724978
OS 29.2884225 41.61295462
OS 29.29095742 41.61422208
OS 29.29412734 41.617392
OS 29.2953948 41.61992692
OS 29.30109964 41.62563176
OS 29.30363456 41.62689922
OS 29.30553702 41.62879914
OS 29.30680448 41.6313366
OS 29.31250932 41.6370389
OS 29.31504424 41.6383089
OS 29.31821416 41.64147628
OS 29.31948162 41.6440112
OS 29.32518646 41.6497135
OS 29.32772138 41.6509835
OS 29.33088876 41.65415088
OS 29.33215622 41.6566858
OS 29.3365936 41.66112318
OS 29.33912852 41.66239064
OS 29.3435659 41.66682802
OS 29.34483336 41.66936294
OS 29.3505382 41.67633524
OS 29.35243812 41.6782377
OS 29.35497558 41.68457754
OS 29.35624304 41.68964738
OS 29.36131288 41.70105706
OS 29.36258034 41.70612436
OS 29.3644828 41.73591602
OS 29.36638272 41.7733099
OS 29.36701772 41.822116
OS 29.36638272 41.822751
OS 29.36765018 41.82655084
OS 29.36701772 41.9856412
OS 29.36765018 41.99515096
OS 29.36638272 41.99895334
OS 29.36511526 42.07247364
OS 29.3638478 42.07627856
OS 29.36194788 42.10606768
OS 29.35624304 42.11937982
OS 29.35307312 42.12761704
OS 29.34863574 42.13458934
OS 29.34483336 42.13839172
OS 29.3435659 42.14092918
OS 29.3365936 42.14790148
OS 29.33405868 42.14916894
OS 29.33215622 42.15106886
OS 29.33088876 42.15360378
OS 29.323919 42.16057608
OS 29.32138408 42.16184608
OS 29.31948162 42.163746
OS 29.31821416 42.16628092
OS 29.29856472 42.18592782
OS 29.29666226 42.18656282
OS 29.2953948 42.18909774
OS 29.28715504 42.1973375
OS 29.28462012 42.19860496
OS 29.2814502 42.20304234
OS 29.27574536 42.20874718
OS 29.27321044 42.21001464
OS 29.27130798 42.2119171
OS 29.27004052 42.21445202
OS 29.26307076 42.22142432
OS 29.26053584 42.22269178
OS 29.25863338 42.22459424
OS 29.25736592 42.22712916
OS 29.23898394 42.2455086
OS 29.23644902 42.24677606
OS 29.2345491 42.24867852
OS 29.2332791 42.25121344
OS 29.2263068 42.25818574
OS 29.22377188 42.2594532
OS 29.21743458 42.26705796
OS 29.21489966 42.26959542
OS 29.2123622 42.27086288
OS 29.20602744 42.27720018
OS 29.20349252 42.27846764
OS 29.19461776 42.28227256
OS 29.186378 42.28543994
OS 29.1800407 42.28797486
OS 29.1724334 42.28924486
OS 29.14454674 42.29051232
OS 29.10715032 42.29241224
OS 29.00320336 42.2936797
OE
OB 25.69464508 42.29241224 H
OS 25.6845054 42.29114478
OS 25.68260294 42.28924486
OS 25.68006802 42.28290502
OS 25.68196794 42.1973375
OS 25.6832354 42.1707183
OS 25.6845054 42.14916894
OS 25.68577286 42.13902672
OS 25.68704032 42.13395688
OS 25.68830778 42.12761704
OS 25.68957524 42.12001228
OS 25.6914777 42.1029003
OS 25.69274516 42.09402554
OS 25.69401262 42.07374364
OS 25.69718 42.0553642
OS 25.69908246 42.0483919
OS 25.7041523 42.02810746
OS 25.7054223 42.01543032
OS 25.70668976 42.00148826
OS 25.70922468 41.99515096
OS 25.71302706 41.98120636
OS 25.71429452 41.97613398
OS 25.71682944 41.96092192
OS 25.7187319 41.94507486
OS 25.71999936 41.9387401
OS 25.72126682 41.93367026
OS 25.7257042 41.91909066
OS 25.72697166 41.91402082
OS 25.72950404 41.8962713
OS 25.7314065 41.88169678
OS 25.73267396 41.87535694
OS 25.73647634 41.86521472
OS 25.7383788 41.85824242
OS 25.74091372 41.84810274
OS 25.74218118 41.8354256
OS 25.74408364 41.82718584
OS 25.74852102 41.81641116
OS 25.7523234 41.80753894
OS 25.75359086 41.79866418
OS 25.75485832 41.79359434
OS 25.75802824 41.78535458
OS 25.76373308 41.77204244
OS 25.766268 41.76317022
OS 25.76753546 41.754298
OS 25.77514276 41.73781594
OS 25.77767768 41.72894372
OS 25.7802126 41.71753404
OS 25.78655244 41.70359198
OS 25.78908482 41.69471722
OS 25.79035228 41.68964738
OS 25.79225474 41.68140762
OS 25.79859204 41.66746302
OS 25.8004945 41.66175818
OS 25.80302942 41.65161596
OS 25.80429688 41.6440112
OS 25.81063418 41.63387152
OS 25.8138041 41.62563176
OS 25.82014394 41.61168716
OS 25.82584878 41.59837502
OS 25.8277487 41.58760034
OS 25.83091862 41.57936312
OS 25.83979338 41.56034614
OS 25.84993052 41.53879678
OS 25.85119798 41.52992202
OS 25.85310044 41.52295226
OS 25.85880528 41.51217758
OS 25.86260766 41.50330282
OS 25.92472336 41.3778065
OS 25.92852574 41.37146666
OS 25.93486558 41.36512936
OS 25.93613304 41.36259444
OS 25.94183788 41.35562214
OS 25.9437378 41.35371968
OS 25.94500526 41.35118476
OS 25.95007764 41.33977762
OS 25.95514748 41.33090286
OS 25.96148732 41.31695826
OS 25.96782462 41.30554858
OS 25.97289446 41.2941389
OS 25.9779643 41.28526668
OS 25.9843016 41.27892938
OS 25.98556906 41.27639446
OS 25.9912739 41.26942216
OS 25.99444382 41.26625224
OS 25.99697874 41.25991494
OS 25.9982462 41.25484256
OS 26.00712096 41.24089796
OS 26.00838842 41.23582812
OS 26.01472826 41.22442098
OS 26.0197981 41.21935114
OS 26.02106556 41.21681622
OS 26.03627508 41.20160416
OS 26.03754254 41.1990667
OS 26.04134746 41.19526432
OS 26.04261492 41.1927294
OS 26.04514984 41.18638956
OS 26.05148714 41.17498242
OS 26.05782698 41.16864258
OS 26.05909444 41.16610766
OS 26.06289682 41.16230782
OS 26.06416428 41.15977036
OS 26.0679692 41.15596798
OS 26.07240404 41.14392584
OS 26.07874388 41.13631854
OS 26.0819138 41.13188116
OS 26.08444872 41.12934624
OS 26.08508118 41.12744632
OS 26.08761864 41.12617632
OS 26.09585586 41.11793656
OS 26.09712332 41.11540164
OS 26.10219316 41.1103318
OS 26.10346062 41.10779688
OS 26.10726554 41.09892466
OS 26.108533 41.09512228
OS 26.11423784 41.08814998
OS 26.11740522 41.08498006
OS 26.11867268 41.08244514
OS 26.14656188 41.05455594
OS 26.14783188 41.05201848
OS 26.15163172 41.0482161
OS 26.15289918 41.04568118
OS 26.15796902 41.03300658
OS 26.16430886 41.02666674
OS 26.16557632 41.02413182
OS 26.17128116 41.01715952
OS 26.17825346 41.01145468
OS 26.1839583 41.00448238
OS 26.1909306 40.99877754
OS 26.19219806 40.99624262
OS 26.19663544 40.99180524
OS 26.19917036 40.99053778
OS 26.2048752 40.98483294
OS 26.20614266 40.98230056
OS 26.20804258 40.98040064
OS 26.2105775 40.97913064
OS 26.3747377 40.81497044
OS 26.3760077 40.81243552
OS 26.37790762 40.81053306
OS 26.38044254 40.8092656
OS 26.38614738 40.8035633
OS 26.38741484 40.80102838
OS 26.39184968 40.796591
OS 26.3943846 40.79532354
OS 26.39755452 40.79215362
OS 26.39882198 40.7896187
OS 26.40452682 40.78391386
OS 26.40706174 40.7826464
OS 26.41023166 40.77947648
OS 26.41149912 40.77694156
OS 26.4159365 40.77250418
OS 26.41847142 40.77123672
OS 26.4229088 40.76679934
OS 26.42417626 40.76426442
OS 26.42734618 40.7610945
OS 26.4298811 40.75982704
OS 26.43241602 40.75729212
OS 26.43495094 40.75602466
OS 26.44002332 40.75095228
OS 26.44636062 40.74841736
OS 26.45143046 40.7471499
OS 26.45396538 40.74461498
OS 26.4565003 40.74335006
OS 26.45903522 40.74081514
OS 26.46157014 40.73954768
OS 26.4780522 40.72306562
OS 26.48058712 40.72179816
OS 26.48692442 40.71546086
OS 26.48945934 40.7141934
OS 26.49579918 40.71165848
OS 26.50086902 40.71038848
OS 26.50340648 40.70785356
OS 26.5059414 40.7065861
OS 26.5110087 40.70151626
OS 26.51354362 40.7002488
OS 26.52305338 40.69073904
OS 26.52368584 40.68883912
OS 26.52622076 40.68757166
OS 26.53319306 40.68186936
OS 26.53763044 40.67743198
OS 26.54460274 40.67552952
OS 26.55094258 40.6729946
OS 26.55410996 40.66982468
OS 26.55664488 40.66855722
OS 26.56171726 40.66348738
OS 26.56425218 40.66221992
OS 26.56932202 40.65714754
OS 26.57185694 40.65588008
OS 26.57439186 40.65334516
OS 26.58072916 40.65081024
OS 26.58896892 40.64764032
OS 26.5934063 40.64320294
OS 26.59594122 40.64193548
OS 26.61242328 40.62545596
OS 26.6149582 40.62419104
OS 26.6212955 40.6178512
OS 26.63016772 40.61404882
OS 26.63523756 40.61278136
OS 26.64411232 40.60644406
OS 26.65045216 40.6039066
OS 26.65869192 40.60073922
OS 26.66629668 40.59439938
OS 26.66819914 40.59249946
OS 26.67073406 40.591232
OS 26.67770636 40.58552716
OS 26.68087628 40.58235724
OS 26.6834112 40.58108978
OS 26.69228342 40.5772874
OS 26.70622802 40.5696801
OS 26.7176377 40.5646128
OS 26.72904484 40.55827296
OS 26.7379196 40.55447058
OS 26.74932674 40.54813074
OS 26.75439658 40.5430609
OS 26.7569315 40.54179344
OS 26.7639038 40.5360886
OS 26.76834118 40.53165122
OS 26.77658094 40.5284813
OS 26.78292078 40.52594638
OS 26.792428 40.52024154
OS 26.79876784 40.51770662
OS 26.90397972 40.46573314
OS 26.9229967 40.45686092
OS 26.93440384 40.45559092
OS 26.96102558 40.44291632
OS 26.98004002 40.4340441
OS 26.98510986 40.43277664
OS 26.99841946 40.42960672
OS 27.02694366 40.41629712
OS 27.04342318 40.40868982
OS 27.05419532 40.40678736
OS 27.05926516 40.4055199
OS 27.06624 40.40234998
OS 27.06877492 40.40108252
OS 27.07764714 40.39728014
OS 27.09539666 40.39347776
OS 27.10933872 40.38713792
OS 27.12201586 40.38333808
OS 27.12962062 40.38207062
OS 27.13596046 40.3795357
OS 27.14990506 40.37319586
OS 27.1549749 40.3719284
OS 27.16384966 40.37066094
OS 27.17018442 40.36812602
OS 27.18412902 40.36178618
OS 27.19427124 40.35925126
OS 27.20377846 40.35735134
OS 27.22089298 40.35037904
OS 27.23103266 40.34784158
OS 27.24560972 40.34594166
OS 27.25575194 40.34340674
OS 27.26209178 40.34086928
OS 27.27286646 40.3377019
OS 27.2906109 40.33516444
OS 27.30265558 40.33326452
OS 27.31279526 40.33199706
OS 27.31786764 40.3307296
OS 27.3261074 40.32755968
OS 27.33434716 40.32565722
OS 27.34068446 40.3243923
OS 27.34829176 40.32312484
OS 27.35843144 40.32185738
OS 27.37491096 40.31932246
OS 27.3799808 40.318055
OS 27.38822056 40.31488508
OS 27.39646286 40.31298262
OS 27.40280016 40.31171516
OS 27.41674222 40.3104477
OS 27.43068682 40.30791278
OS 27.4357592 40.30664532
OS 27.4420965 40.30537786
OS 27.4490688 40.3034754
OS 27.45921102 40.30094048
OS 27.47188562 40.29967302
OS 27.49406998 40.29777056
OS 27.50547966 40.2965031
OS 27.52195918 40.29396818
OS 27.53463378 40.29143326
OS 27.54604346 40.2901658
OS 27.57393266 40.28889834
OS 27.59040964 40.28762834
OS 27.6601301 40.28636088
OS 27.87246394 40.28572842
OS 27.87626632 40.28699588
OS 27.95992884 40.28826334
OS 27.96373122 40.2895308
OS 27.99922772 40.29079826
OS 28.0030301 40.29206572
OS 28.01126732 40.29396818
OS 28.0372566 40.2971381
OS 28.04613136 40.29840556
OS 28.06261088 40.29967302
OS 28.0778204 40.30094048
OS 28.08162278 40.30220794
OS 28.08669516 40.3034754
OS 28.09556738 40.30601032
OS 28.10253968 40.30791278
OS 28.10887952 40.30918024
OS 28.1259915 40.3110827
OS 28.13803364 40.31298262
OS 28.14310348 40.31425008
OS 28.15007578 40.31615254
OS 28.15641562 40.31868746
OS 28.16528784 40.31995492
OS 28.17036022 40.32122238
OS 28.18620474 40.32312484
OS 28.1938095 40.3243923
OS 28.20014934 40.32565722
OS 28.21028902 40.32819214
OS 28.22106624 40.33136206
OS 28.22613608 40.33262952
OS 28.24388306 40.33516444
OS 28.25846012 40.3370669
OS 28.26479742 40.33833436
OS 28.27113726 40.34086928
OS 28.28571432 40.34530666
OS 28.2907867 40.34657412
OS 28.30663122 40.34847658
OS 28.31170106 40.34974404
OS 28.32184328 40.35354642
OS 28.33261796 40.3579838
OS 28.35036494 40.36178618
OS 28.36430954 40.36812602
OS 28.37064684 40.37066094
OS 28.37951906 40.3719284
OS 28.38459144 40.37319586
OS 28.39853604 40.3795357
OS 28.40487334 40.38207062
OS 28.41945294 40.385238
OS 28.42959262 40.38904038
OS 28.43656492 40.3922103
OS 28.44290222 40.39474522
OS 28.4536769 40.39664768
OS 28.45874928 40.39791514
OS 28.47142642 40.40425244
OS 28.47649626 40.4055199
OS 28.48346856 40.40742236
OS 28.49677816 40.41059228
OS 28.50628538 40.41629712
OS 28.51452514 40.4194645
OS 28.52149744 40.42263442
OS 28.54051188 40.43150918
OS 28.55318648 40.43277664
OS 28.56459616 40.43911394
OS 28.57600584 40.44418632
OS 28.58234314 40.4467187
OS 28.60136012 40.45559092
OS 28.61023234 40.45686092
OS 28.61720464 40.45876084
OS 28.63051424 40.46573314
OS 28.63685408 40.46826806
OS 28.70150216 40.50122964
OS 28.71037692 40.50502948
OS 28.72685644 40.51390424
OS 28.73572866 40.51770662
OS 28.74967326 40.52531392
OS 28.75854802 40.5291163
OS 28.76995516 40.5354536
OS 28.776295 40.54179344
OS 28.7826323 40.54559582
OS 28.78770468 40.55066566
OS 28.79657436 40.55447058
OS 28.8029142 40.5570055
OS 28.81051896 40.56207534
OS 28.81939372 40.56587772
OS 28.82573356 40.56841264
OS 28.83270586 40.57411748
OS 28.83460578 40.5760174
OS 28.8371407 40.5772874
OS 28.83967816 40.57982232
OS 28.84221308 40.58108978
OS 28.84854784 40.58742708
OS 28.86122498 40.59249946
OS 28.8637599 40.59376692
OS 28.87390212 40.60010422
OS 28.8859468 40.6045416
OS 28.89608648 40.6108789
OS 28.90305878 40.61404882
OS 28.91129854 40.61721874
OS 28.91319846 40.6191212
OS 28.91573338 40.62038866
OS 28.92207322 40.62672342
OS 28.92460814 40.62799088
OS 28.94108766 40.64447294
OS 28.94362258 40.6457404
OS 28.94616004 40.64827532
OS 28.95249734 40.65081024
OS 28.9607371 40.65398016
OS 28.9677094 40.66095246
OS 28.97024178 40.66221992
OS 28.98165146 40.67109214
OS 28.98418638 40.6736296
OS 28.99623106 40.67806444
OS 29.00066844 40.68123436
OS 29.00573828 40.6863042
OS 29.0082732 40.68757166
OS 29.02348526 40.70278372
OS 29.02602018 40.70405118
OS 29.03109002 40.70912102
OS 29.03742732 40.71165848
OS 29.04566962 40.71482586
OS 29.04756954 40.71672832
OS 29.05010446 40.71799578
OS 29.0564443 40.72433308
OS 29.05897922 40.72560308
OS 29.06721898 40.73384284
OS 29.06848644 40.73637776
OS 29.07292382 40.73954768
OS 29.07609374 40.74271506
OS 29.0773612 40.74524998
OS 29.08053112 40.74841736
OS 29.08306604 40.74968482
OS 29.08686842 40.75348974
OS 29.0894008 40.7547572
OS 29.09320572 40.75855958
OS 29.10715032 40.76362942
OS 29.11348762 40.76996926
OS 29.11602254 40.77123672
OS 29.12299484 40.77694156
OS 29.1242623 40.77947648
OS 29.12996714 40.78518132
OS 29.13250206 40.78644878
OS 29.13567198 40.7896187
OS 29.13693944 40.79215362
OS 29.14264428 40.79785846
OS 29.1451792 40.79912592
OS 29.14708166 40.80102838
OS 29.14834658 40.8035633
OS 29.15531888 40.81053306
OS 29.1578538 40.81180052
OS 29.16165872 40.8156029
OS 29.16419364 40.81687036
OS 29.16672856 40.81940782
OS 29.1787707 40.82384266
OS 29.18320808 40.82701258
OS 29.18828046 40.83208242
OS 29.19081538 40.83335242
OS 29.19778768 40.84032472
OS 29.19905514 40.84285964
OS 29.20539244 40.84919694
OS 29.2066599 40.85173186
OS 29.20919482 40.8580717
OS 29.21046228 40.86314154
OS 29.21616712 40.8701113
OS 29.22503934 40.87898606
OS 29.23137918 40.88152098
OS 29.23961894 40.8846909
OS 29.24405632 40.88786082
OS 29.24912616 40.89293066
OS 29.25166108 40.89419812
OS 29.25863338 40.90117042
OS 29.25990084 40.90370534
OS 29.26750814 40.91131264
OS 29.27004052 40.92145486
OS 29.27384544 40.92778962
OS 29.27574536 40.92969208
OS 29.28081774 40.93095954
OS 29.28779004 40.932862
OS 29.28968996 40.93476192
OS 29.29222488 40.93602938
OS 29.29729726 40.94110176
OS 29.29983218 40.94236922
OS 29.30807194 40.95060898
OS 29.3093394 40.9531439
OS 29.31567924 40.9594812
OS 29.31821416 40.96582104
OS 29.32138408 40.9740608
OS 29.32581892 40.98230056
OS 29.32455146 40.9873704
OS 29.31884662 40.98927032
OS 29.31124186 40.98800286
OS 29.30616948 40.98293556
OS 29.30363456 40.9816681
OS 29.30109964 40.97913064
OS 29.29856472 40.97786318
OS 29.2953948 40.9746958
OS 29.29412734 40.97215834
OS 29.2884225 40.9664535
OS 29.28588758 40.96518604
OS 29.28271766 40.96201866
OS 29.2814502 40.9594812
OS 29.2744779 40.9525089
OS 29.27194298 40.95124144
OS 29.27004052 40.94934152
OS 29.26877306 40.9468066
OS 29.25166108 40.92969208
OS 29.24976116 40.92905708
OS 29.2484937 40.92652216
OS 29.2402514 40.91828494
OS 29.23771648 40.91701748
OS 29.2345491 40.91384756
OS 29.2332791 40.91131264
OS 29.2263068 40.90434034
OS 29.22377188 40.90307288
OS 29.22187196 40.90117042
OS 29.2206045 40.8986355
OS 29.19208284 40.8701113
OS 29.18954792 40.86884384
OS 29.186378 40.86567646
OS 29.18511054 40.86314154
OS 29.1794057 40.8574367
OS 29.17687078 40.85616924
OS 29.17370086 40.85300186
OS 29.1724334 40.8504644
OS 29.16672856 40.84475956
OS 29.16419364 40.8434921
OS 29.16165872 40.84095718
OS 29.15912126 40.83968972
OS 29.15405142 40.83461988
OS 29.1451792 40.83208242
OS 29.1388419 40.82828004
OS 29.13250206 40.82194274
OS 29.12996714 40.82067528
OS 29.12552976 40.81750536
OS 29.1242623 40.81497044
OS 29.07355882 40.76426442
OS 29.07292382 40.76236196
OS 29.0703889 40.7610945
OS 29.06658652 40.75729212
OS 29.06404906 40.75602466
OS 29.05897922 40.75095228
OS 29.0564443 40.74968482
OS 29.05010446 40.7471499
OS 29.04503462 40.74588244
OS 29.04123224 40.7420826
OS 29.03932978 40.7414476
OS 29.03869732 40.73954768
OS 29.03615986 40.73827768
OS 29.03362494 40.73574276
OS 29.03109002 40.7344753
OS 29.02538772 40.72877046
OS 29.02412026 40.72623554
OS 29.02095034 40.72306562
OS 29.01841542 40.72179816
OS 29.01334558 40.71672832
OS 29.01080812 40.71546086
OS 29.0082732 40.71292594
OS 29.00320336 40.71165848
OS 28.9949636 40.70848856
OS 28.9879913 40.70151626
OS 28.98545638 40.7002488
OS 28.97848408 40.69454396
OS 28.97531416 40.69137404
OS 28.97277924 40.69010658
OS 28.96390702 40.6863042
OS 28.95503226 40.68123436
OS 28.94869496 40.67489706
OS 28.94616004 40.6736296
OS 28.92967798 40.65714754
OS 28.92714306 40.65588008
OS 28.92460814 40.65334516
OS 28.91827084 40.65081024
OS 28.91002854 40.64764032
OS 28.90305878 40.64066802
OS 28.90052386 40.63940056
OS 28.89355156 40.63369572
OS 28.89165164 40.6317958
OS 28.88911418 40.63052834
OS 28.88657926 40.62799088
OS 28.87453712 40.62355604
OS 28.87009974 40.62038866
OS 28.86629736 40.61658374
OS 28.8637599 40.61531628
OS 28.86122498 40.61278136
OS 28.85869006 40.6115139
OS 28.85235276 40.6051766
OS 28.8498153 40.6039066
OS 28.84094562 40.60010422
OS 28.8168588 40.58869454
OS 28.80798404 40.5836247
OS 28.7686877 40.5646128
OS 28.7623504 40.56080788
OS 28.75728056 40.55573804
OS 28.7547431 40.55447058
OS 28.75220818 40.55193566
OS 28.74967326 40.55066566
OS 28.74587088 40.54686328
OS 28.74333342 40.54559582
OS 28.7407985 40.5430609
OS 28.73255874 40.53989098
OS 28.72622398 40.53735606
OS 28.71798422 40.53165122
OS 28.71164438 40.5291163
OS 28.70340462 40.52594638
OS 28.69579732 40.52087654
OS 28.68882502 40.51770662
OS 28.68058526 40.5145367
OS 28.67044558 40.5081994
OS 28.66347328 40.50502948
OS 28.65713598 40.5024971
OS 28.6457263 40.49615726
OS 28.63431662 40.49108742
OS 28.61276726 40.4809452
OS 28.60072512 40.47904528
OS 28.59438782 40.47650782
OS 28.56142624 40.4600283
OS 28.54558426 40.453056
OS 28.52656728 40.44418632
OS 28.5151576 40.44291632
OS 28.49867808 40.43531156
OS 28.49234078 40.43277664
OS 28.48346856 40.43150918
OS 28.4676215 40.42580434
OS 28.4543119 40.4200995
OS 28.44543714 40.41883204
OS 28.4403673 40.41756458
OS 28.42262286 40.40995728
OS 28.41628302 40.40742236
OS 28.40424088 40.4055199
OS 28.39790104 40.40298498
OS 28.38205652 40.39601268
OS 28.36240962 40.3915753
OS 28.35670478 40.38840538
OS 28.35036494 40.38587046
OS 28.34149272 40.38333808
OS 28.33642034 40.38207062
OS 28.32944804 40.38016816
OS 28.32311074 40.37763324
OS 28.31613844 40.37573078
OS 28.31550344 40.37509832
OS 28.30853114 40.37319586
OS 28.30346384 40.3719284
OS 28.28698178 40.37066094
OS 28.28191194 40.36939348
OS 28.2698698 40.36749102
OS 28.26479742 40.36622356
OS 28.25846012 40.36368864
OS 28.24768544 40.36051872
OS 28.2426156 40.35925126
OS 28.23374084 40.3579838
OS 28.2216987 40.35608388
OS 28.2077541 40.3510115
OS 28.2007818 40.34911158
OS 28.19063958 40.34657412
OS 28.17226014 40.34340674
OS 28.1671903 40.34213674
OS 28.160853 40.33960182
OS 28.15578062 40.33833436
OS 28.14817586 40.3370669
OS 28.13803364 40.33579944
OS 28.13042634 40.33453198
OS 28.1190192 40.33326452
OS 28.09366746 40.32946214
OS 28.08669516 40.32755968
OS 28.0778204 40.32629222
OS 28.07275056 40.32502476
OS 28.04993374 40.32375984
OS 28.04613136 40.32248984
OS 28.0036651 40.32058992
OS 27.99098796 40.31932246
OS 27.97957828 40.318055
OS 27.97197098 40.31678754
OS 27.96563368 40.31551754
OS 27.95549146 40.31425008
OS 27.94028194 40.31298262
OS 27.92000004 40.31171516
OS 27.87563132 40.3104477
OS 27.86485664 40.30981524
OS 27.86105426 40.3110827
OS 27.82936014 40.30981524
OS 27.66646994 40.3104477
OS 27.66203256 40.30981524
OS 27.65823018 40.3110827
OS 27.65442526 40.30981524
OS 27.6341459 40.3110827
OS 27.5986494 40.31235016
OS 27.59484702 40.31361762
OS 27.56949528 40.31488508
OS 27.5656929 40.31615254
OS 27.55681814 40.31742
OS 27.5517483 40.31868746
OS 27.53146386 40.31995492
OS 27.5105495 40.32185738
OS 27.48519522 40.32312484
OS 27.475053 40.3243923
OS 27.45857602 40.32565722
OS 27.44463142 40.32819214
OS 27.43765912 40.3300946
OS 27.40723754 40.33389698
OS 27.3806158 40.3377019
OS 27.37554596 40.33896936
OS 27.3666712 40.34150428
OS 27.35652898 40.3440392
OS 27.34448938 40.34594166
OS 27.32737486 40.34784158
OS 27.31406272 40.3510115
OS 27.30709042 40.35418142
OS 27.29441582 40.3579838
OS 27.28617606 40.35988626
OS 27.28110622 40.36115372
OS 27.27413392 40.36432364
OS 27.26779408 40.36685856
OS 27.25258202 40.36939348
OS 27.23990488 40.37066094
OS 27.23103266 40.3719284
OS 27.22279544 40.37383086
OS 27.20885084 40.3789007
OS 27.19807362 40.38207062
OS 27.18983386 40.38397308
OS 27.18476402 40.385238
OS 27.17779172 40.38840538
OS 27.16638458 40.39347776
OS 27.15434244 40.39537768
OS 27.14420022 40.3991826
OS 27.13088808 40.40488744
OS 27.12581824 40.4061549
OS 27.1125061 40.40932228
OS 27.09856404 40.41566212
OS 27.08778936 40.41883204
OS 27.07828214 40.42073196
OS 27.0719423 40.42326942
OS 27.0586327 40.42897172
OS 27.04849302 40.43150918
OS 27.04088826 40.43277664
OS 27.01172906 40.4467187
OS 26.99524954 40.45432346
OS 26.98637732 40.45559092
OS 26.98130748 40.45686092
OS 26.95722066 40.46826806
OS 26.95088336 40.47080552
OS 26.93440384 40.47841028
OS 26.92933146 40.47967774
OS 26.91982678 40.4815802
OS 26.91348948 40.48411512
OS 26.90397972 40.48981996
OS 26.89573996 40.49298988
OS 26.88940266 40.4955248
OS 26.88179536 40.50059464
OS 26.87545806 40.50312956
OS 26.861516 40.50946686
OS 26.85961354 40.51136932
OS 26.85707862 40.51263678
OS 26.84566894 40.51770662
OS 26.83425926 40.52404646
OS 26.82284958 40.5291163
OS 26.80890498 40.53672106
OS 26.79749784 40.54179344
OS 26.79116054 40.54559582
OS 26.78418824 40.55130066
OS 26.7784834 40.55573804
OS 26.77594848 40.5570055
OS 26.76960864 40.5633428
OS 26.76263634 40.56524272
OS 26.75503158 40.5690451
OS 26.7455269 40.57474994
OS 26.73918706 40.5772874
OS 26.7100304 40.591232
OS 26.70749548 40.59249946
OS 26.70496056 40.59503438
OS 26.7024231 40.59630184
OS 26.69735326 40.60137168
OS 26.69481834 40.60263914
OS 26.68784858 40.60834398
OS 26.68467866 40.6115139
OS 26.67834136 40.61404882
OS 26.67326898 40.61531628
OS 26.66629668 40.62102112
OS 26.66312676 40.62419104
OS 26.66059184 40.62545596
OS 26.65361954 40.6311608
OS 26.65045216 40.63433072
OS 26.6479147 40.63559818
OS 26.63523756 40.64066802
OS 26.63270264 40.64193548
OS 26.62383042 40.64827532
OS 26.61876058 40.64954278
OS 26.6073509 40.65588008
OS 26.6003786 40.66158492
OS 26.59594122 40.66475484
OS 26.59087138 40.66982468
OS 26.58833646 40.67109214
OS 26.57692678 40.67616452
OS 26.57439186 40.67743198
OS 26.5674221 40.68313682
OS 26.56298472 40.6863042
OS 26.54777266 40.70151626
OS 26.54523774 40.70278372
OS 26.5388979 40.70912102
OS 26.53002568 40.71165848
OS 26.52115092 40.71672832
OS 26.51608108 40.72179816
OS 26.51354362 40.72306562
OS 26.50657386 40.73003792
OS 26.5053064 40.73257538
OS 26.50340648 40.7344753
OS 26.50086902 40.73574276
OS 26.4983341 40.73827768
OS 26.49579918 40.73954768
OS 26.48945934 40.74588244
OS 26.48058712 40.74841736
OS 26.47424728 40.75222228
OS 26.4704449 40.75602466
OS 26.46790998 40.75729212
OS 26.46537506 40.75982704
OS 26.46284014 40.7610945
OS 26.46093768 40.76299696
OS 26.45967022 40.76553188
OS 26.43875586 40.78644878
OS 26.4368534 40.78708378
OS 26.43558594 40.7896187
OS 26.40325936 40.82194274
OS 26.40072444 40.8232102
OS 26.3943846 40.8295475
OS 26.39184968 40.83081496
OS 26.38804984 40.83208242
OS 26.37981008 40.83525234
OS 26.37220278 40.84159218
OS 26.3677654 40.84475956
OS 26.23656424 40.97596326
OS 26.23529678 40.97849818
OS 26.23022694 40.98356802
OS 26.22769202 40.98990532
OS 26.22578956 40.99687762
OS 26.2238871 40.99877754
OS 26.22261964 41.001315
OS 26.21628234 41.0076523
OS 26.21501488 41.01018722
OS 26.18269084 41.0425138
OS 26.18078838 41.0431488
OS 26.17952092 41.04568118
OS 26.1624064 41.0627957
OS 26.15987148 41.06406316
OS 26.15416664 41.069768
OS 26.15289918 41.07230292
OS 26.15036426 41.07483784
OS 26.1490968 41.07737276
OS 26.14529442 41.08117768
OS 26.14402696 41.0837126
OS 26.14149204 41.0900499
OS 26.14022458 41.09512228
OS 26.13261728 41.10272704
OS 26.13134982 41.10525942
OS 26.12564498 41.11223172
OS 26.12311006 41.11349918
OS 26.11613776 41.12047402
OS 26.1148703 41.12300894
OS 26.10980046 41.12807878
OS 26.108533 41.1306137
OS 26.10599554 41.13695354
OS 26.10282816 41.1451933
OS 26.09585586 41.1521656
OS 26.0945884 41.15470052
OS 26.07810888 41.1711775
OS 26.07684142 41.17371242
OS 26.07303904 41.17751734
OS 26.07177158 41.18005226
OS 26.06923666 41.18638956
OS 26.06416428 41.19526432
OS 26.0603619 41.1990667
OS 26.05909444 41.20160416
OS 26.05655952 41.20413908
OS 26.05529206 41.206674
OS 26.04895222 41.2130113
OS 26.04768476 41.21554876
OS 26.04514984 41.22188606
OS 26.04197992 41.23012328
OS 26.03881 41.23456066
OS 26.03374016 41.24216796
OS 26.0318377 41.24914026
OS 26.02993778 41.2535751
OS 26.02423548 41.2605474
OS 26.02106556 41.26371732
OS 26.0197981 41.26625224
OS 26.01726318 41.2687897
OS 26.01599572 41.27132462
OS 26.01092334 41.27639446
OS 26.00838842 41.2827343
OS 26.00712096 41.2878016
OS 26.00141612 41.2947739
OS 25.9982462 41.29794382
OS 25.99697874 41.30047874
OS 25.9912739 41.30745104
OS 25.98937398 41.3093535
OS 25.98810652 41.31188842
OS 25.98556906 41.31442334
OS 25.9843016 41.31949318
OS 25.96275478 41.36132444
OS 25.95894986 41.3701992
OS 25.95388002 41.37907396
OS 25.94881018 41.3841438
OS 25.94754272 41.38667872
OS 25.94183788 41.39365102
OS 25.93993542 41.39555348
OS 25.93866796 41.3980884
OS 25.93359812 41.40949554
OS 25.92852574 41.4183703
OS 25.92218844 41.4323149
OS 25.9158486 41.44372458
OS 25.9095113 41.45766918
OS 25.90444146 41.46653886
OS 25.8968367 41.48302092
OS 25.89556924 41.48555584
OS 25.8892294 41.49569552
OS 25.88669448 41.50203536
OS 25.88352456 41.51027512
OS 25.87655226 41.52358472
OS 25.8752848 41.52865456
OS 25.87211742 41.54323416
OS 25.86514512 41.55654376
OS 25.86260766 41.56288106
OS 25.85119798 41.58696534
OS 25.84993052 41.5958401
OS 25.8486656 41.60090994
OS 25.84549568 41.6091497
OS 25.84359576 41.61105216
OS 25.83979338 41.61992692
OS 25.83725592 41.62626422
OS 25.82711624 41.64781358
OS 25.82584878 41.65288342
OS 25.82394632 41.66239064
OS 25.8214114 41.66873048
OS 25.8144391 41.685845
OS 25.81317164 41.69471722
OS 25.80873426 41.70675936
OS 25.80556434 41.71373166
OS 25.80302942 41.72006896
OS 25.80176196 41.72514134
OS 25.79859204 41.73845094
OS 25.79605712 41.74478824
OS 25.7928872 41.75176308
OS 25.79035228 41.75810038
OS 25.78908482 41.76317022
OS 25.7878199 41.77204244
OS 25.78148006 41.78598704
OS 25.77894514 41.79232688
OS 25.77767768 41.79739672
OS 25.77450776 41.81070632
OS 25.77197284 41.81704616
OS 25.77007038 41.822751
OS 25.76753546 41.83162322
OS 25.766268 41.83669306
OS 25.76500054 41.85317258
OS 25.76373308 41.85824242
OS 25.76183062 41.8702871
OS 25.76056316 41.87535694
OS 25.75802824 41.88169678
OS 25.75359086 41.8962713
OS 25.7523234 41.90894844
OS 25.75105594 41.91402082
OS 25.74978848 41.92162558
OS 25.7459861 41.93050034
OS 25.74218118 41.94570986
OS 25.74091372 41.95458462
OS 25.73964626 41.97106414
OS 25.7383788 41.97613398
OS 25.73647634 41.98310628
OS 25.73330896 41.9938835
OS 25.72950404 42.00909302
OS 25.7263392 42.03507976
OS 25.72126682 42.0553642
OS 25.7193669 42.07247364
OS 25.71746444 42.09212308
OS 25.71619698 42.1162099
OS 25.71492952 42.12761704
OS 25.71366206 42.1504364
OS 25.7123946 42.16057608
OS 25.7111246 42.16818338
OS 25.70985714 42.17325322
OS 25.70858968 42.18339544
OS 25.70732222 42.2049448
OS 25.70605476 42.22142432
OS 25.7047873 42.24424368
OS 25.70351984 42.28480748
OS 25.70161738 42.28924486
OS 25.69971746 42.29114478
OS 25.69464508 42.29241224
OE
SE
S P 0
OB 32.91135658 44.95700432 I
OS 32.98107704 44.95573686
OS 32.98488196 44.9544694
OS 33.00516132 44.95320194
OS 33.01403608 44.94939702
OS 33.0229083 44.9468621
OS 33.04129028 44.94496218
OS 33.04636266 44.94369218
OS 33.05269742 44.9411598
OS 33.06600956 44.93545496
OS 33.07488178 44.9341875
OS 33.07995416 44.93292004
OS 33.08819392 44.92975012
OS 33.09009384 44.9278502
OS 33.10150352 44.92277782
OS 33.10974074 44.91961044
OS 33.11671304 44.91517306
OS 33.13065764 44.90883322
OS 33.13699748 44.90503084
OS 33.14206732 44.899961
OS 33.14460224 44.89869354
OS 33.154112 44.89172124
OS 33.15474446 44.88981878
OS 33.15727938 44.88855132
OS 33.16995398 44.88348148
OS 33.17249144 44.88221402
OS 33.1800962 44.87460926
OS 33.18263112 44.8733418
OS 33.1870685 44.87017188
OS 33.18833596 44.86763696
OS 33.19087088 44.86510204
OS 33.19150588 44.86319958
OS 33.1940408 44.86193212
OS 33.20925286 44.84672006
OS 33.21115532 44.84608506
OS 33.21242278 44.84355014
OS 33.2149577 44.84101522
OS 33.2155927 44.83911276
OS 33.21812762 44.8378453
OS 33.22066254 44.83531038
OS 33.22319746 44.83404292
OS 33.2282673 44.82643562
OS 33.2352396 44.81946586
OS 33.24030944 44.80552126
OS 33.24601428 44.79854896
OS 33.2491842 44.79537904
OS 33.25045166 44.79284412
OS 33.2561565 44.78587182
OS 33.25932642 44.7827019
OS 33.26376126 44.77065976
OS 33.26693118 44.76622238
OS 33.27200102 44.76115508
OS 33.27327102 44.75862016
OS 33.27960832 44.7497454
OS 33.2834107 44.74594302
OS 33.28594562 44.7358008
OS 33.28721308 44.72565858
OS 33.2960853 44.70664414
OS 33.29862022 44.69650446
OS 33.29989022 44.6876297
OS 33.30622752 44.6736851
OS 33.30812998 44.65910804
OS 33.30939744 44.65150074
OS 33.3106649 44.62995138
OS 33.31193236 44.61727678
OS 33.31319982 44.6058671
OS 33.31446728 44.60079472
OS 33.31826966 44.59065504
OS 33.32143958 44.58241528
OS 33.32270704 44.57734544
OS 33.32143958 44.56593576
OS 33.31510228 44.55199116
OS 33.31383482 44.54692132
OS 33.31256482 44.53804656
OS 33.31129736 44.53297672
OS 33.3100299 44.51269482
OS 33.30812998 44.49938522
OS 33.30559252 44.48670808
OS 33.29989022 44.47339594
OS 33.29862022 44.46452372
OS 33.2960853 44.45438404
OS 33.289748 44.44424182
OS 33.28721308 44.43790452
OS 33.2840457 44.42966476
OS 33.28151078 44.42332492
OS 33.27960832 44.42142246
OS 33.27834086 44.41888754
OS 33.27453848 44.41001532
OS 33.27263602 44.39670572
OS 33.2701011 44.39036842
OS 33.2631288 44.38339612
OS 33.25805642 44.37452136
OS 33.25171912 44.36818406
OS 33.24664928 44.35423692
OS 33.23904198 44.34663216
OS 33.23777452 44.34409724
OS 33.23333714 44.33839494
OS 33.23080222 44.33712748
OS 33.17439136 44.28071662
OS 33.1737589 44.27881416
OS 33.17122144 44.2775467
OS 33.16868652 44.27501178
OS 33.16615414 44.27374432
OS 33.15981684 44.26740448
OS 33.153477 44.26486956
OS 33.14523724 44.26170218
OS 33.13762994 44.2566298
OS 33.13065764 44.25345988
OS 33.12241788 44.2502925
OS 33.11544558 44.24585512
OS 33.10150352 44.23951528
OS 33.09009384 44.23317798
OS 33.0786867 44.22810814
OS 33.05459988 44.216701
OS 33.04255774 44.21479854
OS 33.03241806 44.21099616
OS 33.02671322 44.2090937
OS 33.01783846 44.20782624
OS 32.96966736 44.20529132
OS 32.86952278 44.20402386
OS 32.75797106 44.20402386
OS 32.47908922 44.20529132
OS 32.47528684 44.20655878
OS 32.44106034 44.20782624
OS 32.43725796 44.2090937
OS 32.4290182 44.21226362
OS 32.41824098 44.21543354
OS 32.40873376 44.21733346
OS 32.39859154 44.22113838
OS 32.39035178 44.22557068
OS 32.3802121 44.22810814
OS 32.37007242 44.2293756
OS 32.36119766 44.23444544
OS 32.34725306 44.24078528
OS 32.34091576 44.2433202
OS 32.332041 44.2496575
OS 32.31809894 44.25472988
OS 32.3123941 44.25916472
OS 32.31112664 44.26170218
OS 32.30035196 44.26867448
OS 32.29401212 44.27501178
OS 32.28894228 44.27627924
OS 32.28070252 44.27944916
OS 32.27246022 44.28768638
OS 32.26612546 44.29148876
OS 32.264223 44.29339122
OS 32.26295554 44.29592614
OS 32.2572507 44.30163098
OS 32.25471578 44.30289844
OS 32.25154586 44.30606836
OS 32.2502784 44.30860328
OS 32.24457356 44.31430812
OS 32.24203864 44.31557558
OS 32.24013872 44.31747804
OS 32.23886872 44.32001296
OS 32.23316642 44.3257178
OS 32.23062896 44.32698526
OS 32.22746158 44.33015518
OS 32.22365666 44.33649248
OS 32.21731936 44.34283232
OS 32.21478444 44.34916708
OS 32.21351698 44.35423692
OS 32.20464476 44.36818406
OS 32.2033773 44.3732539
OS 32.19703746 44.38466358
OS 32.19196762 44.38973342
OS 32.19070016 44.39226834
OS 32.18499532 44.39924064
OS 32.18055794 44.40367802
OS 32.1748531 44.41952254
OS 32.16978326 44.4271273
OS 32.16661334 44.43790452
OS 32.16471088 44.4486792
OS 32.16217596 44.4550165
OS 32.15900858 44.4619888
OS 32.15647112 44.4683261
OS 32.15520366 44.47339594
OS 32.1539362 44.48607308
OS 32.15266874 44.4962153
OS 32.1475989 44.50889244
OS 32.14633398 44.51396228
OS 32.14443152 44.53487664
OS 32.14316406 44.55516108
OS 32.14252906 44.60649956
OS 32.14379652 44.61030448
OS 32.14506398 44.6407286
OS 32.14633398 44.64452844
OS 32.1475989 44.6534032
OS 32.15013382 44.6597405
OS 32.15266874 44.66861526
OS 32.15710612 44.69586946
OS 32.15964104 44.7022093
OS 32.16534588 44.71551636
OS 32.16661334 44.72439112
OS 32.1685158 44.73263088
OS 32.17041572 44.73453334
OS 32.17168318 44.73706826
OS 32.17675556 44.7421381
OS 32.17802302 44.74467556
OS 32.18372786 44.75164786
OS 32.18562778 44.75354778
OS 32.18689778 44.7560827
OS 32.19196762 44.76748984
OS 32.19703746 44.7763646
OS 32.2033773 44.7903092
OS 32.20781214 44.79854896
OS 32.21034706 44.79981642
OS 32.21224952 44.80171888
OS 32.21351698 44.8042538
OS 32.21922182 44.8112261
OS 32.22619412 44.81693094
OS 32.23189642 44.8239007
OS 32.23886872 44.82960554
OS 32.24457356 44.83657784
OS 32.24711102 44.8378453
OS 32.25154586 44.84228268
OS 32.25281332 44.8448176
OS 32.2572507 44.84925498
OS 32.25978562 44.85052244
OS 32.264223 44.85495982
OS 32.26549046 44.85749474
OS 32.26865784 44.86066466
OS 32.27119276 44.86193212
OS 32.27563014 44.8663695
OS 32.2768976 44.86890442
OS 32.28133498 44.8733418
OS 32.2838699 44.87460926
OS 32.28830728 44.87904664
OS 32.28957474 44.88158156
OS 32.29274466 44.88474894
OS 32.29527958 44.8860164
OS 32.2978145 44.88855132
OS 32.30035196 44.88981878
OS 32.30161942 44.8923537
OS 32.30415434 44.89362116
OS 32.30668926 44.89615608
OS 32.31366156 44.89805854
OS 32.32126886 44.90186092
OS 32.32887108 44.9069333
OS 32.3390133 44.91073568
OS 32.3453506 44.9132706
OS 32.34852052 44.91644052
OS 32.35105544 44.91770798
OS 32.3599302 44.92151036
OS 32.3662675 44.92404528
OS 32.36880496 44.92531528
OS 32.37767718 44.93165258
OS 32.38971932 44.93608996
OS 32.39605662 44.93862488
OS 32.40429638 44.94306226
OS 32.40936876 44.94432718
OS 32.42711574 44.9468621
OS 32.44042534 44.95003202
OS 32.44676518 44.95256694
OS 32.45309994 44.9538344
OS 32.47084946 44.95510186
OS 32.49239882 44.95636932
OS 32.5443723 44.95763678
OS 32.9075542 44.95827178
OS 32.91135658 44.95700432
OE
SE
S P 0
OB 33.63590682 41.42965806 I
OS 33.65102744 41.42410054
OS 33.66916558 41.39695302
OS 33.66954404 41.39637136
OS 33.67340738 41.38701908
OS 33.67847722 41.37941432
OS 33.68453766 41.37334118
OS 33.69019424 41.36465184
OS 33.69121786 41.3639508
OS 33.69128644 41.3638492
OS 33.69409568 41.35891906
OS 33.703387 41.351708
OS 33.70648834 41.34706742
OS 33.75719436 41.2963614
OS 33.75909682 41.29508886
OS 33.76036428 41.29319402
OS 33.76860404 41.28495172
OS 33.77242928 41.28239648
OS 33.77872086 41.27610236
OS 33.78166726 41.27413386
OS 33.78373228 41.27125858
OS 33.81463646 41.25209682
OS 33.81524098 41.25169042
OS 33.82160114 41.2467552
OS 33.82413606 41.24548774
OS 33.82478884 41.24530994
OS 33.82618838 41.24437268
OS 33.82693768 41.24362592
OS 33.83454244 41.23855862
OS 33.83544668 41.23818524
OS 33.84487008 41.23188604
OS 33.84811874 41.23123834
OS 33.84868262 41.23083448
OS 33.84958432 41.23042554
OS 33.85135216 41.22932826
OS 33.85338924 41.22856372
OS 33.85845654 41.22441844
OS 33.86587588 41.2204662
OS 33.86742274 41.21912254
OS 33.87175598 41.21664604
OS 33.8796503 41.20923178
OS 33.89902034 41.20190896
OS 33.90250268 41.19957978
OS 33.90664034 41.19875428
OS 33.92867992 41.18701694
OS 33.93764104 41.18614826
OS 33.9377782 41.1860873
OS 33.94258388 41.1850205
OS 33.9467444 41.18239414
OS 33.95498416 41.17922676
OS 33.96731332 41.17710078
OS 33.97862394 41.17175408
OS 33.98369632 41.17048408
OS 33.98410272 41.17046376
OS 33.98599248 41.16973732
OS 33.9983826 41.16759864
OS 34.00975418 41.16222654
OS 34.01482402 41.16095908
OS 34.02544122 41.16044346
OS 34.03546406 41.15691794
OS 34.04877366 41.15501802
OS 34.0519893 41.15519328
OS 34.05506016 41.15422046
OS 34.06580944 41.15302412
OS 34.07620058 41.14870358
OS 34.08254042 41.14743358
OS 34.09011216 41.14742342
OS 34.09730036 41.14503582
OS 34.10744004 41.14376836
OS 34.10888276 41.1438725
OS 34.11026198 41.14343562
OS 34.12737142 41.14153824
OS 34.14984534 41.14347372
OS 34.17231672 41.14153824
OS 34.1894287 41.14343562
OS 34.19080792 41.1438725
OS 34.19224556 41.14376836
OS 34.20238778 41.14503582
OS 34.2095836 41.14742596
OS 34.21717058 41.14743612
OS 34.22350788 41.14870612
OS 34.23317004 41.1527244
OS 34.24087894 41.1539436
OS 34.24414538 41.15441096
OS 34.25253246 41.15524916
OS 34.26679456 41.15960018
OS 34.28167896 41.16032154
OS 34.28674626 41.161589
OS 34.3701878 41.07650154
OS 34.37600948 41.06231056
OS 34.37772652 41.05754298
OS 34.22878346 40.6979628
OS 34.15000282 40.30190822
OS 34.15000282 39.89809394
OS 34.22878346 39.50203936
OS 34.38331706 39.12896162
OS 34.60766256 38.7932041
OS 34.73961556 38.6612511
OS 34.69101266 38.54391834
OS 24.4984143 38.54391834
OS 24.47837624 38.55555154
OS 24.44327344 38.5962398
OS 24.40533346 38.67092088
OS 24.40766264 38.6806567
OS 24.4089301 38.71361574
OS 24.4084221 38.71680344
OS 24.408257 38.72020196
OS 24.40893518 38.72494668
OS 24.4086126 38.7308725
OS 24.40897328 38.73428118
OS 24.41173426 38.74435228
OS 24.41057602 38.75355978
OS 24.41049474 38.75445132
OS 24.41087574 38.75609216
OS 24.4115082 38.77573906
OS 24.4104541 38.78209922
OS 24.4115209 38.78846192
OS 24.41093162 38.8079742
OS 24.41161488 38.81140828
OS 24.41161742 38.82052434
OS 24.4117368 38.8214743
OS 24.41161742 38.82191118
OS 24.41168092 39.09385374
OS 24.4193949 39.12344474
OS 24.4345333 39.15231438
OS 24.44182564 39.16166666
OS 24.49878006 39.20444788
OS 24.53871394 39.21788194
OS 25.06819726 39.21727488
OS 25.07174564 39.21797592
OS 25.07307406 39.21787432
OS 25.07367604 39.21794544
OS 25.07425516 39.21778796
OS 25.08372174 39.21898176
OS 25.08498158 39.21868204
OS 25.1020961 39.21804958
OS 25.10861374 39.2190986
OS 25.1151263 39.21798354
OS 25.1212223 39.21814864
OS 25.12258882 39.21777526
OS 25.12668838 39.21829596
OS 25.13857558 39.218616
OS 25.14080316 39.21912146
OS 25.15137718 39.2177905
OS 25.1589159 39.21985552
OS 25.15923594 39.21983266
OS 25.175464 39.2177905
OS 25.17943402 39.21887762
OS 25.18353612 39.2185271
OS 25.18923842 39.2191621
OS 25.19162348 39.21991902
OS 25.21730034 39.22142778
OS 25.23900972 39.22708944
OS 25.2613541 39.22892332
OS 25.27022632 39.23145824
OS 25.28067588 39.2368278
OS 25.29219732 39.23911634
OS 25.31045992 39.25131342
OS 25.31566946 39.25290092
OS 25.3218315 39.2579733
OS 25.34099834 39.26782088
OS 25.34859802 39.27677946
OS 25.35836432 39.28330218
OS 25.36343416 39.28837202
OS 25.36915424 39.29692674
OS 25.37709936 39.30346724
OS 25.38280674 39.31044208
OS 25.39235714 39.32837194
OS 25.39246382 39.32849894
OS 25.39252478 39.3286869
OS 25.39386844 39.33121166
OS 25.40814832 39.34993908
OS 25.41240028 39.36600712
OS 25.42020824 39.38066546
OS 25.42248154 39.40408934
OS 25.42850642 39.42685536
OS 25.42977388 39.4471398
OS 25.42951734 39.44904226
OS 25.42956052 39.44943088
OS 25.4289687 39.45631428
OS 25.42881122 39.46135364
OS 25.43030982 39.47324084
OS 25.43324606 39.4907643
OS 25.43261106 39.51167866
OS 25.43226054 39.51320012
OS 25.43352038 39.52285466
OS 25.4327914 39.53378936
OS 25.43380994 39.54024604
OS 25.43334766 39.55183098
OS 25.43366008 39.72935666
OS 25.78402768 39.72894264
OS 25.89076102 39.67687518
OS 25.89329594 39.59194774
OS 25.89491138 39.58492464
OS 25.89421542 39.57774406
OS 25.89548288 39.56506692
OS 25.90517552 39.5332839
OS 25.90973228 39.5138529
OS 25.91122072 39.50521436
OS 25.91259994 39.50162788
OS 25.91275742 39.50095478
OS 25.91340766 39.49952476
OS 25.9143881 39.4969746
OS 25.91503072 39.4959586
OS 25.91592734 39.49398502
OS 25.9166233 39.49301728
OS 25.91730656 39.48978894
OS 25.92111402 39.48091418
OS 25.92454302 39.47591546
OS 25.92614322 39.47007346
OS 25.92741068 39.467536
OS 25.94745382 39.44170928
OS 25.96560974 39.4145389
OS 25.96834024 39.4118084
OS 25.96905906 39.41054602
OS 25.97093358 39.4090906
OS 25.97324498 39.40563366
OS 25.97894982 39.39993136
OS 25.98232802 39.39767584
OS 25.98373518 39.39585974
OS 25.98502804 39.39512314
OS 25.98782204 39.39232914
OS 25.99163204 39.38978406
OS 25.99222894 39.38918716
OS 25.9944235 39.38772158
OS 25.99594496 39.38556512
OS 26.0195187 39.37066802
OS 26.04078866 39.35416056
OS 26.04332358 39.3528931
OS 26.04878712 39.35139704
OS 26.05838578 39.34498354
OS 26.06097658 39.34446792
OS 26.06320416 39.34306076
OS 26.0678422 39.34127768
OS 26.07764914 39.33707398
OS 26.09365368 39.33368816
OS 26.10844156 39.32669554
OS 26.11351394 39.32542554
OS 26.13386442 39.32442732
OS 26.15364848 39.31953528
OS 26.19484728 39.31763536
OS 26.20183736 39.31869454
OS 26.2106156 39.31680732
OS 26.24933536 39.31621296
OS 26.27848694 39.3150471
OS 26.28356694 39.3158472
OS 26.28861646 39.3148947
OS 26.39249738 39.31590308
OS 26.43216456 39.31524268
OS 26.45656888 39.31351294
OS 26.54222022 39.25457224
OS 26.54348768 39.25203732
OS 26.5467338 39.24785394
OS 26.54987578 39.24024918
OS 26.55494816 39.23264188
OS 26.56791232 39.21965232
OS 26.57605556 39.2074654
OS 26.57879876 39.2026521
OS 26.5797792 39.2018901
OS 26.5816842 39.19904022
OS 26.5886565 39.19206792
OS 26.59150638 39.19016292
OS 26.59226838 39.18918248
OS 26.59353076 39.18846366
OS 26.59626126 39.18573062
OS 26.60571514 39.17941364
OS 26.60693434 39.17768644
OS 26.61676922 39.17146852
OS 26.63096782 39.15788968
OS 26.63794012 39.1534523
OS 26.65377194 39.14730296
OS 26.6624181 39.141527
OS 26.66492762 39.14102662
OS 26.67221742 39.13641906
OS 26.67286004 39.13596694
OS 26.6731115 39.13585518
OS 26.67418846 39.13517446
OS 26.67758698 39.13386636
OS 26.68426972 39.1308971
OS 26.71943094 39.12296722
OS 26.75435594 39.11372416
OS 26.77464038 39.1124567
OS 26.7779246 39.11289866
OS 26.78745214 39.11082348
OS 26.85717514 39.10955602
OS 26.8578457 39.10967794
OS 26.8650593 39.10825554
OS 27.21049422 39.10889054
OS 27.2128488 39.10936298
OS 27.21521354 39.10895404
OS 27.26591702 39.1102215
OS 27.26820556 39.11073712
OS 27.27052458 39.11038914
OS 27.31045846 39.1122916
OS 27.33004694 39.1171684
OS 27.350212 39.11814884
OS 27.3552793 39.1194163
OS 27.37190614 39.12726998
OS 27.38328788 39.1290683
OS 27.39006714 39.13156512
OS 27.39016366 39.13158798
OS 27.39031352 39.13165656
OS 27.3953351 39.13350568
OS 27.39561958 39.13368094
OS 27.40019412 39.13160068
OS 27.43651104 39.12308914
OS 27.4725892 39.11368098
OS 27.49413856 39.11241352
OS 27.49702908 39.11281484
OS 27.50614006 39.11082602
OS 27.5745956 39.10955856
OS 27.57520012 39.10966778
OS 27.58232482 39.10825554
OS 28.43988216 39.10889054
OS 28.44228754 39.1093706
OS 28.44470308 39.1089515
OS 28.49667656 39.11021896
OS 28.49972202 39.11090222
OS 28.50281828 39.11046026
OS 28.53767978 39.11236272
OS 28.5420562 39.1134854
OS 28.54231528 39.11344222
OS 28.54709048 39.11455982
OS 28.55539882 39.1141077
OS 28.56427358 39.11537516
OS 28.59159636 39.12498652
OS 28.60101722 39.12719124
OS 28.6129349 39.12907592
OS 28.61968368 39.13156512
OS 28.61978274 39.13158798
OS 28.61993768 39.1316591
OS 28.6249745 39.13351584
OS 28.6314515 39.13748332
OS 28.63885306 39.13921814
OS 28.64582282 39.14238806
OS 28.66952864 39.1594213
OS 28.69491086 39.17386374
OS 28.70143866 39.18226098
OS 28.70584302 39.18477304
OS 28.70713842 39.18644436
OS 28.71043788 39.18881418
OS 28.71222858 39.19170216
OS 28.7138618 39.19333538
OS 28.71696314 39.19797596
OS 28.72625446 39.20518702
OS 28.73892906 39.22742218
OS 28.75461356 39.24763804
OS 28.75714594 39.25271042
OS 28.75976214 39.26226844
OS 28.76073496 39.26380768
OS 28.76354928 39.2677269
OS 28.76441796 39.26963698
OS 28.76505804 39.27065044
OS 28.76604864 39.273226
OS 28.76988658 39.28166896
OS 28.77881468 39.31975626
OS 28.78800186 39.35790198
OS 28.78926932 39.38959356
OS 28.78901532 39.39121154
OS 28.7906841 39.39911602
OS 28.79195156 39.5055979
OS 28.79193124 39.50570712
OS 28.79323426 39.51234414
OS 28.79291676 39.6388717
OS 28.88259908 39.72879532
OS 32.47278494 39.72940492
OS 32.47682608 39.7302101
OS 32.4808977 39.72956748
OS 32.51193396 39.73080954
OS 32.55031336 39.73204652
OS 32.55479646 39.73309046
OS 32.55937862 39.73253928
OS 32.5758556 39.73380674
OS 32.59245958 39.73845748
OS 32.60967824 39.73929568
OS 32.61474554 39.74056314
OS 32.62193882 39.74396166
OS 32.62982552 39.74495734
OS 32.63552782 39.7468598
OS 32.6371204 39.74776912
OS 32.63791542 39.74798502
OS 32.64218008 39.750111
OS 32.64669874 39.75095174
OS 32.65303858 39.75348666
OS 32.65475054 39.75460172
OS 32.67352876 39.75857682
OS 32.68240352 39.76238428
OS 32.68747844 39.76586662
OS 32.69299532 39.76807388
OS 32.69512384 39.76945818
OS 32.69761558 39.7699865
OS 32.70649034 39.77379396
OS 32.71151954 39.77724328
OS 32.71740472 39.77885872
OS 32.7199371 39.78012618
OS 32.72283778 39.78237916
OS 32.72572068 39.7829532
OS 32.7472802 39.79735754
OS 32.7490201 39.79783506
OS 32.75155756 39.79910252
OS 32.7596881 39.80541188
OS 32.76565456 39.8090644
OS 32.77998524 39.8166971
OS 32.78550212 39.82121068
OS 32.78602028 39.82152818
OS 32.78621332 39.82179234
OS 32.78695754 39.82240194
OS 32.78964232 39.8256633
OS 32.79187752 39.82715682
OS 32.79293416 39.82821346
OS 32.7971404 39.83061122
OS 32.7999344 39.83421294
OS 32.80455466 39.83729904
OS 32.80772458 39.84046896
OS 32.80947972 39.84309532
OS 32.80981754 39.84328836
OS 32.81169714 39.84571152
OS 32.81199178 39.84600362
OS 32.8144124 39.84788322
OS 32.81460544 39.84822104
OS 32.8172318 39.84997618
OS 32.82040172 39.8531461
OS 32.82276392 39.85668178
OS 32.82309666 39.85711104
OS 32.82466892 39.85868076
OS 32.82708954 39.86056036
OS 32.82731052 39.86094898
OS 32.83000292 39.86274984
OS 32.83190538 39.8646523
OS 32.83444538 39.86845976
OS 32.83733844 39.87135282
OS 32.83976668 39.8732375
OS 32.84131862 39.87596038
OS 32.84319822 39.87721514
OS 32.84994192 39.8839563
OS 32.85238794 39.88585368
OS 32.85240826 39.88588924
OS 32.85244128 39.88591464
OS 32.85399322 39.88863752
OS 32.85589314 39.88990752
OS 32.85676182 39.89077366
OS 32.8580496 39.89151026
OS 32.85995714 39.89397152
OS 32.86261906 39.8966309
OS 32.8630788 39.8969865
OS 32.8665713 39.89931822
OS 32.8684763 39.90121814
OS 32.87104424 39.90505608
OS 32.87411256 39.9081244
OS 32.87456976 39.90847746
OS 32.87808004 39.91082442
OS 32.87997996 39.91272434
OS 32.88351056 39.91800754
OS 32.88804446 39.92153306
OS 32.89041428 39.92569866
OS 32.89204242 39.9273268
OS 32.89349784 39.92950612
OS 32.89564414 39.93101996
OS 32.90489482 39.94566052
OS 32.91063268 39.95198258
OS 32.9144376 39.95832242
OS 32.91550948 39.96130946
OS 32.92025674 39.9671159
OS 32.92207792 39.97053728
OS 32.92291866 39.9711545
OS 32.92315488 39.97154312
OS 32.92466364 39.97278518
OS 32.93037102 39.97976002
OS 32.94161814 40.00087758
OS 32.94472456 40.004873
OS 32.94599456 40.00740792
OS 32.94689372 40.01067944
OS 32.94886984 40.01393826
OS 32.95247664 40.01791336
OS 32.95817894 40.02742058
OS 32.95981216 40.0319748
OS 32.9641835 40.03918332
OS 32.96782078 40.04917822
OS 32.97266964 40.05663566
OS 32.97520456 40.0629755
OS 32.97759978 40.07584822
OS 32.98138438 40.08444866
OS 32.98244356 40.08922132
OS 32.98505214 40.09335136
OS 32.98822206 40.10159112
OS 32.99036074 40.11398124
OS 32.99573284 40.12535282
OS 32.9970003 40.13042266
OS 32.9971527 40.1335748
OS 32.99989336 40.14778864
OS 33.00104144 40.15105
OS 33.00202696 40.15795372
OS 33.01007876 40.18335118
OS 33.01118874 40.19333592
OS 33.01355348 40.21224368
OS 33.01310136 40.21850986
OS 33.0147168 40.22457792
OS 33.01600712 40.24480902
OS 33.0250673 40.27550746
OS 33.02633476 40.2894546
OS 33.02435356 40.3081363
OS 33.02525526 40.31239842
OS 33.02232918 40.3281134
OS 33.01997968 40.36159314
OS 33.01807976 40.3685629
OS 33.01541784 40.3738969
OS 33.01461266 40.3851872
OS 33.01316232 40.39047802
OS 33.01355602 40.39594664
OS 33.01245874 40.40472996
OS 33.01071122 40.42044748
OS 33.00655832 40.4335488
OS 33.00589538 40.44728004
OS 33.00463046 40.45234988
OS 32.99924566 40.4637621
OS 32.99709936 40.47620302
OS 32.99075698 40.49268254
OS 32.98889262 40.49563148
OS 32.98424696 40.51622834
OS 32.97917712 40.52763548
OS 32.97658378 40.53131086
OS 32.9739879 40.53554758
OS 32.9737847 40.5361267
OS 32.97215148 40.54310154
OS 32.9689841 40.55007384
OS 32.96455434 40.55624096
OS 32.96413524 40.55733316
OS 32.9634088 40.55848124
OS 32.96315988 40.55982236
OS 32.96062496 40.5661622
OS 32.95992646 40.56723408
OS 32.95967754 40.56849138
OS 32.95640348 40.57339104
OS 32.95624092 40.5738203
OS 32.95217692 40.58032524
OS 32.95174004 40.58266712
OS 32.94920512 40.58900188
OS 32.94855488 40.59000264
OS 32.9483212 40.59117866
OS 32.94261382 40.59973084
OS 32.9407266 40.60303538
OS 32.93936516 40.60460256
OS 32.93279672 40.61444506
OS 32.92619272 40.62840744
OS 32.92403118 40.63036578
OS 32.92311424 40.6324816
OS 32.91741194 40.64072136
OS 32.91560346 40.64247142
OS 32.91196872 40.64884174
OS 32.90853718 40.65150112
OS 32.90581176 40.65569212
OS 32.9048237 40.6563703
OS 32.90416076 40.65736344
OS 32.90226084 40.65926844
OS 32.90085622 40.66020824
OS 32.89738912 40.66938018
OS 32.88962942 40.67764026
OS 32.88956084 40.67780536
OS 32.88933478 40.67803142
OS 32.88409984 40.6882219
OS 32.8655426 40.70396482
OS 32.86415322 40.70690614
OS 32.85286292 40.7171525
OS 32.84438948 40.7298144
OS 32.84248702 40.73171686
OS 32.82105196 40.74601706
OS 32.81149394 40.7546937
OS 32.80744772 40.75874754
OS 32.80666794 40.75907266
OS 32.8052303 40.76037568
OS 32.7997058 40.76235688
OS 32.79967532 40.76239498
OS 32.79231186 40.7665936
OS 32.78573072 40.77507212
OS 32.78004366 40.7783157
OS 32.77858824 40.779446
OS 32.7741915 40.78165072
OS 32.7702418 40.78390116
OS 32.75703888 40.7958798
OS 32.75069904 40.79968218
OS 32.73504756 40.8052905
OS 32.7312147 40.80702278
OS 32.7162414 40.81618456
OS 32.7111741 40.81804892
OS 32.70813118 40.82003012
OS 32.70292926 40.82376646
OS 32.70112332 40.82458688
OS 32.70057722 40.82494248
OS 32.69862396 40.82572226
OS 32.6975724 40.82620232
OS 32.6968866 40.82659348
OS 32.69667578 40.8266646
OS 32.69650814 40.82680938
OS 32.69549468 40.8271472
OS 32.68898212 40.8301063
OS 32.6808084 40.832024
OS 32.66416886 40.8375485
OS 32.65012266 40.84426934
OS 32.64327228 40.84601686
OS 32.6415781 40.84688808
OS 32.63270334 40.849423
OS 32.63076024 40.84958302
OS 32.61579964 40.85704554
OS 32.60882734 40.858948
OS 32.60659722 40.85910548
OS 32.604583 40.86005544
OS 32.59951062 40.8613229
OS 32.59602574 40.86149308
OS 32.58301586 40.8639137
OS 32.57890614 40.86535896
OS 32.57003392 40.86662642
OS 32.56880202 40.86656038
OS 32.56745836 40.8668093
OS 32.5335519 40.87487126
OS 32.49932794 40.87614126
OS 32.49707496 40.87578058
OS 32.48824592 40.87754842
OS 31.57126528 40.87881588
OS 31.45788476 40.88001984
OS 31.409513 40.88274018
OS 31.40769944 40.88290528
OS 31.40405454 40.88428196
OS 31.39644978 40.88554942
OS 31.3900312 40.88534876
OS 31.38389202 40.8872436
OS 31.36551004 40.88914352
OS 31.36054688 40.8886787
OS 31.34999826 40.89127966
OS 31.33564472 40.89193244
OS 31.3277504 40.896667
OS 31.32537042 40.89752044
OS 31.3233435 40.8988006
OS 31.31639914 40.90147268
OS 31.31184238 40.9032964
OS 31.30322416 40.90920952
OS 31.30156554 40.90992072
OS 31.29605628 40.91542998
OS 31.29263744 40.91771344
OS 31.29035906 40.92112466
OS 31.2694447 40.94204156
OS 31.2564526 41.04272716
OS 31.34700868 41.1385131
OS 31.37200482 41.13908206
OS 31.37460578 41.13966118
OS 32.925385 41.14029618
OS 32.9311254 41.14143918
OS 32.93380002 41.14094642
OS 32.98007374 41.14158142
OS 32.98400566 41.14241962
OS 32.98799092 41.14184304
OS 33.03616202 41.14437796
OS 33.04088134 41.14557684
OS 33.04573528 41.14510694
OS 33.05840988 41.1463744
OS 33.07409184 41.15115722
OS 33.07989828 41.15090322
OS 33.09217664 41.15279298
OS 33.09730236 41.15336194
OS 33.10918702 41.15444144
OS 33.1120496 41.15528726
OS 33.1150341 41.15505612
OS 33.13088116 41.15695858
OS 33.15976858 41.16639722
OS 33.18941038 41.17308758
OS 33.19729962 41.17659532
OS 33.2064106 41.18024022
OS 33.21107658 41.18327552
OS 33.21561048 41.1844109
OS 33.22382992 41.18829202
OS 33.22433538 41.18843934
OS 33.22641564 41.1895163
OS 33.23167852 41.19200042
OS 33.24900894 41.19591456
OS 33.26041608 41.20098694
OS 33.2622652 41.2022925
OS 33.26438864 41.20305704
OS 33.2685644 41.20557164
OS 33.27334468 41.2065216
OS 33.30105354 41.22503566
OS 33.30179014 41.22523886
OS 33.30432506 41.22650886
OS 33.30771596 41.22914284
OS 33.31065982 41.23091576
OS 33.32428438 41.23774328
OS 33.33211774 41.2438342
OS 33.33255208 41.24409582
OS 33.33268416 41.24427362
OS 33.33569152 41.24661296
OS 33.3381477 41.24945014
OS 33.34060134 41.25135514
OS 33.34666686 41.25481208
OS 33.34758888 41.2560008
OS 33.37578034 41.27434976
OS 33.376489 41.27538354
OS 33.37752786 41.27607696
OS 33.3815309 41.28008
OS 33.38279328 41.28079882
OS 33.384236 41.2826581
OS 33.38767262 41.28495426
OS 33.39337746 41.29065656
OS 33.39566346 41.29408048
OS 33.39907976 41.2963614
OS 33.41746428 41.31474338
OS 33.41921942 41.3173672
OS 33.4195547 41.31756024
OS 33.4203167 41.31854068
OS 33.42316658 41.32044568
OS 33.43013888 41.32741798
OS 33.43204388 41.33026786
OS 33.43302432 41.33102986
OS 33.4332199 41.3313753
OS 33.43584118 41.33312536
OS 33.44154602 41.33882766
OS 33.44384472 41.34226682
OS 33.44569892 41.343707
OS 33.4458818 41.34402704
OS 33.44847514 41.34575932
OS 33.45291252 41.35019416
OS 33.45468798 41.35284846
OS 33.45504866 41.3530542
OS 33.45581066 41.35403464
OS 33.45866054 41.35593964
OS 33.46563284 41.36291194
OS 33.46753784 41.36576182
OS 33.46851828 41.36652382
OS 33.46923456 41.36778112
OS 33.47324014 41.3717867
OS 33.48898306 41.39535028
OS 33.50730408 41.4169479
OS 33.50772318 41.41770228
OS 33.5297526 41.42972156
OS 33.53654202 41.4326959
OS 33.55536342 41.43944722
OS 33.56749446 41.44055212
OS 33.5816829 41.4409382
OS 33.63590682 41.42965806
OE
SE
S P 0
OB 34.19865144 42.10797014 I
OS 34.20372128 42.10670268
OS 34.21005858 42.10543522
OS 34.21829834 42.1022653
OS 34.22844056 42.09973038
OS 34.24428762 42.09782792
OS 34.2544273 42.095293
OS 34.2607646 42.09275808
OS 34.26266706 42.09085562
OS 34.2753442 42.08705324
OS 34.28548388 42.08578578
OS 34.30450086 42.07691102
OS 34.31464054 42.0743761
OS 34.32478022 42.07310864
OS 34.33175252 42.0674038
OS 34.33492244 42.06423642
OS 34.3437972 42.05916658
OS 34.3501345 42.05282674
OS 34.35647434 42.05029182
OS 34.35837426 42.04965936
OS 34.35900926 42.04902436
OS 34.3640791 42.0477569
OS 34.37168386 42.04015214
OS 34.37421878 42.03888214
OS 34.3767537 42.03634722
OS 34.37928862 42.03507976
OS 34.38245854 42.03064238
OS 34.38816338 42.02493754
OS 34.3906983 42.02367008
OS 34.39703814 42.01733278
OS 34.39957306 42.01606532
OS 34.40591036 42.0135304
OS 34.41098274 42.0122604
OS 34.41795504 42.0065581
OS 34.42239242 42.00212326
OS 34.42492734 42.0008558
OS 34.4318971 41.9938835
OS 34.43316456 41.99134604
OS 34.43506702 41.98944612
OS 34.43760194 41.98817866
OS 34.44330678 41.98247382
OS 34.44457424 41.9799389
OS 34.45091154 41.97359906
OS 34.452179 41.97106414
OS 34.45471646 41.9647243
OS 34.45598392 41.95965446
OS 34.45851884 41.95711954
OS 34.4597863 41.95458462
OS 34.4661236 41.94824478
OS 34.4673936 41.94570986
OS 34.4730959 41.9387401
OS 34.47626582 41.93557018
OS 34.4807032 41.92352804
OS 34.48387312 41.91909066
OS 34.48767296 41.91528828
OS 34.48894042 41.91275336
OS 34.49781518 41.90134368
OS 34.5003501 41.89880876
OS 34.50288502 41.88866654
OS 34.50415248 41.87852686
OS 34.51302724 41.85951242
OS 34.51556216 41.8493702
OS 34.51682962 41.84049544
OS 34.52443692 41.82401846
OS 34.52633684 41.81704616
OS 34.52760684 41.80310156
OS 34.5288743 41.79549426
OS 34.53077422 41.78852196
OS 34.53330914 41.78218466
OS 34.5358466 41.7733099
OS 34.53711406 41.7606353
OS 34.53964898 41.7264088
OS 34.53774652 41.70168952
OS 34.53647906 41.68647746
OS 34.5352116 41.6788727
OS 34.53140922 41.66873048
OS 34.53014176 41.6636581
OS 34.5282393 41.6566858
OS 34.52697184 41.6440112
OS 34.52570438 41.63513898
OS 34.52443692 41.6313366
OS 34.51809708 41.617392
OS 34.51556216 41.60851724
OS 34.5142947 41.59837502
OS 34.50161756 41.57175582
OS 34.49654772 41.56288106
OS 34.48894042 41.54640154
OS 34.48387312 41.53752932
OS 34.47880074 41.52611964
OS 34.4737309 41.51724742
OS 34.46866106 41.51217758
OS 34.4673936 41.50964012
OS 34.46295622 41.50393782
OS 34.4604213 41.50266782
OS 34.452179 41.49442806
OS 34.45154654 41.49252814
OS 34.44901162 41.49126068
OS 34.44077186 41.48302092
OS 34.43950186 41.48048346
OS 34.4318971 41.47414616
OS 34.3913333 41.43358236
OS 34.3906983 41.4316799
OS 34.38816338 41.43041244
OS 34.37992362 41.42217268
OS 34.37865616 41.41963776
OS 34.37421878 41.41646784
OS 34.36724648 41.410763
OS 34.3640791 41.40759308
OS 34.3577418 41.40505816
OS 34.35266942 41.40379324
OS 34.34633212 41.39999086
OS 34.3437972 41.39745594
OS 34.33492244 41.39365102
OS 34.32668268 41.39048364
OS 34.31971038 41.38604626
OS 34.30576832 41.37970642
OS 34.28675388 41.3708342
OS 34.2816815 41.36956674
OS 34.26520198 41.36829674
OS 34.26013214 41.36702928
OS 34.24808746 41.36259444
OS 34.23731532 41.35942452
OS 34.23224294 41.35815706
OS 34.21956834 41.3568896
OS 34.21069358 41.35562214
OS 34.19865144 41.35371968
OS 34.19357906 41.35245222
OS 34.18343938 41.34864984
OS 34.17710208 41.34737984
OS 34.16695986 41.34611238
OS 34.14984534 41.344215
OS 34.13273336 41.34611238
OS 34.12259368 41.34737984
OS 34.11625384 41.34864984
OS 34.10928154 41.35181722
OS 34.10230924 41.35371968
OS 34.09470448 41.35498714
OS 34.07758996 41.3568896
OS 34.06428036 41.35878952
OS 34.05921052 41.36005698
OS 34.05097076 41.3632269
OS 34.042096 41.36702928
OS 34.03322378 41.36829674
OS 34.0281514 41.36956674
OS 34.01991164 41.37273412
OS 34.00406712 41.37970642
OS 33.9951949 41.38097388
OS 33.9875876 41.38224134
OS 33.9806153 41.38794618
OS 33.97744792 41.3911161
OS 33.96857316 41.39618594
OS 33.96223332 41.40252578
OS 33.95589602 41.40505816
OS 33.94765626 41.40822808
OS 33.9400515 41.41329792
OS 33.9330792 41.41646784
OS 33.92293698 41.42027022
OS 33.91533222 41.42787752
OS 33.9127973 41.42914498
OS 33.90455754 41.43738474
OS 33.90392254 41.4392872
OS 33.90138762 41.44055466
OS 33.8506816 41.49126068
OS 33.84814668 41.49252814
OS 33.84307684 41.5001329
OS 33.83610454 41.5071052
OS 33.83356708 41.51344504
OS 33.8297647 41.52358472
OS 33.82722978 41.52611964
OS 33.82596486 41.52865456
OS 33.82215994 41.53752932
OS 33.81899256 41.54576908
OS 33.8107528 41.55400884
OS 33.8094828 41.55654376
OS 33.8031455 41.56541852
OS 33.80061058 41.56795344
OS 33.79807566 41.57429074
OS 33.7968082 41.5831655
OS 33.79490574 41.59013526
OS 33.79237082 41.59647256
OS 33.78539852 41.61231962
OS 33.78349606 41.6243643
OS 33.77969368 41.63450398
OS 33.77779122 41.64147628
OS 33.77652376 41.64654612
OS 33.7746213 41.67633524
OS 33.77335384 41.70929428
OS 33.77272138 41.74542324
OS 33.77398884 41.74922562
OS 33.7752563 41.7948618
OS 33.77652376 41.79866418
OS 33.77779122 41.81641116
OS 33.7815936 41.82528338
OS 33.78413106 41.83415814
OS 33.78603098 41.84493282
OS 33.7885659 41.85127012
OS 33.7955382 41.86584972
OS 33.7968082 41.87472448
OS 33.79870812 41.88296424
OS 33.80124304 41.889299
OS 33.80441296 41.89246892
OS 33.80821534 41.90134368
OS 33.8094828 41.90641352
OS 33.81328772 41.91275336
OS 33.81962502 41.91909066
OS 33.82089248 41.92162558
OS 33.82659732 41.92986534
OS 33.82849724 41.93050034
OS 33.8297647 41.93303526
OS 33.83356708 41.94191002
OS 33.83863946 41.9507797
OS 33.84497676 41.95711954
OS 33.84624422 41.95965446
OS 33.90265508 42.01606532
OS 33.90455754 42.01669778
OS 33.905825 42.0192327
OS 33.91406476 42.027475
OS 33.91659968 42.02874246
OS 33.92293698 42.03507976
OS 33.92927682 42.03761468
OS 33.93751658 42.0407846
OS 33.94322142 42.04648944
OS 33.94575634 42.0477569
OS 33.94828872 42.05029182
OS 33.95462856 42.05409674
OS 33.96096586 42.06043404
OS 33.97491046 42.06550134
OS 33.98378522 42.07184118
OS 33.99582736 42.07627856
OS 34.00026474 42.07817848
OS 34.01040442 42.08451832
OS 34.02561648 42.08705324
OS 34.03766116 42.09149062
OS 34.04463346 42.09466054
OS 34.05477314 42.09719546
OS 34.07125266 42.09846292
OS 34.0763225 42.09973038
OS 34.08899964 42.10099784
OS 34.09280202 42.1022653
OS 34.10547916 42.10606768
OS 34.110549 42.10733768
OS 34.12322614 42.10860514
OS 34.15745264 42.11114006
OS 34.19865144 42.10797014
OE
SE
S P 0
OB 43.2467766 45.28782662 I
OS 43.5750081 45.19987658
OS 43.8889648 45.06983112
OS 44.18321872 44.89994068
OS 44.45280162 44.69308308
OS 44.693078 44.45280924
OS 44.89994068 44.18322126
OS 45.06983112 43.8889648
OS 45.19986896 43.57502842
OS 45.28782408 43.24677914
OS 45.33217502 42.90990402
OS 45.33217756 42.7399958
OS 45.33217502 -2.06000096
OS 45.33217502 -2.22990918
OS 45.28782662 -2.56677922
OS 45.19987658 -2.89501072
OS 45.06983112 -3.20896742
OS 44.89994068 -3.50322134
OS 44.69308308 -3.77280424
OS 44.45280924 -4.01308062
OS 44.18322126 -4.2199433
OS 43.8889648 -4.38983374
OS 43.57502842 -4.51987158
OS 43.24677914 -4.6078267
OS 42.90989132 -4.6521751
OS 42.7399958 -4.65217764
OS -2.06000096 -4.65218272
OS -2.22990918 -4.65218272
OS -2.56678938 -4.60783178
OS -2.89502088 -4.51988428
OS -3.20895472 -4.38984644
OS -3.50322388 -4.21994838
OS -3.77279916 -4.0130984
OS -4.0130984 -3.77279916
OS -4.21994584 -3.50322642
OS -4.38984136 -3.2089598
OS -4.51988174 -2.89502088
OS -4.60782924 -2.56679192
OS -4.65218018 -2.22991172
OS -4.65217764 -2.06000604
OS -4.65218526 42.73999834
OS -4.65218526 42.90990656
OS -4.60783432 43.24678422
OS -4.51988682 43.57501318
OS -4.38984644 43.88895464
OS -4.21995092 44.18321872
OS -4.01310094 44.452794
OS -3.77280932 44.69308562
OS -3.50323404 44.89993814
OS -3.20894964 45.06984128
OS -2.89502342 45.19987658
OS -2.56679192 45.28782408
OS -2.22992188 45.33217248
OS -2.07798416 45.33216486
OS -2.07795622 45.33216994
OS 42.74000088 45.33217502
OS 42.90990656 45.33217502
OS 43.2467766 45.28782662
OE
OB 32.90719606 45.1621906 H
OS 32.5440167 45.1615556
OS 32.54171292 45.16109332
OS 32.53940152 45.16149464
OS 32.48742804 45.16022718
OS 32.4839584 45.15944994
OS 32.4804278 45.15993762
OS 32.4588759 45.15866762
OS 32.4576186 45.15833996
OS 32.45632574 45.15850252
OS 32.43857622 45.15723506
OS 32.42606926 45.15380606
OS 32.4130924 45.15379082
OS 32.40675764 45.15252336
OS 32.39729106 45.1485889
OS 32.39698626 45.14854572
OS 32.39318134 45.14840348
OS 32.3889751 45.14740272
OS 32.38053468 45.14619622
OS 32.37057534 45.14269356
OS 32.36002672 45.14218556
OS 32.35495434 45.14092064
OS 32.33252868 45.13034154
OS 32.33167524 45.13031614
OS 32.33076084 45.12990466
OS 32.32032144 45.12795902
OS 32.31653176 45.12644264
OS 32.30716932 45.12299332
OS 32.29187598 45.11363088
OS 32.29053232 45.11337942
OS 32.28419756 45.1108445
OS 32.28208682 45.10947036
OS 32.27962048 45.10894966
OS 32.27074826 45.10514728
OS 32.26572668 45.10170304
OS 32.25986182 45.10009776
OS 32.25732436 45.0988303
OS 32.25135536 45.09419734
OS 32.23947324 45.0868288
OS 32.23780954 45.08637414
OS 32.22865284 45.08455296
OS 32.2226432 45.08053722
OS 32.2224908 45.08046102
OS 32.22225458 45.08027814
OS 32.2183125 45.07764416
OS 32.2171187 45.07714886
OS 32.21296072 45.07601094
OS 32.21042326 45.07474348
OS 32.19922694 45.06605414
OS 32.1818127 45.05736734
OS 32.17648632 45.05123578
OS 32.16801034 45.0464047
OS 32.1641851 45.04147456
OS 32.162496 45.0403468
OS 32.1601846 45.03803794
OS 32.15596566 45.03563256
OS 32.15383206 45.03288174
OS 32.15362124 45.03274204
OS 32.15241982 45.03154062
OS 32.14860982 45.02899808
OS 32.1454399 45.0258307
OS 32.14365682 45.02316624
OS 32.14328852 45.02295542
OS 32.14140892 45.0205348
OS 32.14110158 45.02022746
OS 32.14066216 45.01988456
OS 32.13714426 45.01753506
OS 32.13270434 45.01309768
OS 32.13034214 45.009562
OS 32.1300094 45.00913274
OS 32.12970714 45.00883048
OS 32.12728398 45.00695088
OS 32.1270757 45.00658512
OS 32.12440616 45.0047995
OS 32.12124132 45.00162958
OS 32.11951666 44.9990464
OS 32.11920424 44.9988686
OS 32.11732464 44.99644798
OS 32.11703762 44.99616096
OS 32.1165347 44.9957698
OS 32.11305998 44.99344824
OS 32.10862006 44.98901086
OS 32.10606228 44.98518054
OS 32.10563048 44.98475128
OS 32.1031997 44.98286406
OS 32.10206432 44.98087016
OS 32.09816034 44.97612798
OS 32.0905759 44.97024788
OS 32.08944306 44.9682616
OS 32.08858454 44.96721766
OS 32.0867532 44.96571144
OS 32.08137856 44.959143
OS 32.0799079 44.9583048
OS 32.07889698 44.95700178
OS 32.07406844 44.95302668
OS 32.06847282 44.946189
OS 32.06805626 44.9459096
OS 32.06764732 44.94550066
OS 32.06140146 44.9403597
OS 32.05630622 44.93413416
OS 32.05376114 44.93215804
OS 32.0425953 44.9125721
OS 32.02824938 44.89519342
OS 32.02381454 44.88695366
OS 32.02178508 44.88033188
OS 32.01774394 44.87470832
OS 32.015303 44.86933876
OS 32.01490422 44.86864026
OS 32.01467816 44.86796208
OS 32.0114041 44.86076118
OS 32.01123392 44.86003982
OS 31.94032474 44.81798758
OS 31.89052042 44.80990022
OS 31.80836412 44.86455594
OS 31.80832348 44.86477692
OS 31.80578856 44.87111168
OS 31.80510784 44.87215816
OS 31.804864 44.87338498
OS 31.80171948 44.87809414
OS 31.80117338 44.87949876
OS 31.79229862 44.8934459
OS 31.79084828 44.89496228
OS 31.78989832 44.8968622
OS 31.78824478 44.89899072
OS 31.78283458 44.91044104
OS 31.77639822 44.9162805
OS 31.7623952 44.93780192
OS 31.76136396 44.93851058
OS 31.76067054 44.9395469
OS 31.75432308 44.9458969
OS 31.75177546 44.94970944
OS 31.69536714 45.0061203
OS 31.69350532 45.0073649
OS 31.6922658 45.00922164
OS 31.68973342 45.01175656
OS 31.68505982 45.0148833
OS 31.67781066 45.02422288
OS 31.6729237 45.02700926
OS 31.6696725 45.02918096
OS 31.66949978 45.02943242
OS 31.668212 45.03027062
OS 31.66273576 45.03609992
OS 31.65829838 45.03926984
OS 31.64679218 45.04446414
OS 31.64662708 45.04457336
OS 31.63216432 45.05580016
OS 31.63183412 45.0561583
OS 31.6293881 45.05795408
OS 31.62081814 45.0646038
OS 31.61828322 45.06587126
OS 31.61385854 45.06708284
OS 31.61241836 45.0677534
OS 31.59904272 45.07988952
OS 31.59270288 45.0836919
OS 31.58359698 45.0869558
OS 31.58333282 45.08720726
OS 31.57636052 45.09164464
OS 31.57583728 45.09184784
OS 31.5722 45.0944615
OS 31.5582554 45.10080134
OS 31.55232196 45.10219326
OS 31.54004106 45.10995042
OS 31.53541826 45.11172588
OS 31.5301122 45.11400172
OS 31.5292486 45.1141846
OS 31.52323388 45.1181978
OS 31.52071166 45.11869818
OS 31.51853996 45.12006978
OS 31.5103002 45.1232397
OS 31.49791008 45.12537838
OS 31.4865385 45.13075048
OS 31.48146866 45.13201794
OS 31.47466146 45.13234814
OS 31.47133406 45.13308728
OS 31.45450148 45.14080634
OS 31.44119188 45.14397372
OS 31.43173546 45.14432678
OS 31.42281752 45.14746368
OS 31.41162628 45.14906134
OS 31.40480384 45.15189598
OS 31.39846654 45.15316344
OS 31.38356436 45.15317868
OS 31.36223344 45.15824852
OS 31.32800694 45.15951598
OS 31.32565744 45.15913752
OS 31.31669378 45.16092314
OS 24.38900888 45.1621906
OS 24.36236682 45.15689724
OS 24.33529042 45.15499732
OS 24.32832066 45.1530974
OS 24.31844006 45.14816726
OS 24.31096992 45.1466839
OS 24.29771112 45.13782692
OS 24.29464788 45.13630038
OS 24.26059918 45.12021456
OS 24.18411216 45.085508
OS 24.10065284 45.10646808
OS 24.09989592 45.10678812
OS 24.09939046 45.10688972
OS 24.09520454 45.1086601
OS 24.0882932 45.11131948
OS 24.08314208 45.11337942
OS 24.08215656 45.1135623
OS 24.07974864 45.1150863
OS 24.0774601 45.11694812
OS 24.07341388 45.11908934
OS 24.06987058 45.12132962
OS 24.0673509 45.1222999
OS 24.06668288 45.12265296
OS 24.06555766 45.12298824
OS 24.06293892 45.12399662
OS 24.05779034 45.12605656
OS 24.05118126 45.12728846
OS 24.04194836 45.1300469
OS 24.01848892 45.14080634
OS 24.00517932 45.14397372
OS 23.9957229 45.14432678
OS 23.98680496 45.14746368
OS 23.98505744 45.1477126
OS 23.98442752 45.14792342
OS 23.9813338 45.14831204
OS 23.97825024 45.14977
OS 23.97317786 45.15103746
OS 23.95379512 45.15197726
OS 23.9272191 45.15825868
OS 23.8917226 45.15952614
OS 23.88967028 45.1591934
OS 23.8810673 45.16092314
OS 23.26879268 45.1621906
OS 23.260812 45.16062088
OS 23.25273226 45.16159116
OS 23.2436924 45.1608952
OS 23.23678106 45.16187564
OS 23.21811968 45.16083932
OS 23.21072828 45.16190866
OS 23.19868868 45.16127366
OS 23.19349438 45.15995286
OS 23.19325816 45.15998588
OS 23.15839666 45.15808596
OS 23.13429206 45.15191122
OS 23.1231948 45.15190106
OS 23.1117775 45.14715888
OS 23.09375874 45.14380354
OS 23.08742398 45.14126862
OS 23.0839645 45.13901818
OS 23.08132036 45.13834
OS 23.07173694 45.1311518
OS 23.06942554 45.13051934
OS 23.06688808 45.12925188
OS 23.06485862 45.12767708
OS 23.04971514 45.12138804
OS 23.03645634 45.10810638
OS 23.02073374 45.09787526
OS 23.0142161 45.08837312
OS 23.00403324 45.08047118
OS 23.00130782 45.07569344
OS 22.99715238 45.0720968
OS 22.992715 45.0663945
OS 22.9832662 45.0475604
OS 22.97048492 45.0307964
OS 22.96595102 45.01366918
OS 22.96462768 45.01134762
OS 22.96446766 45.01008778
OS 22.95703816 44.9952745
OS 22.9555167 44.97425092
OS 22.95012428 44.95388012
OS 22.94885682 44.93359568
OS 22.94915146 44.93140112
OS 22.94866124 44.92598838
OS 22.9495731 44.91742096
OS 22.94843772 44.90841412
OS 22.94537702 44.89036996
OS 22.94600694 44.8681856
OS 22.94618474 44.86740582
OS 22.94533892 44.86356534
OS 22.94526526 44.8599941
OS 22.9450138 44.85817292
OS 22.94517382 44.85546528
OS 22.94470392 44.83250622
OS 22.9457123 44.8268344
OS 22.94564372 44.82566346
OS 22.94685276 44.8169538
OS 22.9453694 44.80828478
OS 22.94599932 44.78483296
OS 22.9464235 44.78296606
OS 22.94511286 44.77292036
OS 22.94574786 44.7634106
OS 22.94828532 44.7539872
OS 22.9479221 44.75182312
OS 22.94855456 44.73090622
OS 22.95164574 44.71748994
OS 22.9515035 44.7163571
OS 22.95341612 44.7093594
OS 22.95327642 44.70790652
OS 22.95565132 44.70012142
OS 22.95654032 44.6962657
OS 22.96307066 44.66126958
OS 22.96560812 44.65493228
OS 22.96631678 44.65384262
OS 22.966426 44.65337272
OS 22.968712 44.6501647
OS 22.97024616 44.64781012
OS 22.97248898 44.63960846
OS 22.97375644 44.637071
OS 22.97560556 44.63468848
OS 22.9764844 44.63180304
OS 22.9960043 44.6080896
OS 22.99931138 44.60108936
OS 23.0026337 44.59807692
OS 23.00902688 44.58825728
OS 23.01454122 44.58447776
OS 23.02251428 44.57419584
OS 23.02513556 44.57269978
OS 23.02705072 44.57037314
OS 23.03402556 44.56466576
OS 23.04719038 44.55765536
OS 23.05823938 44.54762998
OS 23.06457922 44.5438276
OS 23.07486114 44.54014206
OS 23.0836851 44.53370062
OS 23.0992553 44.52992364
OS 23.10424894 44.52726426
OS 23.11323546 44.52639304
OS 23.13948128 44.51698742
OS 23.1503982 44.51751828
OS 23.16100778 44.51494526
OS 23.18297878 44.51403086
OS 23.18678878 44.51293612
OS 23.2019983 44.51166866
OS 23.20325814 44.5118109
OS 23.20447734 44.51147816
OS 23.21249104 44.51248908
OS 23.23424614 44.51128004
OS 23.2411524 44.51225794
OS 23.2419271 44.51219952
OS 23.2495471 44.51311392
OS 23.25707058 44.51159754
OS 23.74674194 44.51033516
OS 23.75912952 44.5100329
OS 23.76038936 38.8278624
OS 23.7598966 38.81455026
OS 23.76101928 38.80756018
OS 23.7605824 38.7975094
OS 23.76171524 38.79014594
OS 23.76047318 38.7828028
OS 23.76110818 38.76061844
OS 23.7629065 38.75275968
OS 23.76257376 38.74666368
OS 23.76153744 38.74287908
OS 23.76211656 38.73828422
OS 23.76204036 38.73688722
OS 23.76026998 38.72284356
OS 23.76220292 38.71578236
OS 23.76180414 38.70846716
OS 23.76304874 38.6997448
OS 23.76368882 38.6818505
OS 23.766272 38.67092088
OS 23.7293531 38.59798224
OS 23.69360768 38.55596048
OS 23.67308702 38.54391834
OS 6.44999726 38.54391834
OS 6.44999726 38.80190614
OS 6.37121662 39.19796072
OS 6.21668302 39.57103846
OS 5.99233752 39.90679598
OS 5.7067958 40.1923377
OS 5.37103828 40.4166832
OS 4.99796054 40.5712168
OS 4.60190596 40.64999744
OS 4.19809168 40.64999744
OS 3.8020371 40.5712168
OS 3.42895936 40.4166832
OS 3.09320184 40.1923377
OS 2.80766012 39.90679598
OS 2.58331462 39.57103846
OS 2.42878102 39.19796072
OS 2.35000038 38.80190614
OS 2.35000038 38.54391834
OS -1.16000022 38.54391834
OS -1.23803664 38.5283964
OS -1.30419348 38.48419278
OS -1.3483971 38.41803594
OS -1.36391904 38.33999952
OS -1.36391904 2.3400004
OS -1.3483971 2.26196398
OS -1.30419348 2.19580714
OS -1.23803664 2.15160352
OS -1.16000022 2.13608158
OS 2.35000038 2.13608158
OS 2.35000038 1.79809394
OS 2.42878102 1.40203936
OS 2.58331462 1.02896162
OS 2.80766012 0.6932041
OS 3.09320184 0.40766238
OS 3.42895936 0.18331688
OS 3.8020371 0.02878328
OS 4.19809168 -0.04999736
OS 4.60190596 -0.04999736
OS 4.99796054 0.02878328
OS 5.37103828 0.18331688
OS 5.7067958 0.40766238
OS 5.99233752 0.6932041
OS 6.21668302 1.02896162
OS 6.37121662 1.40203936
OS 6.44999726 1.79809394
OS 6.44999726 2.13608158
OS 43.84000122 2.13608158
OS 43.91803764 2.15160352
OS 43.98419448 2.19580714
OS 44.0283981 2.26196398
OS 44.04392004 2.3400004
OS 44.04392004 38.33999952
OS 44.0283981 38.41803594
OS 43.98419448 38.48419278
OS 43.91803764 38.5283964
OS 43.84000122 38.54391834
OS 37.70898986 38.54391834
OS 37.66038696 38.6612511
OS 37.79233996 38.7932041
OS 38.01668546 39.12896162
OS 38.17121906 39.50203936
OS 38.2499997 39.89809394
OS 38.2499997 40.30190822
OS 38.17121906 40.6979628
OS 38.01668546 41.07104054
OS 37.79233996 41.40679806
OS 37.50679824 41.69233978
OS 37.17104072 41.91668528
OS 36.79796298 42.07121888
OS 36.4019084 42.14999952
OS 35.99809412 42.14999952
OS 35.60203954 42.07121888
OS 35.2289618 41.91668528
OS 34.89320428 41.69233978
OS 34.86683654 41.66597204
OS 34.82574188 41.67210614
OS 34.77918114 41.69384854
OS 34.74179234 41.72053378
OS 34.74112178 41.72611416
OS 34.74301154 41.741471
OS 34.74047662 41.7756975
OS 34.73976542 41.77826798
OS 34.74002196 41.78092482
OS 34.7387545 41.79359942
OS 34.73341034 41.8111178
OS 34.7319092 41.8293677
OS 34.72937174 41.83824246
OS 34.72759882 41.84168924
OS 34.72753532 41.84190514
OS 34.72752008 41.84213374
OS 34.72562016 41.84910604
OS 34.725102 41.8501449
OS 34.72433238 41.85275348
OS 34.7230827 41.87065794
OS 34.72118278 41.87763024
OS 34.71369486 41.89265434
OS 34.71339514 41.89881638
OS 34.71086022 41.9089586
OS 34.70248076 41.9267005
OS 34.70097454 41.9328473
OS 34.700718 41.93811272
OS 34.69818308 41.94825494
OS 34.69170608 41.9619684
OS 34.68874698 41.97684518
OS 34.67487096 41.99761222
OS 34.66420296 42.0201979
OS 34.66008054 42.02393678
OS 34.65877498 42.02654282
OS 34.64990022 42.0379525
OS 34.64902646 42.03870688
OS 34.64853878 42.03939014
OS 34.64844226 42.03958572
OS 34.64792664 42.0402512
OS 34.64663124 42.04206222
OS 34.64620706 42.042461
OS 34.64207956 42.04777214
OS 34.63858198 42.05348206
OS 34.63526728 42.05970506
OS 34.63456878 42.06225776
OS 34.63330132 42.06479522
OS 34.63092896 42.06785338
OS 34.63092134 42.06786608
OS 34.63085784 42.06794482
OS 34.6213811 42.0801546
OS 34.6185617 42.0861236
OS 34.61272986 42.09141442
OS 34.60278068 42.10630898
OS 34.5980893 42.1135175
OS 34.59786578 42.11367244
OS 34.59513274 42.11776184
OS 34.59237684 42.12052028
OS 34.59165294 42.12178774
OS 34.58979366 42.12323046
OS 34.5874975 42.12666708
OS 34.5817952 42.13237192
OS 34.57917138 42.13412452
OS 34.57897834 42.13446488
OS 34.57800806 42.13521672
OS 34.57611576 42.13805136
OS 34.569146 42.14502112
OS 34.56631898 42.14691088
OS 34.56556714 42.14788116
OS 34.56428698 42.14861268
OS 34.56210512 42.150792
OS 34.5535758 42.15648668
OS 34.54705308 42.16440894
OS 34.54008078 42.17011124
OS 34.53574246 42.17242264
OS 34.53244046 42.17606246
OS 34.51913086 42.18235658
OS 34.51841204 42.1830754
OS 34.5145995 42.18562302
OS 34.50827236 42.19195016
OS 34.4956638 42.20037534
OS 34.4854784 42.21160214
OS 34.46617948 42.2207182
OS 34.46555972 42.2212008
OS 34.46324324 42.22236158
OS 34.46088612 42.22522416
OS 34.45391128 42.23093154
OS 34.44650718 42.23487616
OS 34.44494762 42.23622998
OS 34.43607286 42.24129982
OS 34.43606016 42.2413049
OS 34.42558266 42.2503727
OS 34.41027154 42.25545778
OS 34.40971274 42.25583116
OS 34.40831066 42.25611056
OS 34.4038682 42.2575863
OS 34.3836879 42.26833304
OS 34.37463788 42.26921188
OS 34.37171942 42.27057332
OS 34.34474716 42.2771824
OS 34.33880102 42.28115496
OS 34.33755642 42.28140134
OS 34.33649724 42.28209222
OS 34.33015994 42.28462714
OS 34.31647696 42.28717476
OS 34.30388618 42.29312344
OS 34.29374396 42.29565836
OS 34.28086108 42.29628574
OS 34.27998732 42.29657022
OS 34.27788674 42.29756336
OS 34.2739091 42.29855904
OS 34.26859542 42.30029386
OS 34.25995688 42.30133018
OS 34.25317762 42.30453312
OS 34.25052332 42.30519606
OS 34.25004834 42.30539418
OS 34.248471 42.30570914
OS 34.24810778 42.30580058
OS 34.2479884 42.30580566
OS 34.24371358 42.30666164
OS 34.23075704 42.30667434
OS 34.2142953 42.31128698
OS 34.1730965 42.3144569
OS 34.15774728 42.31261286
OS 34.14239044 42.31450262
OS 34.10816394 42.3119677
OS 34.10559346 42.3112565
OS 34.10293916 42.31151304
OS 34.09026202 42.31024558
OS 34.07594404 42.30587932
OS 34.06099868 42.30514526
OS 34.05592884 42.30387526
OS 34.05163116 42.30184326
OS 34.04689406 42.30139114
OS 34.04564184 42.30101522
OS 34.0391369 42.30051484
OS 34.02895404 42.29766242
OS 34.02686362 42.29756082
OS 34.02179632 42.29629336
OS 34.02069904 42.2957752
OS 34.0053168 42.2950259
OS 33.99517712 42.29249098
OS 33.98281494 42.28665152
OS 33.97688658 42.28566346
OS 33.9767926 42.2856279
OS 33.97669354 42.28563044
OS 33.97086424 42.28342064
OS 33.96716854 42.28283644
OS 33.9603207 42.28031422
OS 33.96023434 42.2802939
OS 33.96009972 42.28023294
OS 33.95512132 42.27839906
OS 33.95105224 42.27590732
OS 33.94029534 42.27182808
OS 33.93191588 42.2686607
OS 33.92532204 42.2676193
OS 33.91327736 42.26318192
OS 33.90658446 42.2590849
OS 33.90246204 42.25752534
OS 33.90238838 42.25745676
OS 33.90229694 42.2574212
OS 33.89717122 42.25421572
OS 33.89131906 42.25208974
OS 33.88741508 42.24972246
OS 33.88292944 42.24883092
OS 33.8687156 42.23933132
OS 33.86525104 42.23776922
OS 33.85637628 42.23142938
OS 33.85624674 42.23129222
OS 33.84969354 42.22894272
OS 33.8433537 42.2251378
OS 33.8363179 42.21875478
OS 33.82327754 42.2108503
OS 33.82213708 42.20929836
OS 33.81261462 42.20190696
OS 33.78053442 42.18103832
OS 33.77981052 42.17998422
OS 33.77874372 42.17927048
OS 33.77367134 42.17420064
OS 33.77278488 42.17360882
OS 33.77221592 42.1732837
OS 33.77212448 42.17316686
OS 33.76984864 42.1716454
OS 33.76161142 42.1634031
OS 33.76035412 42.16152096
OS 33.75846182 42.16025604
OS 33.70205096 42.10384772
OS 33.69949318 42.10001994
OS 33.69441826 42.09494248
OS 33.679384 42.072433
OS 33.66162432 42.0520114
OS 33.6565494 42.04314172
OS 33.65612522 42.04187934
OS 33.6532347 42.03770612
OS 33.60962036 42.02262614
OS 33.56887114 42.02188954
OS 33.5171796 42.03017248
OS 33.50841406 42.03427966
OS 33.5066767 42.03570968
OS 33.5063846 42.03635738
OS 33.50511968 42.03812776
OS 33.50509682 42.03817348
OS 33.50497744 42.03832842
OS 33.50321468 42.04079476
OS 33.50265334 42.04132308
OS 33.5001616 42.04453364
OS 33.49855886 42.0469314
OS 33.47752258 42.07926052
OS 33.47646086 42.07998696
OS 33.47574966 42.08105376
OS 33.47050456 42.08629632
OS 33.46978574 42.0875587
OS 33.4688053 42.0883207
OS 33.4669003 42.09117058
OS 33.459928 42.09814288
OS 33.45802808 42.09941288
OS 33.45675808 42.1013128
OS 33.45369992 42.10437096
OS 33.44588942 42.12002752
OS 33.4360774 42.1285543
OS 33.42885872 42.13935438
OS 33.4130142 42.15519636
OS 33.40924992 42.15771096
OS 33.40657022 42.16136348
OS 33.38149534 42.176573
OS 33.37626294 42.18180794
OS 33.37282378 42.18410664
OS 33.3713836 42.18596084
OS 33.36847784 42.18761692
OS 33.36388044 42.19069286
OS 33.36181796 42.19369768
OS 33.35916112 42.19542742
OS 33.35550098 42.19987242
OS 33.34852614 42.2055798
OS 33.32725364 42.21691074
OS 33.32326584 42.22000446
OS 33.32073092 42.22127192
OS 33.3185008 42.22188152
OS 33.29512772 42.23709104
OS 33.29110436 42.23869886
OS 33.2853919 42.24114996
OS 33.28293064 42.2426257
OS 33.2764384 42.24695894
OS 33.27527508 42.24719008
OS 33.2742794 42.24783778
OS 33.26976582 42.24964626
OS 33.26875744 42.25042858
OS 33.26622252 42.25169604
OS 33.26069294 42.25320988
OS 33.25103586 42.25965386
OS 33.2485238 42.2601517
OS 33.2483333 42.26027362
OS 33.24769068 42.26072574
OS 33.24743922 42.2608375
OS 33.24636226 42.26151822
OS 33.24296374 42.26282632
OS 33.236281 42.26579558
OS 33.23411438 42.26628326
OS 33.22695158 42.27106354
OS 33.22577556 42.27129722
OS 33.22477226 42.27195
OS 33.21843496 42.27448492
OS 33.2029435 42.27737036
OS 33.18857726 42.28384228
OS 33.1866367 42.28428932
OS 33.18103854 42.2865296
OS 33.15537946 42.29130988
OS 33.13059922 42.29953948
OS 33.124267 42.30033196
OS 33.12332974 42.30064438
OS 33.12278872 42.30091362
OS 33.11581642 42.30281354
OS 33.09561072 42.30422324
OS 33.0938124 42.30445184
OS 33.06519422 42.3111422
OS 33.02716534 42.31240966
OS 33.02528574 42.31209978
OS 33.01684278 42.31379142
OS 32.06610808 42.31505888
OS 32.06540196 42.31491918
OS 32.061912 42.31566848
OS 32.02442922 42.31622982
OS 32.01896314 42.31749474
OS 32.00503632 42.31792908
OS 31.91720312 42.40934622
OS 31.91593566 42.41821844
OS 31.91241014 42.42823874
OS 31.91189452 42.43884578
OS 31.91139922 42.44082698
OS 31.91212312 42.44256942
OS 31.91339058 42.44890418
OS 31.91339312 42.45225444
OS 31.91457676 42.45538372
OS 31.91584422 42.46299102
OS 31.9156334 42.46974234
OS 31.91760698 42.47621426
OS 31.91855694 42.4857037
OS 31.91950182 42.48775348
OS 31.9202308 42.49078878
OS 31.92159732 42.49409078
OS 31.9268475 42.50174634
OS 31.93188178 42.5134913
OS 31.94197066 42.52945774
OS 31.94205448 42.52958474
OS 31.9427098 42.53009274
OS 31.94318986 42.53041278
OS 31.943421 42.53064392
OS 31.94417792 42.53123066
OS 31.97631146 42.5521501
OS 31.97701758 42.5531788
OS 31.97805136 42.55386968
OS 31.97942296 42.55524128
OS 31.980505 42.55549528
OS 31.98086568 42.55555878
OS 31.9810003 42.55561212
OS 31.9931288 42.55845692
OS 31.9948687 42.55854074
OS 31.999936 42.5598082
OS 32.01285952 42.56591182
OS 32.01513536 42.56614042
OS 32.02287474 42.56850008
OS 32.02653488 42.56867788
OS 32.03160472 42.56994534
OS 32.0353182 42.57169794
OS 32.0484881 42.57277998
OS 32.05187392 42.5729273
OS 32.05692852 42.57416428
OS 32.1142868 42.57531236
OS 32.11856924 42.5762547
OS 32.12291772 42.57566796
OS 32.12977826 42.57609722
OS 32.13388036 42.57527172
OS 32.13709854 42.57590418
OS 32.14774876 42.57590926
OS 32.14874444 42.5757848
OS 32.14920418 42.5759118
OS 34.7856683 42.57717164
OS 34.78810162 42.57765678
OS 34.79054256 42.5772326
OS 34.84251604 42.57850006
OS 34.84576216 42.57922904
OS 34.84906162 42.57876422
OS 34.88265312 42.58066414
OS 34.90132974 42.58549014
OS 34.92059564 42.5864274
OS 34.92566294 42.58769486
OS 34.93023748 42.5898564
OS 34.93096138 42.5899834
OS 34.93558164 42.59044314
OS 34.93740028 42.59099686
OS 34.94814194 42.59253102
OS 34.97640452 42.60247258
OS 35.00553324 42.60960744
OS 35.02377044 42.61811644
OS 35.03666348 42.62397876
OS 35.04274424 42.62834756
OS 35.04990196 42.6305853
OS 35.05661264 42.63424544
OS 35.06047344 42.63596248
OS 35.0628966 42.63767444
OS 35.06384402 42.63819006
OS 35.06502512 42.63917558
OS 35.06503782 42.63918574
OS 35.06599794 42.63955404
OS 35.07121764 42.64285096
OS 35.07722982 42.64426066
OS 35.08419958 42.64743058
OS 35.09021176 42.65175112
OS 35.09138524 42.65196956
OS 35.09772 42.65450448
OS 35.09877918 42.65519536
OS 35.10002378 42.65544174
OS 35.11029554 42.66230482
OS 35.11289142 42.6633767
OS 35.12049872 42.66844654
OS 35.12142836 42.66937618
OS 35.1233232 42.67032106
OS 35.12970368 42.67527152
OS 35.13213446 42.67689712
OS 35.14443822 42.6849032
OS 35.14576918 42.68540612
OS 35.14702394 42.68658468
OS 35.16441024 42.69789784
OS 35.16512652 42.69893924
OS 35.16618062 42.69964536
OS 35.17250776 42.7059725
OS 35.1763203 42.70852012
OS 35.18202514 42.71422242
OS 35.18431114 42.71764126
OS 35.18772998 42.71992726
OS 35.20864688 42.74084416
OS 35.20991942 42.74274662
OS 35.21181426 42.74401408
OS 35.22005656 42.75225384
OS 35.22132656 42.75415376
OS 35.22322648 42.75542376
OS 35.24287338 42.77507066
OS 35.24542862 42.7788959
OS 35.25047814 42.78394288
OS 35.26554034 42.80648538
OS 35.28332796 42.82694762
OS 35.2883978 42.83582238
OS 35.29072952 42.84279214
OS 35.3006152 42.85843346
OS 35.3013899 42.85959424
OS 35.30638608 42.86602552
OS 35.30765608 42.86856298
OS 35.30784404 42.86924878
OS 35.3212908 42.88936558
OS 35.32180896 42.89196908
OS 35.32262684 42.89326448
OS 35.32417116 42.8952533
OS 35.32543862 42.89778822
OS 35.32693468 42.9032543
OS 35.33334564 42.91284788
OS 35.33386634 42.91546408
OS 35.33528874 42.91771706
OS 35.33793796 42.92461316
OS 35.34072942 42.93158292
OS 35.34353612 42.9357917
OS 35.34377234 42.93698042
OS 35.34443274 42.93799642
OS 35.34696766 42.94433626
OS 35.35039158 42.96273094
OS 35.35757724 42.98002072
OS 35.3594797 42.9895254
OS 35.35948732 42.99528866
OS 35.36139486 43.0007141
OS 35.36392978 43.01846108
OS 35.36366308 43.02336836
OS 35.3706557 43.04978944
OS 35.37192316 43.07007388
OS 35.37161074 43.07238528
OS 35.37349796 43.08059964
OS 35.37476542 43.12369836
OS 35.37425488 43.12672604
OS 35.37609384 43.13683016
OS 35.37546138 43.17549404
OS 35.37497624 43.17774194
OS 35.37533692 43.18001016
OS 35.37406692 43.21296666
OS 35.37304838 43.2172237
OS 35.37355384 43.2215798
OS 35.37165392 43.24503416
OS 35.36992672 43.2511073
OS 35.37026962 43.25740904
OS 35.36900216 43.26628126
OS 35.36377484 43.28114534
OS 35.3634421 43.2844702
OS 35.36350814 43.28747756
OS 35.36267502 43.29219688
OS 35.36221528 43.29681714
OS 35.36166156 43.29863324
OS 35.3601274 43.30937998
OS 35.35018076 43.3376578
OS 35.3430459 43.36677636
OS 35.33658922 43.3806092
OS 35.33618282 43.38162774
OS 35.33594406 43.38199604
OS 35.33417114 43.38579334
OS 35.32910384 43.3926996
OS 35.3285552 43.39563838
OS 35.32601774 43.40197568
OS 35.323907 43.40521672
OS 35.32305864 43.408981
OS 35.3179888 43.42039068
OS 35.315271 43.42424132
OS 35.31402894 43.4287803
OS 35.31276148 43.43131776
OS 35.3104704 43.43426924
OS 35.30989382 43.43717246
OS 35.29040948 43.4663342
OS 35.287585 43.47102304
OS 35.28421188 43.47919676
OS 35.27914204 43.48680406
OS 35.27647504 43.48947614
OS 35.2723196 43.49637986
OS 35.26839784 43.49927546
OS 35.2663252 43.50237934
OS 35.2635058 43.50732472
OS 35.2613976 43.50896048
OS 35.26108518 43.50952182
OS 35.249358 43.52334704
OS 35.24622872 43.5302787
OS 35.2430588 43.53471608
OS 35.24127064 43.53639502
OS 35.2368866 43.54408614
OS 35.22840808 43.55066728
OS 35.22420946 43.55803074
OS 35.22235018 43.55947346
OS 35.22005402 43.56291008
OS 35.21435172 43.56861492
OS 35.21091256 43.57091362
OS 35.20947238 43.57276782
OS 35.20821254 43.57348664
OS 35.20737942 43.57431976
OS 35.19882216 43.5800373
OS 35.1922842 43.58797734
OS 35.1853119 43.59367964
OS 35.18098374 43.59598342
OS 35.1776919 43.59961562
OS 35.1643696 43.60591736
OS 35.16371682 43.60657014
OS 35.15988904 43.60913046
OS 35.15604094 43.6129811
OS 35.15079584 43.6164863
OS 35.14981286 43.61791886
OS 35.14104986 43.62361862
OS 35.13895182 43.6255922
OS 35.13038186 43.63471588
OS 35.12594448 43.6378858
OS 35.11080354 43.64472094
OS 35.1106486 43.64484032
OS 35.10811368 43.64610778
OS 35.10713578 43.64637702
OS 35.10382616 43.64787054
OS 35.0932242 43.65495206
OS 35.09057752 43.65719742
OS 35.07916784 43.66353472
OS 35.07167484 43.6659401
OS 35.06959966 43.66732694
OS 35.06950568 43.66734472
OS 35.06456538 43.67089564
OS 35.05062078 43.67723548
OS 35.04759564 43.67794414
OS 35.03968608 43.68322226
OS 35.03793094 43.68357024
OS 35.037903 43.68359056
OS 35.0360107 43.68445162
OS 35.03499216 43.68509424
OS 35.03239882 43.68609246
OS 35.0239584 43.68992786
OS 35.02200006 43.6903876
OS 35.01572626 43.6945786
OS 35.01446896 43.69482752
OS 35.01339708 43.69552602
OS 35.00705724 43.69806094
OS 34.99121272 43.70100988
OS 34.98915278 43.70194714
OS 34.98545454 43.70281582
OS 34.98373496 43.70352956
OS 34.98046344 43.70565808
OS 34.97412614 43.708193
OS 34.96867276 43.709209
OS 34.96661028 43.70962048
OS 34.96114674 43.710987
OS 34.9597726 43.71105304
OS 34.94782698 43.71669438
OS 34.9427546 43.71796184
OS 34.93454278 43.71836062
OS 34.92684404 43.72127146
OS 34.91923928 43.72253892
OS 34.91215014 43.72231794
OS 34.90536834 43.72436264
OS 34.89036202 43.72581552
OS 34.8860237 43.72643528
OS 34.88172856 43.7262016
OS 34.85761126 43.73295546
OS 34.83288944 43.73485538
OS 34.83069996 43.73459122
OS 34.82857144 43.73513986
OS 34.80575208 43.73640732
OS 34.80269392 43.73597298
OS 34.79966878 43.73665624
OS 34.75023276 43.7379237
OS 34.74764196 43.73747666
OS 34.7450664 43.73798974
OS 30.5833907 43.7392572
OS 30.53816854 43.74039004
OS 30.5156489 43.74161686
OS 30.51496056 43.74176926
OS 30.51200908 43.7436895
OS 30.50567178 43.74622442
OS 30.49413002 43.74837326
OS 30.48869696 43.75108344
OS 30.48744728 43.75210706
OS 30.483048 43.75445148
OS 30.4796952 43.75814464
OS 30.46714252 43.764073
OS 30.46548898 43.7653557
OS 30.46402594 43.76681874
OS 30.46213872 43.76924952
OS 30.4316638 43.89148956
OS 30.49166622 43.98386428
OS 30.5005359 43.9863992
OS 30.51400044 43.99331816
OS 30.51804666 43.99351374
OS 30.52818888 43.99604866
OS 30.53037582 43.9970799
OS 30.54958076 43.9976641
OS 30.5547268 43.99885028
OS 31.22703686 44.00010504
OS 31.22813414 44.00032602
OS 31.2292365 44.00012028
OS 31.32937854 44.00138774
OS 31.33342476 44.00224626
OS 31.33751416 44.00165444
OS 31.38568526 44.00418936
OS 31.39461336 44.00645758
OS 31.40380816 44.0059572
OS 31.41268038 44.00722466
OS 31.43006414 44.01333844
OS 31.44835214 44.0156473
OS 31.45405698 44.01754976
OS 31.45686114 44.01914742
OS 31.46003868 44.01965034
OS 31.46159316 44.02022438
OS 31.46646742 44.02062316
OS 31.47534472 44.02315808
OS 31.488126 44.02972398
OS 31.49032056 44.03027262
OS 31.49454712 44.03226906
OS 31.50076504 44.03334094
OS 31.50900226 44.03650832
OS 31.5113162 44.03796882
OS 31.53006902 44.0419363
OS 31.53894124 44.04573868
OS 31.54260138 44.0482482
OS 31.54799634 44.0501913
OS 31.5482859 44.05036656
OS 31.54982768 44.0507882
OS 31.55236514 44.05205566
OS 31.5535437 44.05297006
OS 31.55691428 44.05364062
OS 31.5826902 44.07085674
OS 31.59020098 44.07354914
OS 31.59653574 44.07735152
OS 31.60329214 44.08348308
OS 31.61615978 44.09123008
OS 31.61741962 44.09293442
OS 31.62725704 44.10056966
OS 31.65936772 44.1214637
OS 31.660084 44.1225051
OS 31.6611381 44.12321122
OS 31.66620032 44.12827344
OS 31.67001286 44.13082106
OS 31.73339602 44.19420168
OS 31.73466856 44.19610414
OS 31.7365634 44.1973716
OS 31.73909832 44.19990398
OS 31.74042674 44.2018928
OS 31.74578868 44.20605332
OS 31.74581154 44.20609396
OS 31.74584202 44.20611682
OS 31.75127254 44.21565198
OS 31.75424434 44.21781352
OS 31.7588646 44.2253624
OS 31.76717294 44.23316782
OS 31.77034286 44.2376052
OS 31.77608834 44.25033568
OS 31.78123438 44.25695238
OS 31.786068 44.26659676
OS 31.79618736 44.28260892
OS 31.80264658 44.2909325
OS 31.80391404 44.29346742
OS 31.8042417 44.29466376
OS 31.81689344 44.31359692
OS 31.89909292 44.34549678
OS 31.93870676 44.35338602
OS 31.95042378 44.34898166
OS 31.9921636 44.32563906
OS 32.00812496 44.30175036
OS 32.00831038 44.30107472
OS 32.00957784 44.29853726
OS 32.01327608 44.29377222
OS 32.02448764 44.27515148
OS 32.02559254 44.27307376
OS 32.02799538 44.26707174
OS 32.02866848 44.26603796
OS 32.02890724 44.264834
OS 32.0320416 44.26014262
OS 32.0325877 44.25873292
OS 32.04145992 44.24478578
OS 32.04423868 44.24188002
OS 32.04435552 44.24170222
OS 32.04776928 44.23447846
OS 32.04882846 44.23152444
OS 32.0504058 44.22889808
OS 32.0509392 44.22776778
OS 32.0512567 44.22747822
OS 32.05263338 44.22518714
OS 32.06190946 44.21496872
OS 32.0713989 44.20038912
OS 32.0724149 44.19969316
OS 32.07309816 44.19866954
OS 32.07421068 44.19755448
OS 32.0766313 44.19331522
OS 32.08017968 44.1905644
OS 32.08321244 44.18602034
OS 32.08637982 44.18285042
OS 32.08977072 44.1805822
OS 32.09041588 44.18008182
OS 32.09331148 44.17718622
OS 32.09584894 44.17338384
OS 32.09774886 44.17147884
OS 32.10044634 44.16967544
OS 32.10066478 44.16928936
OS 32.10308794 44.16740976
OS 32.1047999 44.16569526
OS 32.1073526 44.1618751
OS 32.11052252 44.15870518
OS 32.11434776 44.15614994
OS 32.11605718 44.15443798
OS 32.11793678 44.15201736
OS 32.11827968 44.15182178
OS 32.12003228 44.14919796
OS 32.1219322 44.1472955
OS 32.12714174 44.1438157
OS 32.13061392 44.13934022
OS 32.13483032 44.13693738
OS 32.13655498 44.13521272
OS 32.13871906 44.13376746
OS 32.14022528 44.13163386
OS 32.15484552 44.12239588
OS 32.16117774 44.11664786
OS 32.16675812 44.11330014
OS 32.16754298 44.112434
OS 32.17629582 44.10829888
OS 32.17872406 44.10516706
OS 32.18357546 44.10239846
OS 32.18723814 44.09816936
OS 32.19294552 44.09373452
OS 32.21489874 44.08273632
OS 32.22241206 44.0773693
OS 32.2319523 44.07306654
OS 32.24838102 44.06309958
OS 32.2547234 44.06079326
OS 32.25770028 44.05885524
OS 32.26285394 44.05515192
OS 32.26463702 44.05434166
OS 32.26518312 44.05398606
OS 32.26714654 44.0532012
OS 32.2682235 44.05271098
OS 32.268922 44.0523122
OS 32.2691125 44.0522487
OS 32.26926998 44.05211154
OS 32.2702809 44.05177626
OS 32.27680108 44.04881208
OS 32.28497734 44.04689438
OS 32.30742586 44.03943694
OS 32.31755284 44.03605366
OS 32.32696354 44.0302142
OS 32.33710576 44.02640928
OS 32.35281058 44.02383372
OS 32.35580016 44.02194396
OS 32.35885578 44.02076794
OS 32.36069982 44.01980274
OS 32.36352938 44.01896962
OS 32.36403992 44.01877404
OS 32.36442092 44.018708
OS 32.36828426 44.01757262
OS 32.36877194 44.01736942
OS 32.36939932 44.01724496
OS 32.37055502 44.0169046
OS 32.37277244 44.01563968
OS 32.37657482 44.01437222
OS 32.40532254 44.01074764
OS 32.433514 44.00404712
OS 32.4677405 44.00277966
OS 32.469709 44.00309716
OS 32.47816212 44.00137504
OS 32.75704396 44.00010758
OS 32.75750624 44.00019648
OS 32.75797106 44.00010504
OS 32.86952278 44.00010504
OS 32.87080802 44.00036158
OS 32.87210342 44.00012028
OS 32.972248 44.00138774
OS 32.97629422 44.00224626
OS 32.98038362 44.00165444
OS 33.02855472 44.00418936
OS 33.03747266 44.00645504
OS 33.04667 44.00595466
OS 33.05554476 44.00722212
OS 33.07293614 44.01333844
OS 33.0735051 44.0134121
OS 33.07437886 44.01337654
OS 33.07891022 44.01409282
OS 33.09122414 44.0156473
OS 33.09692898 44.01754976
OS 33.1002513 44.0194446
OS 33.10402066 44.02006182
OS 33.1141578 44.0238642
OS 33.11844024 44.0265185
OS 33.14187936 44.03240368
OS 33.1637386 44.04275672
OS 33.17291308 44.04683342
OS 33.18039846 44.05211662
OS 33.18911066 44.05491316
OS 33.19336516 44.05727536
OS 33.19985486 44.06022684
OS 33.20428716 44.063412
OS 33.20904458 44.06641682
OS 33.21505676 44.06782652
OS 33.22202652 44.07099644
OS 33.22803108 44.07530936
OS 33.22918424 44.07552526
OS 33.23552408 44.07806018
OS 33.23661374 44.07876884
OS 33.23789136 44.07902284
OS 33.24819106 44.08590878
OS 33.25075646 44.08696796
OS 33.25736554 44.09137486
OS 33.25742142 44.0913901
OS 33.2599538 44.09265756
OS 33.2645258 44.09620848
OS 33.2648814 44.09638628
OS 33.26498046 44.09646248
OS 33.26509984 44.0964955
OS 33.2714346 44.10142056
OS 33.3022194 44.12144592
OS 33.302956 44.1225178
OS 33.30403804 44.1232417
OS 33.30906978 44.12827598
OS 33.31287978 44.13082106
OS 33.3154147 44.13335344
OS 33.31668724 44.13525844
OS 33.31858462 44.1365259
OS 33.32529276 44.1432315
OS 33.32775656 44.14514412
OS 33.32782006 44.14525334
OS 33.32791658 44.14532954
OS 33.32861254 44.14655382
OS 33.37499548 44.19293422
OS 33.37809682 44.1975748
OS 33.38738814 44.20478586
OS 33.38978336 44.20898702
OS 33.39081714 44.2100208
OS 33.39106098 44.21038402
OS 33.394269 44.21316024
OS 33.396682 44.21625904
OS 33.3970503 44.21653082
OS 33.3976091 44.21745284
OS 33.39870638 44.21886254
OS 33.3998697 44.22118156
OS 33.41529766 44.24662982
OS 33.4201643 44.25290108
OS 33.42143176 44.255436
OS 33.42160956 44.25608878
OS 33.42660574 44.26356146
OS 33.4350995 44.27333284
OS 33.44016934 44.2822076
OS 33.44110406 44.2850016
OS 33.44809414 44.29279686
OS 33.45104054 44.30117124
OS 33.45849798 44.312332
OS 33.45874436 44.3135766
OS 33.45943524 44.31463578
OS 33.46197016 44.32097308
OS 33.46484036 44.3363858
OS 33.46577254 44.33856004
OS 33.46594018 44.33934998
OS 33.46990766 44.3452885
OS 33.47015658 44.3465458
OS 33.47085508 44.34761768
OS 33.47339 44.35395752
OS 33.473644 44.35532404
OS 33.47438568 44.35649752
OS 33.47705268 44.36343426
OS 33.47908214 44.36850918
OS 33.48062392 44.37678958
OS 33.49391574 44.40492516
OS 33.49645066 44.41506738
OS 33.4966564 44.41927362
OS 33.49720758 44.42073158
OS 33.4970628 44.4254509
OS 33.49731172 44.42662692
OS 33.49788322 44.42824744
OS 33.5055464 44.4466853
OS 33.50808386 44.45936244
OS 33.50809148 44.46513332
OS 33.51000156 44.47056892
OS 33.51190148 44.48387852
OS 33.51145444 44.49205224
OS 33.51355248 44.4999745
OS 33.51406048 44.50812282
OS 33.51442624 44.50915914
OS 33.51539398 44.51592316
OS 33.52411126 44.5434212
OS 33.52537872 44.55483088
OS 33.525079 44.55833354
OS 33.52524156 44.55903204
OS 33.52477166 44.5618997
OS 33.5239614 44.57132564
OS 33.52529236 44.57722606
OS 33.522031 44.59612112
OS 33.52053748 44.62680432
OS 33.51927002 44.63187162
OS 33.51864772 44.63318988
OS 33.51856898 44.63410428
OS 33.51459896 44.64175984
OS 33.5143729 44.64223736
OS 33.51398682 44.64609562
OS 33.5129632 44.6634743
OS 33.51019968 44.67406864
OS 33.51054258 44.6850135
OS 33.50987202 44.68903686
OS 33.50843184 44.7000757
OS 33.50093122 44.72225498
OS 33.50048164 44.72539188
OS 33.49763176 44.7334894
OS 33.49690786 44.73657804
OS 33.49645066 44.7459608
OS 33.49391574 44.75610048
OS 33.4855439 44.7738246
OS 33.48403514 44.7799841
OS 33.4837786 44.78524698
OS 33.48124368 44.7953892
OS 33.47476668 44.80910266
OS 33.47180758 44.82397944
OS 33.45792902 44.84474902
OS 33.45575224 44.84935912
OS 33.45558714 44.8499611
OS 33.45431968 44.85249602
OS 33.45419522 44.85265604
OS 33.44726356 44.86733216
OS 33.4442816 44.87003726
OS 33.43922192 44.87712386
OS 33.43415462 44.88188636
OS 33.43285922 44.88475656
OS 33.431607 44.88650916
OS 33.43157398 44.8865752
OS 33.43139872 44.88680126
OS 33.4296893 44.88919394
OS 33.4291432 44.88970702
OS 33.42526462 44.89470574
OS 33.42366442 44.8973194
OS 33.42362124 44.89753784
OS 33.4225519 44.89913804
OS 33.4216121 44.9006722
OS 33.4139794 44.91500288
OS 33.40946582 44.92051976
OS 33.40914832 44.92103792
OS 33.40888416 44.92123096
OS 33.40827456 44.92197518
OS 33.40607492 44.92378366
OS 33.4052672 44.92499524
OS 33.40383718 44.92768002
OS 33.40261036 44.92918116
OS 33.40140386 44.93116998
OS 33.39795454 44.93952404
OS 33.3928847 44.94713134
OS 33.38992814 44.95009298
OS 33.385633 44.95717958
OS 33.38194238 44.95988722
OS 33.3801212 44.96261518
OS 33.37724846 44.967652
OS 33.3695675 44.97361338
OS 33.36895536 44.97468526
OS 33.36712402 44.97610512
OS 33.36485326 44.97950364
OS 33.36232088 44.98203856
OS 33.36041588 44.9833111
OS 33.35914842 44.98520848
OS 33.35661604 44.9877434
OS 33.35471358 44.98901594
OS 33.35344612 44.99091078
OS 33.34672528 44.99763416
OS 33.34482536 45.00008272
OS 33.3447898 45.00010304
OS 33.3447644 45.00013606
OS 33.34350456 45.00085488
OS 33.33823406 45.00612538
OS 33.33632906 45.00739792
OS 33.3350616 45.0092953
OS 33.33252922 45.01183022
OS 33.32788864 45.01493156
OS 33.32067758 45.02422288
OS 33.31574744 45.02703212
OS 33.31254958 45.0291708
OS 33.31237686 45.02942226
OS 33.31108654 45.03026046
OS 33.30560268 45.03609992
OS 33.3011653 45.03926984
OS 33.28966672 45.0444616
OS 33.28947114 45.04459114
OS 33.27505664 45.05576714
OS 33.27468326 45.05617608
OS 33.2718791 45.05823348
OS 33.26361394 45.0646419
OS 33.26107648 45.06590936
OS 33.25666958 45.06711332
OS 33.25527258 45.0677661
OS 33.24188424 45.0799073
OS 33.23554186 45.08370968
OS 33.22645374 45.08696342
OS 33.22619974 45.08720726
OS 33.21922744 45.09164464
OS 33.21869912 45.09185038
OS 33.21505676 45.09446658
OS 33.20110962 45.10080642
OS 33.19519142 45.1021958
OS 33.18521684 45.108495
OS 33.18434308 45.10911222
OS 33.18399764 45.10926716
OS 33.18292576 45.1099428
OS 33.17958058 45.11123058
OS 33.1729334 45.1141846
OS 33.17176754 45.11444876
OS 33.16623034 45.118147
OS 33.16363954 45.11866262
OS 33.16141196 45.12006978
OS 33.1531722 45.1232397
OS 33.14076938 45.12538092
OS 33.12938764 45.13075556
OS 33.12508742 45.13182998
OS 33.1220572 45.13304156
OS 33.10842502 45.13557902
OS 33.09589012 45.14150484
OS 33.09081774 45.14277484
OS 33.07714238 45.1434454
OS 33.07005578 45.14546978
OS 33.0697205 45.14549772
OS 33.06225544 45.1478015
OS 33.04475738 45.14960998
OS 33.01788164 45.15672452
OS 32.99760228 45.15799198
OS 32.9943079 45.15754748
OS 32.98478544 45.15962266
OS 32.91506244 45.16089012
OS 32.9143995 45.16077074
OS 32.90719606 45.1621906
OE
OB 14.42216826 44.87499788 H
OS 14.11783054 44.87499788
OS 13.8193399 44.81562538
OS 13.53816952 44.69915876
OS 13.28511948 44.53007858
OS 13.06992052 44.31487962
OS 12.90084034 44.06182958
OS 12.8147318 43.85394836
OS 12.677267 43.85394836
OS 12.59115846 44.06182958
OS 12.42207828 44.31487962
OS 12.20687932 44.53007858
OS 11.95382928 44.69915876
OS 11.6726589 44.81562538
OS 11.37416826 44.87499788
OS 11.06983054 44.87499788
OS 10.7713399 44.81562538
OS 10.49016952 44.69915876
OS 10.23711948 44.53007858
OS 10.02192052 44.31487962
OS 9.85284034 44.06182958
OS 9.73637372 43.7806592
OS 9.67700122 43.48216856
OS 9.67700122 43.17783084
OS 9.73637372 42.8793402
OS 9.85284034 42.59816982
OS 10.02192052 42.34511978
OS 10.23711948 42.12992082
OS 10.49016952 41.96084064
OS 10.7713399 41.84437402
OS 11.06983054 41.78500152
OS 11.37416826 41.78500152
OS 11.6726589 41.84437402
OS 11.95382928 41.96084064
OS 12.20687932 42.12992082
OS 12.42207828 42.34511978
OS 12.59115846 42.59816982
OS 12.677267 42.80605104
OS 12.8147318 42.80605104
OS 12.90084034 42.59816982
OS 13.06992052 42.34511978
OS 13.28511948 42.12992082
OS 13.53816952 41.96084064
OS 13.8193399 41.84437402
OS 14.11783054 41.78500152
OS 14.42216826 41.78500152
OS 14.7206589 41.84437402
OS 15.00182928 41.96084064
OS 15.25487932 42.12992082
OS 15.47007828 42.34511978
OS 15.63915846 42.59816982
OS 15.75562508 42.8793402
OS 15.81499758 43.17783084
OS 15.81499758 43.48216856
OS 15.75562508 43.7806592
OS 15.63915846 44.06182958
OS 15.47007828 44.31487962
OS 15.25487932 44.53007858
OS 15.00182928 44.69915876
OS 14.7206589 44.81562538
OS 14.42216826 44.87499788
OE
OB 43.12499884 44.7353563 H
OS 42.81173556 44.69411432
OS 42.51982098 44.57320016
OS 42.26914838 44.38085104
OS 42.07679926 44.13017844
OS 41.9558851 43.83826386
OS 41.91464312 43.52500058
OS 41.9558851 43.2117373
OS 42.07679926 42.91982272
OS 42.26914838 42.66915012
OS 42.51982098 42.476801
OS 42.81173556 42.35588684
OS 43.12499884 42.31464486
OS 43.43826212 42.35588684
OS 43.7301767 42.476801
OS 43.9808493 42.66915012
OS 44.17319842 42.91982272
OS 44.29411258 43.2117373
OS 44.33535456 43.52500058
OS 44.29411258 43.83826386
OS 44.17319842 44.13017844
OS 43.9808493 44.38085104
OS 43.7301767 44.57320016
OS 43.43826212 44.69411432
OS 43.12499884 44.7353563
OE
OB -2.37499906 44.7353563 H
OS -2.68826234 44.69411432
OS -2.98017692 44.57320016
OS -3.23084952 44.38085104
OS -3.42319864 44.13017844
OS -3.5441128 43.83826386
OS -3.58535478 43.52500058
OS -3.5441128 43.2117373
OS -3.42319864 42.91982272
OS -3.23084952 42.66915012
OS -2.98017692 42.476801
OS -2.68826234 42.35588684
OS -2.37499906 42.31464486
OS -2.06173578 42.35588684
OS -1.7698212 42.476801
OS -1.5191486 42.66915012
OS -1.32679948 42.91982272
OS -1.20588532 43.2117373
OS -1.16464334 43.52500058
OS -1.20588532 43.83826386
OS -1.32679948 44.13017844
OS -1.5191486 44.38085104
OS -1.7698212 44.57320016
OS -2.06173578 44.69411432
OS -2.37499906 44.7353563
OE
OB 8.3379056 44.57499848 H
OS 8.0100932 44.57499848
OS 7.69344664 44.49015486
OS 7.40955084 44.32624866
OS 7.17775044 44.09444826
OS 7.01384424 43.81055246
OS 6.92900062 43.4939059
OS 6.92900062 43.1660935
OS 7.01384424 42.84944694
OS 7.17775044 42.56555114
OS 7.40955084 42.33375074
OS 7.69344664 42.16984454
OS 8.0100932 42.08500092
OS 8.3379056 42.08500092
OS 8.65455216 42.16984454
OS 8.93844796 42.33375074
OS 9.17024836 42.56555114
OS 9.33415456 42.84944694
OS 9.41899818 43.1660935
OS 9.41899818 43.4939059
OS 9.33415456 43.81055246
OS 9.17024836 44.09444826
OS 8.93844796 44.32624866
OS 8.65455216 44.49015486
OS 8.3379056 44.57499848
OE
OB 5.2899056 44.57499848 H
OS 4.9620932 44.57499848
OS 4.64544664 44.49015486
OS 4.36155084 44.32624866
OS 4.12975044 44.09444826
OS 3.96584424 43.81055246
OS 3.88100062 43.4939059
OS 3.88100062 43.1660935
OS 3.96584424 42.84944694
OS 4.12975044 42.56555114
OS 4.36155084 42.33375074
OS 4.64544664 42.16984454
OS 4.9620932 42.08500092
OS 5.2899056 42.08500092
OS 5.60655216 42.16984454
OS 5.89044796 42.33375074
OS 6.12224836 42.56555114
OS 6.28615456 42.84944694
OS 6.37099818 43.1660935
OS 6.37099818 43.4939059
OS 6.28615456 43.81055246
OS 6.12224836 44.09444826
OS 5.89044796 44.32624866
OS 5.60655216 44.49015486
OS 5.2899056 44.57499848
OE
OB 2.2419056 44.57499848 H
OS 1.9140932 44.57499848
OS 1.59744664 44.49015486
OS 1.31355084 44.32624866
OS 1.08175044 44.09444826
OS 0.91784424 43.81055246
OS 0.83300062 43.4939059
OS 0.83300062 43.1660935
OS 0.91784424 42.84944694
OS 1.08175044 42.56555114
OS 1.31355084 42.33375074
OS 1.59744664 42.16984454
OS 1.9140932 42.08500092
OS 2.2419056 42.08500092
OS 2.55855216 42.16984454
OS 2.84244796 42.33375074
OS 3.07424836 42.56555114
OS 3.23815456 42.84944694
OS 3.32299818 43.1660935
OS 3.32299818 43.4939059
OS 3.23815456 43.81055246
OS 3.07424836 44.09444826
OS 2.84244796 44.32624866
OS 2.55855216 44.49015486
OS 2.2419056 44.57499848
OE
OB 0.17101566 41.93899918 H
OS 0.12699492 41.93899918
OS 0.12699492 40.76701016
OS 1.29899918 40.76701016
OS 1.29899918 40.81101566
OS 1.2104751 41.141396
OS 1.0394569 41.43760318
OS 0.79760318 41.6794569
OS 0.501396 41.8504751
OS 0.17101566 41.93899918
OE
OB -0.12700508 41.93899918 H
OS -0.17101566 41.93899918
OS -0.501396 41.8504751
OS -0.79760318 41.6794569
OS -1.0394569 41.43760318
OS -1.2104751 41.141396
OS -1.29899918 40.81101566
OS -1.29899918 40.76701016
OS -0.12700508 40.76701016
OS -0.12700508 41.93899918
OE
OB 1.29899918 40.51301016 H
OS 0.12699492 40.51301016
OS 0.12699492 39.34100082
OS 0.17101566 39.34100082
OS 0.501396 39.4295249
OS 0.79760318 39.6005431
OS 1.0394569 39.84239682
OS 1.2104751 40.138604
OS 1.29899918 40.46898434
OS 1.29899918 40.51301016
OE
OB -0.12700508 40.51301016 H
OS -1.29899918 40.51301016
OS -1.29899918 40.46898434
OS -1.2104751 40.138604
OS -1.0394569 39.84239682
OS -0.79760318 39.6005431
OS -0.501396 39.4295249
OS -0.17101566 39.34100082
OS -0.12700508 39.34100082
OS -0.12700508 40.51301016
OE
OB 20.46429994 44.98999892 H
OS 20.01570038 44.98999892
OS 19.57262278 44.9198238
OS 19.14597898 44.78119822
OS 18.74627442 44.57753848
OS 18.38334906 44.31385854
OS 18.06614116 43.99665064
OS 17.80246122 43.63372528
OS 17.59880148 43.23402072
OS 17.4601759 42.80737692
OS 17.39000078 42.36429932
OS 17.39000078 41.91569976
OS 17.4601759 41.47262216
OS 17.59880148 41.04597836
OS 17.80246122 40.6462738
OS 18.06614116 40.28334844
OS 18.38334906 39.96614054
OS 18.74627442 39.7024606
OS 19.14597898 39.49880086
OS 19.57262278 39.36017528
OS 20.01570038 39.29000016
OS 20.46429994 39.29000016
OS 20.90737754 39.36017528
OS 21.33402134 39.49880086
OS 21.7337259 39.7024606
OS 22.09665126 39.96614054
OS 22.41385916 40.28334844
OS 22.6775391 40.6462738
OS 22.88119884 41.04597836
OS 23.01982442 41.47262216
OS 23.08999954 41.91569976
OS 23.08999954 42.36429932
OS 23.01982442 42.80737692
OS 22.88119884 43.23402072
OS 22.6775391 43.63372528
OS 22.41385916 43.99665064
OS 22.09665126 44.31385854
OS 21.7337259 44.57753848
OS 21.33402134 44.78119822
OS 20.90737754 44.9198238
OS 20.46429994 44.98999892
OE
OB 40.79216886 42.18499818 H
OS 40.48783114 42.18499818
OS 40.1893405 42.12562568
OS 39.90817012 42.00915906
OS 39.65512008 41.84007888
OS 39.43992112 41.62487992
OS 39.27084094 41.37182988
OS 39.15437432 41.0906595
OS 39.09500182 40.79216886
OS 39.09500182 40.48783114
OS 39.15437432 40.1893405
OS 39.27084094 39.90817012
OS 39.43992112 39.65512008
OS 39.65512008 39.43992112
OS 39.90817012 39.27084094
OS 40.1893405 39.15437432
OS 40.48783114 39.09500182
OS 40.79216886 39.09500182
OS 41.0906595 39.15437432
OS 41.37182988 39.27084094
OS 41.62487992 39.43992112
OS 41.84007888 39.65512008
OS 42.00915906 39.90817012
OS 42.12562568 40.1893405
OS 42.18499818 40.48783114
OS 42.18499818 40.79216886
OS 42.12562568 41.0906595
OS 42.00915906 41.37182988
OS 41.84007888 41.62487992
OS 41.62487992 41.84007888
OS 41.37182988 42.00915906
OS 41.0906595 42.12562568
OS 40.79216886 42.18499818
OE
OB 40.8039062 1.24499878 H
OS 40.4760938 1.24499878
OS 40.15944724 1.16015516
OS 39.87555144 0.99624896
OS 39.64375104 0.76444856
OS 39.47984484 0.48055276
OS 39.39500122 0.1639062
OS 39.39500122 -0.1639062
OS 39.47984484 -0.48055276
OS 39.64375104 -0.76444856
OS 39.87555144 -0.99624896
OS 40.15944724 -1.16015516
OS 40.4760938 -1.24499878
OS 40.8039062 -1.24499878
OS 41.12055276 -1.16015516
OS 41.40444856 -0.99624896
OS 41.63624896 -0.76444856
OS 41.80015516 -0.48055276
OS 41.88499878 -0.1639062
OS 41.88499878 0.1639062
OS 41.80015516 0.48055276
OS 41.63624896 0.76444856
OS 41.40444856 0.99624896
OS 41.12055276 1.16015516
OS 40.8039062 1.24499878
OE
OB 0.1639062 1.24499878 H
OS -0.1639062 1.24499878
OS -0.48055276 1.16015516
OS -0.76444856 0.99624896
OS -0.99624896 0.76444856
OS -1.16015516 0.48055276
OS -1.24499878 0.1639062
OS -1.24499878 -0.1639062
OS -1.16015516 -0.48055276
OS -0.99624896 -0.76444856
OS -0.76444856 -0.99624896
OS -0.48055276 -1.16015516
OS -0.1639062 -1.24499878
OS 0.1639062 -1.24499878
OS 0.48055276 -1.16015516
OS 0.76444856 -0.99624896
OS 0.99624896 -0.76444856
OS 1.16015516 -0.48055276
OS 1.24499878 -0.1639062
OS 1.24499878 0.1639062
OS 1.16015516 0.48055276
OS 0.99624896 0.76444856
OS 0.76444856 0.99624896
OS 0.48055276 1.16015516
OS 0.1639062 1.24499878
OE
OB 35.70190726 1.0499979 H
OS 35.29809298 1.0499979
OS 34.9020384 0.97121726
OS 34.52896066 0.81668366
OS 34.19320314 0.59233816
OS 33.90766142 0.30679644
OS 33.68331592 -0.02896108
OS 33.52878232 -0.40203882
OS 33.45000168 -0.7980934
OS 33.45000168 -1.20190768
OS 33.52878232 -1.59796226
OS 33.68331592 -1.97104
OS 33.90766142 -2.30679752
OS 34.19320314 -2.59233924
OS 34.52896066 -2.81668474
OS 34.9020384 -2.97121834
OS 35.29809298 -3.04999898
OS 35.70190726 -3.04999898
OS 36.09796184 -2.97121834
OS 36.47103958 -2.81668474
OS 36.8067971 -2.59233924
OS 37.09233882 -2.30679752
OS 37.31668432 -1.97104
OS 37.47121792 -1.59796226
OS 37.54999856 -1.20190768
OS 37.54999856 -0.7980934
OS 37.47121792 -0.40203882
OS 37.31668432 -0.02896108
OS 37.09233882 0.30679644
OS 36.8067971 0.59233816
OS 36.47103958 0.81668366
OS 36.09796184 0.97121726
OS 35.70190726 1.0499979
OE
OB -2.20000068 -1.48964396 H
OS -2.51326396 -1.53088594
OS -2.80517854 -1.6518001
OS -3.05585114 -1.84414922
OS -3.24820026 -2.09482182
OS -3.36911442 -2.3867364
OS -3.4103564 -2.69999968
OS -3.36911442 -3.01326296
OS -3.24820026 -3.30517754
OS -3.05585114 -3.55585014
OS -2.80517854 -3.74819926
OS -2.51326396 -3.86911342
OS -2.20000068 -3.9103554
OS -1.8867374 -3.86911342
OS -1.59482282 -3.74819926
OS -1.34415022 -3.55585014
OS -1.1518011 -3.30517754
OS -1.03088694 -3.01326296
OS -0.98964496 -2.69999968
OS -1.03088694 -2.3867364
OS -1.1518011 -2.09482182
OS -1.34415022 -1.84414922
OS -1.59482282 -1.6518001
OS -1.8867374 -1.53088594
OS -2.20000068 -1.48964396
OE
OB 20.66429954 1.58999936 H
OS 20.21569998 1.58999936
OS 19.77262238 1.51982424
OS 19.34597858 1.38119866
OS 18.94627402 1.17753892
OS 18.58334866 0.91385898
OS 18.26614076 0.59665108
OS 18.00246082 0.23372572
OS 17.79880108 -0.16597884
OS 17.6601755 -0.59262264
OS 17.59000038 -1.03570024
OS 17.59000038 -1.4842998
OS 17.6601755 -1.9273774
OS 17.79880108 -2.3540212
OS 18.00246082 -2.75372576
OS 18.26614076 -3.11665112
OS 18.58334866 -3.43385902
OS 18.94627402 -3.69753896
OS 19.34597858 -3.9011987
OS 19.77262238 -4.03982428
OS 20.21569998 -4.1099994
OS 20.66429954 -4.1099994
OS 21.10737714 -4.03982428
OS 21.53402094 -3.9011987
OS 21.9337255 -3.69753896
OS 22.29665086 -3.43385902
OS 22.61385876 -3.11665112
OS 22.8775387 -2.75372576
OS 23.08119844 -2.3540212
OS 23.21982402 -1.9273774
OS 23.28999914 -1.4842998
OS 23.28999914 -1.03570024
OS 23.21982402 -0.59262264
OS 23.08119844 -0.16597884
OS 22.8775387 0.23372572
OS 22.61385876 0.59665108
OS 22.29665086 0.91385898
OS 21.9337255 1.17753892
OS 21.53402094 1.38119866
OS 21.10737714 1.51982424
OS 20.66429954 1.58999936
OE
SE
S P 0
OB -2.56054098 -38.95999828 I
OS -2.63912858 -38.95999828
OS -2.63912858 -38.32020276
OS -2.56054098 -38.32020276
OS -2.56054098 -38.95999828
OE
OB -2.22215202 -38.48662356 I
OS -2.20828362 -38.48754812
OS -2.1925661 -38.48939724
OS -2.17684858 -38.49217092
OS -2.16113106 -38.49586916
OS -2.1463381 -38.50049196
OS -2.14448898 -38.50141652
OS -2.13986618 -38.50326564
OS -2.13339426 -38.50603932
OS -2.12507322 -38.50973756
OS -2.11582762 -38.51528492
OS -2.10658202 -38.52083228
OS -2.09826098 -38.52822876
OS -2.0908645 -38.53562524
OS -2.08993994 -38.5365498
OS -2.08809082 -38.53932348
OS -2.08531714 -38.54394628
OS -2.0816189 -38.54949364
OS -2.0769961 -38.55781468
OS -2.07329786 -38.56613572
OS -2.06959962 -38.57630588
OS -2.06682594 -38.58832516
OS -2.06682594 -38.58924972
OS -2.06590138 -38.5920234
OS -2.06497682 -38.59757076
OS -2.06405226 -38.60496724
OS -2.06405226 -38.6151374
OS -2.0631277 -38.62715668
OS -2.06220314 -38.6428742
OS -2.06220314 -38.66044084
OS -2.06220314 -38.76584068
OS -2.06220314 -38.76676524
OS -2.06220314 -38.77046348
OS -2.06220314 -38.77601084
OS -2.06220314 -38.78340732
OS -2.06220314 -38.79172836
OS -2.06220314 -38.80189852
OS -2.06127858 -38.82408796
OS -2.06127858 -38.84720196
OS -2.06035402 -38.87031596
OS -2.05942946 -38.88048612
OS -2.05942946 -38.88973172
OS -2.0585049 -38.89805276
OS -2.05758034 -38.90452468
OS -2.05758034 -38.90544924
OS -2.05665578 -38.90914748
OS -2.05573122 -38.91469484
OS -2.05295754 -38.92209132
OS -2.05110842 -38.93041236
OS -2.04741018 -38.93965796
OS -2.04278738 -38.94982812
OS -2.03816458 -38.95999828
OS -2.12045042 -38.95999828
OS -2.12137498 -38.95907372
OS -2.12229954 -38.95537548
OS -2.12414866 -38.95075268
OS -2.12692234 -38.9433562
OS -2.12969602 -38.93503516
OS -2.13154514 -38.924865
OS -2.13339426 -38.91377028
OS -2.13524338 -38.901751
OS -2.13616794 -38.901751
OS -2.1370925 -38.90360012
OS -2.14263986 -38.90822292
OS -2.1509609 -38.91469484
OS -2.16205562 -38.92301588
OS -2.17592402 -38.93133692
OS -2.18979242 -38.94058252
OS -2.20458538 -38.94890356
OS -2.2203029 -38.95537548
OS -2.22215202 -38.95630004
OS -2.22769938 -38.9572246
OS -2.23602042 -38.95999828
OS -2.24619058 -38.96277196
OS -2.25913442 -38.96554564
OS -2.27392738 -38.96739476
OS -2.29056946 -38.96924388
OS -2.30721154 -38.97016844
OS -2.31460802 -38.97016844
OS -2.32015538 -38.96924388
OS -2.3266273 -38.96924388
OS -2.33402378 -38.96831932
OS -2.35066586 -38.96554564
OS -2.36915706 -38.96092284
OS -2.38949738 -38.95445092
OS -2.40798858 -38.94520532
OS -2.42463066 -38.93318604
OS -2.42647978 -38.93133692
OS -2.43110258 -38.92671412
OS -2.4375745 -38.91839308
OS -2.44497098 -38.90729836
OS -2.45236746 -38.89342996
OS -2.45883938 -38.87771244
OS -2.46346218 -38.85829668
OS -2.46438674 -38.84905108
OS -2.4653113 -38.83795636
OS -2.4653113 -38.83610724
OS -2.4653113 -38.832409
OS -2.46438674 -38.82593708
OS -2.46346218 -38.81761604
OS -2.46161306 -38.80744588
OS -2.45883938 -38.79727572
OS -2.45514114 -38.786181
OS -2.45051834 -38.77601084
OS -2.44959378 -38.77508628
OS -2.44774466 -38.77138804
OS -2.44404642 -38.76584068
OS -2.43942362 -38.75936876
OS -2.43387626 -38.75197228
OS -2.42647978 -38.7445758
OS -2.4190833 -38.73717932
OS -2.4098377 -38.7307074
OS -2.40891314 -38.72978284
OS -2.4052149 -38.72793372
OS -2.4005921 -38.72423548
OS -2.39319562 -38.72053724
OS -2.38487458 -38.716839
OS -2.37470442 -38.7122162
OS -2.36453426 -38.70851796
OS -2.35251498 -38.70481972
OS -2.35159042 -38.70481972
OS -2.34789218 -38.70389516
OS -2.34234482 -38.70204604
OS -2.33494834 -38.70112148
OS -2.32570274 -38.69927236
OS -2.31368346 -38.69742324
OS -2.29981506 -38.69464956
OS -2.28317298 -38.69280044
OS -2.28224842 -38.69280044
OS -2.27855018 -38.69187588
OS -2.27392738 -38.69187588
OS -2.26745546 -38.69095132
OS -2.26005898 -38.69002676
OS -2.25081338 -38.68817764
OS -2.24064322 -38.68725308
OS -2.2295485 -38.68540396
OS -2.20735906 -38.68078116
OS -2.1833205 -38.67615836
OS -2.16205562 -38.670611
OS -2.15188546 -38.66783732
OS -2.14263986 -38.66506364
OS -2.14263986 -38.66413908
OS -2.14263986 -38.66228996
OS -2.1417153 -38.6567426
OS -2.1417153 -38.65027068
OS -2.1417153 -38.64657244
OS -2.1417153 -38.64472332
OS -2.1417153 -38.64379876
OS -2.1417153 -38.6428742
OS -2.1417153 -38.63732684
OS -2.14263986 -38.62808124
OS -2.14448898 -38.61791108
OS -2.14726266 -38.60681636
OS -2.15188546 -38.59572164
OS -2.15743282 -38.58555148
OS -2.1648293 -38.57723044
OS -2.16575386 -38.57630588
OS -2.17037666 -38.57260764
OS -2.17777314 -38.5689094
OS -2.18701874 -38.56336204
OS -2.19996258 -38.55873924
OS -2.21475554 -38.55411644
OS -2.23324674 -38.55134276
OS -2.25451162 -38.5504182
OS -2.26375722 -38.5504182
OS -2.27300282 -38.55134276
OS -2.28594666 -38.55319188
OS -2.2988905 -38.555041
OS -2.3127589 -38.55873924
OS -2.32570274 -38.56336204
OS -2.33679746 -38.56983396
OS -2.33772202 -38.57075852
OS -2.34142026 -38.5735322
OS -2.34604306 -38.578155
OS -2.35159042 -38.58555148
OS -2.35713778 -38.59479708
OS -2.3636097 -38.60681636
OS -2.36915706 -38.62160932
OS -2.37470442 -38.6382514
OS -2.4514429 -38.62808124
OS -2.4514429 -38.62715668
OS -2.45051834 -38.62623212
OS -2.45051834 -38.62345844
OS -2.44959378 -38.6197602
OS -2.4468201 -38.61143916
OS -2.44312186 -38.59941988
OS -2.43849906 -38.5874006
OS -2.4329517 -38.57445676
OS -2.42555522 -38.56151292
OS -2.41723418 -38.54949364
OS -2.41630962 -38.54856908
OS -2.41261138 -38.54487084
OS -2.40706402 -38.53932348
OS -2.39966754 -38.531927
OS -2.38949738 -38.52453052
OS -2.3774781 -38.51713404
OS -2.3636097 -38.508813
OS -2.34789218 -38.50234108
OS -2.34696762 -38.50234108
OS -2.34604306 -38.50141652
OS -2.34326938 -38.50049196
OS -2.33957114 -38.4995674
OS -2.33032554 -38.49679372
OS -2.3173817 -38.49402004
OS -2.30258874 -38.49124636
OS -2.28409754 -38.48847268
OS -2.26468178 -38.48662356
OS -2.24249234 -38.485699
OS -2.23232218 -38.485699
OS -2.22215202 -38.48662356
OE
OB -3.41206074 -38.48662356 I
OS -3.40558882 -38.48754812
OS -3.39172042 -38.48939724
OS -3.37507834 -38.49309548
OS -3.3575117 -38.49864284
OS -3.33994506 -38.50696388
OS -3.32237842 -38.51713404
OS -3.32145386 -38.51713404
OS -3.3205293 -38.51898316
OS -3.31498194 -38.5226814
OS -3.3066609 -38.53007788
OS -3.29649074 -38.53932348
OS -3.28539602 -38.55134276
OS -3.2743013 -38.56613572
OS -3.26320658 -38.58370236
OS -3.25396098 -38.60311812
OS -3.25396098 -38.60404268
OS -3.25303642 -38.6058918
OS -3.25211186 -38.60866548
OS -3.25026274 -38.61236372
OS -3.24841362 -38.61791108
OS -3.2465645 -38.624383
OS -3.2419417 -38.63917596
OS -3.2373189 -38.65766716
OS -3.23362066 -38.67800748
OS -3.23084698 -38.70112148
OS -3.22992242 -38.72516004
OS -3.22992242 -38.7260846
OS -3.22992242 -38.72793372
OS -3.22992242 -38.73163196
OS -3.22992242 -38.73717932
OS -3.23084698 -38.74365124
OS -3.23084698 -38.75104772
OS -3.2326961 -38.7676898
OS -3.23639434 -38.78803012
OS -3.24101714 -38.809295
OS -3.24748906 -38.83148444
OS -3.2558101 -38.85367388
OS -3.2558101 -38.85459844
OS -3.25673466 -38.85644756
OS -3.25858378 -38.85922124
OS -3.2604329 -38.86291948
OS -3.26690482 -38.87308964
OS -3.27522586 -38.88603348
OS -3.28539602 -38.89990188
OS -3.29833986 -38.91377028
OS -3.31313282 -38.92763868
OS -3.33069946 -38.94058252
OS -3.33162402 -38.94058252
OS -3.33254858 -38.94150708
OS -3.33532226 -38.9433562
OS -3.3390205 -38.94520532
OS -3.3482661 -38.94982812
OS -3.36120994 -38.95537548
OS -3.37692746 -38.96092284
OS -3.39356954 -38.96554564
OS -3.4129853 -38.96924388
OS -3.43240106 -38.97016844
OS -3.43887298 -38.97016844
OS -3.44626946 -38.96924388
OS -3.45551506 -38.96831932
OS -3.46660978 -38.9664702
OS -3.47862906 -38.96369652
OS -3.49064834 -38.95999828
OS -3.50266762 -38.95445092
OS -3.50359218 -38.95352636
OS -3.50821498 -38.95167724
OS -3.51376234 -38.947979
OS -3.52115882 -38.94243164
OS -3.5285553 -38.93688428
OS -3.5378009 -38.9294878
OS -3.54612194 -38.92116676
OS -3.55351842 -38.91192116
OS -3.55351842 -39.1375138
OS -3.63210602 -39.1375138
OS -3.63210602 -38.49586916
OS -3.5609149 -38.49586916
OS -3.5609149 -38.55689012
OS -3.55999034 -38.555041
OS -3.5562921 -38.55134276
OS -3.5516693 -38.54487084
OS -3.54427282 -38.53747436
OS -3.53595178 -38.52822876
OS -3.52670618 -38.51990772
OS -3.51561146 -38.51158668
OS -3.50451674 -38.5041902
OS -3.50266762 -38.50326564
OS -3.49896938 -38.50141652
OS -3.4915729 -38.49864284
OS -3.4823273 -38.4949446
OS -3.47123258 -38.49124636
OS -3.45828874 -38.48847268
OS -3.44349578 -38.48662356
OS -3.4268537 -38.485699
OS -3.41668354 -38.485699
OS -3.41206074 -38.48662356
OE
OB -2.6872057 -39.1375138 I
OS -3.20773298 -39.1375138
OS -3.20773298 -39.08111564
OS -2.6872057 -39.08111564
OS -2.6872057 -39.1375138
OE
OB -0.81127346 -38.48662356 I
OS -0.8011033 -38.48847268
OS -0.78908402 -38.49217092
OS -0.77614018 -38.49679372
OS -0.76134722 -38.50326564
OS -0.7456297 -38.51158668
OS -0.77429106 -38.58370236
OS -0.77521562 -38.5827778
OS -0.77891386 -38.58092868
OS -0.78446122 -38.578155
OS -0.7918577 -38.57538132
OS -0.80017874 -38.57260764
OS -0.8103489 -38.56983396
OS -0.82051906 -38.56798484
OS -0.83068922 -38.56706028
OS -0.83531202 -38.56706028
OS -0.83993482 -38.56798484
OS -0.84640674 -38.5689094
OS -0.85287866 -38.57075852
OS -0.8611997 -38.5735322
OS -0.86952074 -38.57723044
OS -0.87691722 -38.5827778
OS -0.87784178 -38.58370236
OS -0.88061546 -38.58555148
OS -0.88338914 -38.58924972
OS -0.88801194 -38.59387252
OS -0.89263474 -38.60034444
OS -0.89725754 -38.60774092
OS -0.90188034 -38.61606196
OS -0.90557858 -38.62623212
OS -0.90650314 -38.62808124
OS -0.9074277 -38.6336286
OS -0.90927682 -38.64194964
OS -0.9120505 -38.65304436
OS -0.91482418 -38.66691276
OS -0.9166733 -38.68263028
OS -0.91759786 -38.69927236
OS -0.91852242 -38.71776356
OS -0.91852242 -38.95999828
OS -0.99711002 -38.95999828
OS -0.99711002 -38.49586916
OS -0.9259189 -38.49586916
OS -0.9259189 -38.56613572
OS -0.92499434 -38.56521116
OS -0.9212961 -38.55873924
OS -0.9166733 -38.5504182
OS -0.90927682 -38.54024804
OS -0.90188034 -38.53007788
OS -0.8935593 -38.51898316
OS -0.88523826 -38.50973756
OS -0.87691722 -38.50234108
OS -0.87599266 -38.50141652
OS -0.87321898 -38.4995674
OS -0.86767162 -38.49679372
OS -0.86212426 -38.49402004
OS -0.85472778 -38.49124636
OS -0.84548218 -38.48847268
OS -0.83623658 -38.48662356
OS -0.82606642 -38.485699
OS -0.8195945 -38.485699
OS -0.81127346 -38.48662356
OE
OB -0.62821058 -38.42745172 I
OS -0.64947546 -38.54671996
OS -0.69847714 -38.54671996
OS -0.7178929 -38.42745172
OS -0.7178929 -38.32020276
OS -0.62821058 -38.32020276
OS -0.62821058 -38.42745172
OE
OB -1.73768258 -38.96739476 I
OS -1.73768258 -38.96831932
OS -1.73860714 -38.971093
OS -1.74045626 -38.97479124
OS -1.74230538 -38.97941404
OS -1.74507906 -38.98588596
OS -1.74785274 -38.99328244
OS -1.75432466 -39.00899996
OS -1.76079658 -39.0265666
OS -1.76819306 -39.04413324
OS -1.77558954 -39.05985076
OS -1.77928778 -39.06632268
OS -1.78206146 -39.0727946
OS -1.78298602 -39.07464372
OS -1.7857597 -39.07926652
OS -1.7903825 -39.08573844
OS -1.79592986 -39.09405948
OS -1.80332634 -39.10330508
OS -1.81164738 -39.11255068
OS -1.81996842 -39.12179628
OS -1.83013858 -39.12919276
OS -1.83106314 -39.13011732
OS -1.83476138 -39.13196644
OS -1.84030874 -39.13474012
OS -1.84862978 -39.13843836
OS -1.85787538 -39.1421366
OS -1.8689701 -39.14491028
OS -1.88098938 -39.1467594
OS -1.89485778 -39.14768396
OS -1.89855602 -39.14768396
OS -1.90317882 -39.1467594
OS -1.90965074 -39.1467594
OS -1.91704722 -39.14491028
OS -1.92536826 -39.14306116
OS -1.93461386 -39.14121204
OS -1.94478402 -39.1375138
OS -1.95310506 -39.06447356
OS -1.9521805 -39.06447356
OS -1.94848226 -39.06539812
OS -1.94385946 -39.06632268
OS -1.9383121 -39.0681718
OS -1.92351914 -39.07094548
OS -1.90872618 -39.07187004
OS -1.90410338 -39.07187004
OS -1.89948058 -39.07094548
OS -1.89393322 -39.07094548
OS -1.88006482 -39.0681718
OS -1.8735929 -39.06539812
OS -1.86712098 -39.06262444
OS -1.86619642 -39.06262444
OS -1.8643473 -39.06077532
OS -1.86157362 -39.0589262
OS -1.85787538 -39.05615252
OS -1.84955434 -39.04875604
OS -1.84215786 -39.03858588
OS -1.84215786 -39.03766132
OS -1.84030874 -39.0358122
OS -1.83845962 -39.03211396
OS -1.8366105 -39.0265666
OS -1.83291226 -39.01917012
OS -1.82921402 -39.0080754
OS -1.82366666 -38.99513156
OS -1.8181193 -38.97941404
OS -1.8181193 -38.97848948
OS -1.81627018 -38.97479124
OS -1.81442106 -38.96831932
OS -1.81072282 -38.95999828
OS -1.98638922 -38.49586916
OS -1.90317882 -38.49586916
OS -1.80610002 -38.76491612
OS -1.80610002 -38.76584068
OS -1.80517546 -38.76676524
OS -1.8042509 -38.76953892
OS -1.80332634 -38.77416172
OS -1.80147722 -38.77878452
OS -1.7996281 -38.78433188
OS -1.7950053 -38.79727572
OS -1.78945794 -38.81299324
OS -1.78391058 -38.83148444
OS -1.77836322 -38.8509002
OS -1.77281586 -38.87216508
OS -1.77281586 -38.87124052
OS -1.7718913 -38.8693914
OS -1.77096674 -38.86661772
OS -1.77004218 -38.86291948
OS -1.76911762 -38.85829668
OS -1.7672685 -38.85274932
OS -1.76357026 -38.83888092
OS -1.75894746 -38.8231634
OS -1.75247554 -38.8046722
OS -1.74692818 -38.786181
OS -1.7395317 -38.76676524
OS -1.63967922 -38.49586916
OS -1.56109162 -38.49586916
OS -1.73768258 -38.96739476
OE
OB -1.28834642 -38.48662356 I
OS -1.28094994 -38.48754812
OS -1.27170434 -38.48939724
OS -1.26153418 -38.49124636
OS -1.2495149 -38.49402004
OS -1.23842018 -38.49679372
OS -1.22547634 -38.50141652
OS -1.21345706 -38.50603932
OS -1.20051322 -38.51251124
OS -1.18756938 -38.51990772
OS -1.17462554 -38.52822876
OS -1.16260626 -38.53839892
OS -1.15151154 -38.54949364
OS -1.15058698 -38.5504182
OS -1.14873786 -38.55226732
OS -1.14596418 -38.55596556
OS -1.14226594 -38.56151292
OS -1.13764314 -38.56798484
OS -1.13302034 -38.57538132
OS -1.12747298 -38.58462692
OS -1.12192562 -38.59572164
OS -1.11637826 -38.60774092
OS -1.1108309 -38.62068476
OS -1.1062081 -38.63547772
OS -1.1015853 -38.65119524
OS -1.09788706 -38.66876188
OS -1.09511338 -38.68725308
OS -1.09326426 -38.70666884
OS -1.0923397 -38.72793372
OS -1.0923397 -38.72885828
OS -1.0923397 -38.73255652
OS -1.0923397 -38.73902844
OS -1.09326426 -38.74827404
OS -1.43997426 -38.74827404
OS -1.43997426 -38.7491986
OS -1.43997426 -38.75197228
OS -1.4390497 -38.75567052
OS -1.4390497 -38.76121788
OS -1.43812514 -38.7676898
OS -1.43627602 -38.77508628
OS -1.43350234 -38.79172836
OS -1.42795498 -38.81021956
OS -1.4205585 -38.83055988
OS -1.41038834 -38.84905108
OS -1.3974445 -38.86569316
OS -1.39651994 -38.86569316
OS -1.39559538 -38.86754228
OS -1.39004802 -38.87216508
OS -1.38172698 -38.878637
OS -1.37063226 -38.88510892
OS -1.3558393 -38.8925054
OS -1.33919722 -38.89897732
OS -1.32070602 -38.90360012
OS -1.31053586 -38.90452468
OS -1.29944114 -38.90544924
OS -1.29204466 -38.90544924
OS -1.28372362 -38.90452468
OS -1.27355346 -38.90267556
OS -1.26245874 -38.89990188
OS -1.2495149 -38.89620364
OS -1.23749562 -38.89065628
OS -1.22547634 -38.8832598
OS -1.22455178 -38.88233524
OS -1.21992898 -38.878637
OS -1.21438162 -38.87308964
OS -1.2079097 -38.86569316
OS -1.20051322 -38.855523
OS -1.19219218 -38.84257916
OS -1.18387114 -38.8277862
OS -1.17647466 -38.81021956
OS -1.09511338 -38.82038972
OS -1.09511338 -38.82131428
OS -1.09603794 -38.8231634
OS -1.0969625 -38.82686164
OS -1.09881162 -38.832409
OS -1.1015853 -38.83795636
OS -1.10435898 -38.84535284
OS -1.11175546 -38.86107036
OS -1.12100106 -38.878637
OS -1.1339449 -38.8971282
OS -1.14873786 -38.91469484
OS -1.16722906 -38.93133692
OS -1.16815362 -38.93133692
OS -1.17000274 -38.93318604
OS -1.17277642 -38.93503516
OS -1.17647466 -38.93780884
OS -1.18202202 -38.94058252
OS -1.18756938 -38.9433562
OS -1.19496586 -38.94705444
OS -1.2032869 -38.95075268
OS -1.2125325 -38.95445092
OS -1.2217781 -38.95814916
OS -1.2448921 -38.96369652
OS -1.27077978 -38.96831932
OS -1.29944114 -38.97016844
OS -1.3096113 -38.97016844
OS -1.31608322 -38.96924388
OS -1.32440426 -38.96831932
OS -1.33457442 -38.9664702
OS -1.34566914 -38.96462108
OS -1.35768842 -38.96277196
OS -1.3835761 -38.95537548
OS -1.3974445 -38.94982812
OS -1.41038834 -38.94428076
OS -1.42425674 -38.93688428
OS -1.43720058 -38.92856324
OS -1.44921986 -38.91931764
OS -1.46123914 -38.90822292
OS -1.4621637 -38.90729836
OS -1.46401282 -38.90544924
OS -1.4667865 -38.901751
OS -1.47048474 -38.89620364
OS -1.47510754 -38.88973172
OS -1.47973034 -38.88233524
OS -1.4852777 -38.87308964
OS -1.49082506 -38.86291948
OS -1.49637242 -38.8509002
OS -1.50191978 -38.83795636
OS -1.50654258 -38.8231634
OS -1.51116538 -38.80744588
OS -1.51486362 -38.7908038
OS -1.5176373 -38.7723126
OS -1.51948642 -38.75289684
OS -1.52041098 -38.73255652
OS -1.52041098 -38.73163196
OS -1.52041098 -38.72700916
OS -1.52041098 -38.7214618
OS -1.51948642 -38.71314076
OS -1.51856186 -38.7029706
OS -1.5176373 -38.69187588
OS -1.51578818 -38.67893204
OS -1.5130145 -38.6659882
OS -1.50561802 -38.63640228
OS -1.50099522 -38.62160932
OS -1.49544786 -38.6058918
OS -1.48805138 -38.59109884
OS -1.47973034 -38.57723044
OS -1.47048474 -38.56336204
OS -1.46031458 -38.5504182
OS -1.45939002 -38.54949364
OS -1.4575409 -38.54764452
OS -1.45384266 -38.54487084
OS -1.44921986 -38.54024804
OS -1.4436725 -38.53562524
OS -1.43627602 -38.53007788
OS -1.42795498 -38.52360596
OS -1.41778482 -38.5180586
OS -1.40761466 -38.51158668
OS -1.39559538 -38.50603932
OS -1.38265154 -38.50049196
OS -1.36878314 -38.49586916
OS -1.35399018 -38.49124636
OS -1.33827266 -38.48847268
OS -1.32163058 -38.48662356
OS -1.30406394 -38.485699
OS -1.29481834 -38.485699
OS -1.28834642 -38.48662356
OE
OB -3.9261161 -38.48662356 I
OS -3.91779506 -38.48754812
OS -3.90854946 -38.48939724
OS -3.8983793 -38.49124636
OS -3.88636002 -38.49309548
OS -3.8613969 -38.50141652
OS -3.84845306 -38.50603932
OS -3.83550922 -38.51251124
OS -3.82256538 -38.51898316
OS -3.80962154 -38.52822876
OS -3.79760226 -38.53747436
OS -3.78558298 -38.54856908
OS -3.78465842 -38.54949364
OS -3.7828093 -38.55134276
OS -3.78003562 -38.555041
OS -3.77633738 -38.5596638
OS -3.77171458 -38.56613572
OS -3.76616722 -38.57445676
OS -3.76061986 -38.58370236
OS -3.7550725 -38.59387252
OS -3.74952514 -38.60496724
OS -3.74397778 -38.61883564
OS -3.73843042 -38.63270404
OS -3.73380762 -38.64842156
OS -3.73010938 -38.66506364
OS -3.7273357 -38.68263028
OS -3.72548658 -38.70112148
OS -3.72456202 -38.7214618
OS -3.72456202 -38.72238636
OS -3.72456202 -38.72516004
OS -3.72456202 -38.72978284
OS -3.72456202 -38.73625476
OS -3.72548658 -38.74365124
OS -3.72641114 -38.75289684
OS -3.72641114 -38.76214244
OS -3.72826026 -38.7723126
OS -3.73103394 -38.7954266
OS -3.7365813 -38.8185406
OS -3.74305322 -38.8416546
OS -3.75229882 -38.86291948
OS -3.75229882 -38.86384404
OS -3.75322338 -38.8647686
OS -3.7550725 -38.86754228
OS -3.75692162 -38.87124052
OS -3.76339354 -38.88048612
OS -3.77171458 -38.89158084
OS -3.7828093 -38.90452468
OS -3.7966777 -38.91746852
OS -3.81239522 -38.93041236
OS -3.83088642 -38.94243164
OS -3.83181098 -38.94243164
OS -3.83273554 -38.9433562
OS -3.83550922 -38.94520532
OS -3.84013202 -38.94705444
OS -3.84475482 -38.94890356
OS -3.85030218 -38.95075268
OS -3.86417058 -38.95630004
OS -3.8798881 -38.96092284
OS -3.89930386 -38.96554564
OS -3.91964418 -38.96924388
OS -3.94183362 -38.97016844
OS -3.95107922 -38.97016844
OS -3.9584757 -38.96924388
OS -3.96679674 -38.96831932
OS -3.97604234 -38.9664702
OS -3.98713706 -38.96462108
OS -3.99823178 -38.96277196
OS -4.0231949 -38.95537548
OS -4.0370633 -38.94982812
OS -4.05000714 -38.94428076
OS -4.06295098 -38.93688428
OS -4.07589482 -38.92856324
OS -4.0879141 -38.91931764
OS -4.09993338 -38.90822292
OS -4.10085794 -38.90729836
OS -4.10270706 -38.90544924
OS -4.10548074 -38.901751
OS -4.10917898 -38.89620364
OS -4.11380178 -38.88973172
OS -4.11842458 -38.88233524
OS -4.12397194 -38.87308964
OS -4.1295193 -38.86199492
OS -4.13506666 -38.84997564
OS -4.14061402 -38.83610724
OS -4.14523682 -38.82131428
OS -4.14985962 -38.80559676
OS -4.15355786 -38.78803012
OS -4.15633154 -38.76953892
OS -4.15818066 -38.7491986
OS -4.15910522 -38.72793372
OS -4.15910522 -38.7260846
OS -4.15910522 -38.72238636
OS -4.15818066 -38.71591444
OS -4.15818066 -38.70666884
OS -4.1572561 -38.69649868
OS -4.15540698 -38.68355484
OS -4.15355786 -38.670611
OS -4.14985962 -38.65581804
OS -4.14616138 -38.64102508
OS -4.14153858 -38.62530756
OS -4.13599122 -38.60866548
OS -4.12859474 -38.59294796
OS -4.12119826 -38.578155
OS -4.1110281 -38.56336204
OS -4.10085794 -38.54949364
OS -4.0879141 -38.53747436
OS -4.08698954 -38.5365498
OS -4.08514042 -38.53562524
OS -4.08144218 -38.53285156
OS -4.07681938 -38.52915332
OS -4.07127202 -38.52545508
OS -4.06387554 -38.52083228
OS -4.05647906 -38.51620948
OS -4.04723346 -38.51158668
OS -4.0370633 -38.50696388
OS -4.02596858 -38.50234108
OS -4.00100546 -38.49402004
OS -3.9723441 -38.48754812
OS -3.95755114 -38.48662356
OS -3.94183362 -38.485699
OS -3.93258802 -38.485699
OS -3.9261161 -38.48662356
OE
OB -5.4655085 -38.31835364 I
OS -5.45348922 -38.32020276
OS -5.43962082 -38.32297644
OS -5.42482786 -38.32667468
OS -5.40911034 -38.33129748
OS -5.39431738 -38.33869396
OS -5.39339282 -38.33869396
OS -5.39246826 -38.33961852
OS -5.38784546 -38.3423922
OS -5.38044898 -38.347015
OS -5.37120338 -38.35348692
OS -5.36103322 -38.36273252
OS -5.3499385 -38.37290268
OS -5.33976834 -38.38492196
OS -5.32959818 -38.39879036
OS -5.32867362 -38.40063948
OS -5.32497538 -38.40526228
OS -5.32127714 -38.41358332
OS -5.31480522 -38.4256026
OS -5.30925786 -38.439471
OS -5.30186138 -38.45518852
OS -5.29538946 -38.47367972
OS -5.2898421 -38.49402004
OS -5.2898421 -38.4949446
OS -5.28891754 -38.49679372
OS -5.28799298 -38.4995674
OS -5.28706842 -38.5041902
OS -5.28614386 -38.50973756
OS -5.2852193 -38.51620948
OS -5.28337018 -38.52453052
OS -5.28244562 -38.53377612
OS -5.2805965 -38.54394628
OS -5.27967194 -38.555041
OS -5.27874738 -38.56798484
OS -5.27689826 -38.58092868
OS -5.2759737 -38.59572164
OS -5.2759737 -38.6105146
OS -5.27504914 -38.62715668
OS -5.27504914 -38.64472332
OS -5.27504914 -38.64564788
OS -5.27504914 -38.64934612
OS -5.27504914 -38.65581804
OS -5.27504914 -38.66321452
OS -5.2759737 -38.67338468
OS -5.2759737 -38.6844794
OS -5.27689826 -38.69649868
OS -5.27782282 -38.70944252
OS -5.2805965 -38.73902844
OS -5.2852193 -38.76953892
OS -5.29076666 -38.79912484
OS -5.2944649 -38.81299324
OS -5.2990877 -38.82686164
OS -5.2990877 -38.8277862
OS -5.30001226 -38.82963532
OS -5.30186138 -38.83333356
OS -5.3037105 -38.83795636
OS -5.30555962 -38.84442828
OS -5.30925786 -38.8509002
OS -5.31665434 -38.86661772
OS -5.32589994 -38.8832598
OS -5.33791922 -38.901751
OS -5.35178762 -38.91839308
OS -5.3684297 -38.9341106
OS -5.36935426 -38.9341106
OS -5.37027882 -38.93595972
OS -5.3730525 -38.93780884
OS -5.37675074 -38.93965796
OS -5.38137354 -38.94243164
OS -5.38599634 -38.94612988
OS -5.39986474 -38.9526018
OS -5.41650682 -38.95907372
OS -5.43592258 -38.96554564
OS -5.45903658 -38.96924388
OS -5.4839997 -38.971093
OS -5.4932453 -38.971093
OS -5.49971722 -38.97016844
OS -5.5071137 -38.96924388
OS -5.5163593 -38.96739476
OS -5.52652946 -38.96554564
OS -5.53762418 -38.96277196
OS -5.5487189 -38.95907372
OS -5.56073818 -38.95537548
OS -5.57275746 -38.94982812
OS -5.58477674 -38.9433562
OS -5.59679602 -38.93595972
OS -5.6088153 -38.92671412
OS -5.61991002 -38.91654396
OS -5.63008018 -38.90544924
OS -5.63100474 -38.90452468
OS -5.63285386 -38.901751
OS -5.63562754 -38.8971282
OS -5.64025034 -38.88973172
OS -5.64487314 -38.88141068
OS -5.64949594 -38.87031596
OS -5.65596786 -38.85737212
OS -5.66151522 -38.84257916
OS -5.66706258 -38.82593708
OS -5.67260994 -38.80652132
OS -5.6781573 -38.78525644
OS -5.6827801 -38.76121788
OS -5.6874029 -38.7353302
OS -5.69017658 -38.7075934
OS -5.6920257 -38.67708292
OS -5.69295026 -38.64472332
OS -5.69295026 -38.64379876
OS -5.69295026 -38.64010052
OS -5.69295026 -38.6336286
OS -5.69295026 -38.62623212
OS -5.6920257 -38.61606196
OS -5.6920257 -38.60496724
OS -5.69110114 -38.59294796
OS -5.69017658 -38.57907956
OS -5.6874029 -38.5504182
OS -5.6827801 -38.51990772
OS -5.67723274 -38.48939724
OS -5.6735345 -38.47552884
OS -5.66983626 -38.46166044
OS -5.66983626 -38.46073588
OS -5.6689117 -38.45888676
OS -5.66706258 -38.45518852
OS -5.66521346 -38.45056572
OS -5.66336434 -38.4440938
OS -5.6596661 -38.43762188
OS -5.65226962 -38.42190436
OS -5.64302402 -38.40526228
OS -5.63100474 -38.38769564
OS -5.61713634 -38.370129
OS -5.60049426 -38.35533604
OS -5.5995697 -38.35533604
OS -5.59864514 -38.35348692
OS -5.59587146 -38.3516378
OS -5.59217322 -38.34978868
OS -5.58755042 -38.34609044
OS -5.58200306 -38.34331676
OS -5.56813466 -38.33592028
OS -5.55149258 -38.32944836
OS -5.53207682 -38.32297644
OS -5.50896282 -38.3192782
OS -5.4839997 -38.31742908
OS -5.47567866 -38.31742908
OS -5.4655085 -38.31835364
OE
OB -4.89967778 -38.95999828 I
OS -4.97826538 -38.95999828
OS -4.97826538 -38.45981132
OS -4.97918994 -38.46073588
OS -4.98381274 -38.46443412
OS -4.9893601 -38.46998148
OS -4.9986057 -38.4764534
OS -5.00877586 -38.48477444
OS -5.0217197 -38.49402004
OS -5.03651266 -38.5041902
OS -5.05315474 -38.51436036
OS -5.0540793 -38.51436036
OS -5.05500386 -38.51528492
OS -5.06055122 -38.51898316
OS -5.06979682 -38.52360596
OS -5.08089154 -38.52915332
OS -5.09383538 -38.53562524
OS -5.10770378 -38.54209716
OS -5.12157218 -38.54856908
OS -5.13544058 -38.55411644
OS -5.13544058 -38.47830252
OS -5.13451602 -38.47830252
OS -5.1326669 -38.4764534
OS -5.12896866 -38.47552884
OS -5.12434586 -38.47275516
OS -5.1187985 -38.46998148
OS -5.11232658 -38.46628324
OS -5.09660906 -38.45703764
OS -5.07811786 -38.44686748
OS -5.05962666 -38.43392364
OS -5.0402109 -38.41913068
OS -5.02079514 -38.40341316
OS -5.01987058 -38.4024886
OS -5.01894602 -38.40156404
OS -5.01617234 -38.39879036
OS -5.0124741 -38.39601668
OS -5.00415306 -38.38677108
OS -4.99305834 -38.37567636
OS -4.98196362 -38.36273252
OS -4.96994434 -38.34793956
OS -4.95977418 -38.3331466
OS -4.95052858 -38.31742908
OS -4.89967778 -38.31742908
OS -4.89967778 -38.95999828
OE
OB -5.79280274 -38.95999828 I
OS -5.87139034 -38.95999828
OS -5.87139034 -38.32020276
OS -5.79280274 -38.32020276
OS -5.79280274 -38.95999828
OE
OB -5.97031826 -38.42745172 I
OS -5.99158314 -38.54671996
OS -6.04058482 -38.54671996
OS -6.06000058 -38.42745172
OS -6.06000058 -38.32020276
OS -5.97031826 -38.32020276
OS -5.97031826 -38.42745172
OE
OB -4.2866945 -38.49586916 I
OS -4.20718234 -38.49586916
OS -4.20718234 -38.55689012
OS -4.2866945 -38.55689012
OS -4.2866945 -38.82963532
OS -4.2866945 -38.83148444
OS -4.2866945 -38.83518268
OS -4.2866945 -38.84073004
OS -4.28576994 -38.84720196
OS -4.28484538 -38.86199492
OS -4.28392082 -38.86846684
OS -4.28299626 -38.87308964
OS -4.2820717 -38.87493876
OS -4.27929802 -38.878637
OS -4.27559978 -38.8832598
OS -4.26912786 -38.8878826
OS -4.26727874 -38.88880716
OS -4.26265594 -38.89065628
OS -4.2543349 -38.8925054
OS -4.24231562 -38.89342996
OS -4.23307002 -38.89342996
OS -4.22844722 -38.8925054
OS -4.2219753 -38.8925054
OS -4.21457882 -38.89158084
OS -4.20718234 -38.89065628
OS -4.19701218 -38.95999828
OS -4.1988613 -38.95999828
OS -4.20255954 -38.96092284
OS -4.20903146 -38.9618474
OS -4.2173525 -38.96277196
OS -4.2265981 -38.96462108
OS -4.23676826 -38.96554564
OS -4.25710858 -38.9664702
OS -4.26450506 -38.9664702
OS -4.27190154 -38.96554564
OS -4.28114714 -38.96462108
OS -4.29224186 -38.96369652
OS -4.30333658 -38.96092284
OS -4.31350674 -38.95814916
OS -4.3236769 -38.95352636
OS -4.32460146 -38.9526018
OS -4.32737514 -38.95075268
OS -4.33107338 -38.947979
OS -4.33662074 -38.9433562
OS -4.34124354 -38.9387334
OS -4.3467909 -38.93226148
OS -4.35233826 -38.92578956
OS -4.3560365 -38.91746852
OS -4.3560365 -38.91654396
OS -4.35788562 -38.91284572
OS -4.35881018 -38.9063738
OS -4.3606593 -38.8971282
OS -4.36250842 -38.88510892
OS -4.36343298 -38.87771244
OS -4.36343298 -38.8693914
OS -4.36435754 -38.85922124
OS -4.3652821 -38.84905108
OS -4.3652821 -38.83795636
OS -4.3652821 -38.82501252
OS -4.3652821 -38.55689012
OS -4.42352938 -38.55689012
OS -4.42352938 -38.49586916
OS -4.3652821 -38.49586916
OS -4.3652821 -38.38122372
OS -4.2866945 -38.33407116
OS -4.2866945 -38.49586916
OE
OB -4.46421002 -38.7676898 I
OS -4.7073693 -38.7676898
OS -4.7073693 -38.6891022
OS -4.46421002 -38.6891022
OS -4.46421002 -38.7676898
OE
OB -3.43425018 -38.54764452 H
OS -3.43887298 -38.54764452
OS -3.44257122 -38.54856908
OS -3.45181682 -38.5504182
OS -3.4638361 -38.55319188
OS -3.4777045 -38.55873924
OS -3.49249746 -38.56706028
OS -3.5008185 -38.57260764
OS -3.50821498 -38.57907956
OS -3.51561146 -38.58647604
OS -3.52300794 -38.59479708
OS -3.52300794 -38.59572164
OS -3.52485706 -38.5966462
OS -3.52670618 -38.59941988
OS -3.5285553 -38.60311812
OS -3.53132898 -38.60866548
OS -3.53502722 -38.61421284
OS -3.53872546 -38.62160932
OS -3.54149914 -38.6290058
OS -3.54519738 -38.6382514
OS -3.54889562 -38.64842156
OS -3.5516693 -38.65951628
OS -3.55536754 -38.67153556
OS -3.55721666 -38.68540396
OS -3.55906578 -38.69927236
OS -3.5609149 -38.71406532
OS -3.5609149 -38.7307074
OS -3.5609149 -38.73163196
OS -3.5609149 -38.73440564
OS -3.5609149 -38.73902844
OS -3.55999034 -38.74550036
OS -3.55999034 -38.75289684
OS -3.55906578 -38.76121788
OS -3.5562921 -38.78063364
OS -3.5516693 -38.80282308
OS -3.54612194 -38.82408796
OS -3.53687634 -38.84535284
OS -3.53132898 -38.85459844
OS -3.52485706 -38.86291948
OS -3.52300794 -38.8647686
OS -3.51838514 -38.8693914
OS -3.51098866 -38.87678788
OS -3.5008185 -38.88418436
OS -3.48787466 -38.89158084
OS -3.4730817 -38.89897732
OS -3.45643962 -38.90360012
OS -3.44719402 -38.90452468
OS -3.43794842 -38.90544924
OS -3.43240106 -38.90544924
OS -3.42870282 -38.90452468
OS -3.41945722 -38.90267556
OS -3.40651338 -38.89990188
OS -3.39264498 -38.89435452
OS -3.37785202 -38.88695804
OS -3.36305906 -38.87586332
OS -3.35566258 -38.8693914
OS -3.3482661 -38.86199492
OS -3.3482661 -38.86107036
OS -3.34641698 -38.8601458
OS -3.34456786 -38.85737212
OS -3.34271874 -38.85367388
OS -3.3390205 -38.84905108
OS -3.33624682 -38.84257916
OS -3.33254858 -38.83610724
OS -3.32885034 -38.8277862
OS -3.32607666 -38.81946516
OS -3.32237842 -38.80837044
OS -3.31868018 -38.79727572
OS -3.3159065 -38.78525644
OS -3.31405738 -38.77138804
OS -3.31220826 -38.75659508
OS -3.31035914 -38.74087756
OS -3.31035914 -38.72423548
OS -3.31035914 -38.72331092
OS -3.31035914 -38.72053724
OS -3.31035914 -38.71591444
OS -3.3112837 -38.70944252
OS -3.3112837 -38.70204604
OS -3.31220826 -38.693725
OS -3.31498194 -38.67430924
OS -3.31960474 -38.65304436
OS -3.32607666 -38.63177948
OS -3.33532226 -38.6105146
OS -3.34086962 -38.60034444
OS -3.34734154 -38.5920234
OS -3.34734154 -38.59109884
OS -3.34919066 -38.59017428
OS -3.35381346 -38.58462692
OS -3.36120994 -38.578155
OS -3.3713801 -38.56983396
OS -3.38432394 -38.56151292
OS -3.3991169 -38.55411644
OS -3.41575898 -38.54949364
OS -3.42500458 -38.54856908
OS -3.43425018 -38.54764452
OE
OB -3.94183362 -38.5504182 H
OS -3.94738098 -38.5504182
OS -3.95200378 -38.55134276
OS -3.96217394 -38.55226732
OS -3.97604234 -38.55596556
OS -3.99175986 -38.56151292
OS -4.00840194 -38.5689094
OS -4.02411946 -38.58000412
OS -4.0324405 -38.5874006
OS -4.03983698 -38.59479708
OS -4.03983698 -38.59572164
OS -4.0416861 -38.5966462
OS -4.04353522 -38.59941988
OS -4.0463089 -38.60311812
OS -4.04908258 -38.60774092
OS -4.05185626 -38.61328828
OS -4.0555545 -38.62068476
OS -4.05925274 -38.62808124
OS -4.06295098 -38.63732684
OS -4.06664922 -38.64657244
OS -4.0694229 -38.65766716
OS -4.07219658 -38.66968644
OS -4.07497026 -38.68263028
OS -4.07681938 -38.69649868
OS -4.07774394 -38.7122162
OS -4.0786685 -38.72793372
OS -4.0786685 -38.72885828
OS -4.0786685 -38.73163196
OS -4.0786685 -38.73625476
OS -4.07774394 -38.74272668
OS -4.07774394 -38.75012316
OS -4.07681938 -38.7584442
OS -4.0740457 -38.77785996
OS -4.0694229 -38.8000494
OS -4.06202642 -38.82223884
OS -4.05278082 -38.84350372
OS -4.0463089 -38.85274932
OS -4.03983698 -38.86199492
OS -4.03891242 -38.86199492
OS -4.03798786 -38.86384404
OS -4.0324405 -38.86846684
OS -4.02411946 -38.87586332
OS -4.01302474 -38.8832598
OS -3.99915634 -38.89158084
OS -3.98251426 -38.89897732
OS -3.9630985 -38.90360012
OS -3.95292834 -38.90452468
OS -3.94183362 -38.90544924
OS -3.93628626 -38.90544924
OS -3.93166346 -38.90452468
OS -3.9214933 -38.90267556
OS -3.9076249 -38.89990188
OS -3.89283194 -38.89435452
OS -3.87618986 -38.88695804
OS -3.86047234 -38.87586332
OS -3.8521513 -38.86846684
OS -3.84475482 -38.86107036
OS -3.84383026 -38.8601458
OS -3.8429057 -38.85922124
OS -3.84105658 -38.85644756
OS -3.8382829 -38.85274932
OS -3.83550922 -38.84812652
OS -3.83181098 -38.84257916
OS -3.82811274 -38.83518268
OS -3.8244145 -38.8277862
OS -3.82071626 -38.8185406
OS -3.81794258 -38.80837044
OS -3.81424434 -38.79727572
OS -3.81147066 -38.78525644
OS -3.80869698 -38.77138804
OS -3.80684786 -38.75751964
OS -3.80499874 -38.74180212
OS -3.80499874 -38.72516004
OS -3.80499874 -38.72423548
OS -3.80499874 -38.7214618
OS -3.80499874 -38.716839
OS -3.8059233 -38.71129164
OS -3.8059233 -38.70389516
OS -3.80684786 -38.69557412
OS -3.80962154 -38.67615836
OS -3.81424434 -38.65581804
OS -3.82164082 -38.6336286
OS -3.83181098 -38.61328828
OS -3.83735834 -38.60311812
OS -3.84475482 -38.59479708
OS -3.84475482 -38.59387252
OS -3.84660394 -38.59294796
OS -3.8521513 -38.5874006
OS -3.86047234 -38.58092868
OS -3.87156706 -38.57260764
OS -3.88543546 -38.5642866
OS -3.90207754 -38.55689012
OS -3.92056874 -38.55226732
OS -3.9307389 -38.55134276
OS -3.94183362 -38.5504182
OE
OB -5.48492426 -38.38214828 H
OS -5.49047162 -38.38214828
OS -5.49416986 -38.38307284
OS -5.50434002 -38.38492196
OS -5.5163593 -38.38769564
OS -5.5302277 -38.393243
OS -5.54502066 -38.40156404
OS -5.55241714 -38.4071114
OS -5.55981362 -38.41265876
OS -5.56628554 -38.42005524
OS -5.57275746 -38.42837628
OS -5.57275746 -38.42930084
OS -5.57460658 -38.43114996
OS -5.5764557 -38.4348482
OS -5.57922938 -38.439471
OS -5.58200306 -38.44686748
OS -5.5857013 -38.45518852
OS -5.58847498 -38.46535868
OS -5.59217322 -38.47737796
OS -5.59587146 -38.49124636
OS -5.5995697 -38.50696388
OS -5.60326794 -38.52453052
OS -5.60604162 -38.54394628
OS -5.6088153 -38.56613572
OS -5.61066442 -38.59017428
OS -5.61158898 -38.61606196
OS -5.61251354 -38.64472332
OS -5.61251354 -38.64657244
OS -5.61251354 -38.65119524
OS -5.61251354 -38.65951628
OS -5.61158898 -38.670611
OS -5.61158898 -38.68263028
OS -5.61066442 -38.69742324
OS -5.60973986 -38.71314076
OS -5.60789074 -38.72978284
OS -5.60326794 -38.76584068
OS -5.60049426 -38.78340732
OS -5.59679602 -38.8000494
OS -5.59309778 -38.81576692
OS -5.58755042 -38.83055988
OS -5.58200306 -38.84350372
OS -5.57553114 -38.85459844
OS -5.57553114 -38.855523
OS -5.57368202 -38.85644756
OS -5.56905922 -38.86291948
OS -5.56073818 -38.87124052
OS -5.55056802 -38.88048612
OS -5.53669962 -38.88973172
OS -5.5209821 -38.89805276
OS -5.50341546 -38.90452468
OS -5.49416986 -38.90544924
OS -5.4839997 -38.9063738
OS -5.47845234 -38.9063738
OS -5.4747541 -38.90544924
OS -5.4655085 -38.90360012
OS -5.45256466 -38.89990188
OS -5.43869626 -38.89342996
OS -5.42297874 -38.88418436
OS -5.41558226 -38.878637
OS -5.40818578 -38.87124052
OS -5.4007893 -38.86384404
OS -5.39339282 -38.85459844
OS -5.39339282 -38.85367388
OS -5.3915437 -38.85182476
OS -5.38969458 -38.84905108
OS -5.38784546 -38.84442828
OS -5.38414722 -38.83795636
OS -5.38137354 -38.82963532
OS -5.3776753 -38.82038972
OS -5.37397706 -38.809295
OS -5.37120338 -38.7954266
OS -5.36750514 -38.78063364
OS -5.3638069 -38.763067
OS -5.36103322 -38.7445758
OS -5.3591841 -38.72238636
OS -5.35733498 -38.69927236
OS -5.35548586 -38.67338468
OS -5.35548586 -38.64472332
OS -5.35548586 -38.64379876
OS -5.35548586 -38.6428742
OS -5.35548586 -38.6382514
OS -5.35548586 -38.62993036
OS -5.35641042 -38.61883564
OS -5.35641042 -38.60681636
OS -5.35733498 -38.5920234
OS -5.35825954 -38.57630588
OS -5.36010866 -38.55873924
OS -5.36473146 -38.52360596
OS -5.36750514 -38.50603932
OS -5.37120338 -38.48939724
OS -5.37490162 -38.47367972
OS -5.38044898 -38.45888676
OS -5.38599634 -38.44594292
OS -5.39246826 -38.4348482
OS -5.39246826 -38.43392364
OS -5.39431738 -38.43299908
OS -5.3961665 -38.4302254
OS -5.39894018 -38.42652716
OS -5.40726122 -38.41820612
OS -5.41743138 -38.40803596
OS -5.43129978 -38.39879036
OS -5.4470173 -38.39046932
OS -5.45533834 -38.38677108
OS -5.46458394 -38.3839974
OS -5.4747541 -38.38307284
OS -5.48492426 -38.38214828
OE
OB -2.1417153 -38.72700916 H
OS -2.14263986 -38.72700916
OS -2.14356442 -38.72793372
OS -2.1463381 -38.72885828
OS -2.15003634 -38.72978284
OS -2.15465914 -38.73163196
OS -2.1602065 -38.73348108
OS -2.16667842 -38.7353302
OS -2.1740749 -38.73717932
OS -2.18239594 -38.739953
OS -2.1925661 -38.74180212
OS -2.20273626 -38.7445758
OS -2.21475554 -38.74734948
OS -2.22769938 -38.75012316
OS -2.24064322 -38.75289684
OS -2.25543618 -38.75474596
OS -2.2711537 -38.75751964
OS -2.27300282 -38.75751964
OS -2.27855018 -38.7584442
OS -2.28779578 -38.76029332
OS -2.29796594 -38.76214244
OS -2.30906066 -38.76399156
OS -2.32015538 -38.76676524
OS -2.33032554 -38.76953892
OS -2.33957114 -38.77323716
OS -2.3404957 -38.77323716
OS -2.34326938 -38.77508628
OS -2.34696762 -38.7769354
OS -2.35066586 -38.77970908
OS -2.36176058 -38.78710556
OS -2.37100618 -38.79820028
OS -2.37100618 -38.79912484
OS -2.3728553 -38.80097396
OS -2.37377986 -38.8046722
OS -2.37562898 -38.809295
OS -2.3774781 -38.81484236
OS -2.37932722 -38.82038972
OS -2.38025178 -38.8277862
OS -2.38117634 -38.83518268
OS -2.38117634 -38.83610724
OS -2.38117634 -38.84073004
OS -2.38025178 -38.8462774
OS -2.37840266 -38.85367388
OS -2.37562898 -38.86199492
OS -2.37100618 -38.87031596
OS -2.36545882 -38.87956156
OS -2.35806234 -38.8878826
OS -2.35713778 -38.88880716
OS -2.35343954 -38.89065628
OS -2.34789218 -38.89435452
OS -2.3404957 -38.89805276
OS -2.33032554 -38.901751
OS -2.31830626 -38.90544924
OS -2.30443786 -38.90729836
OS -2.28779578 -38.90822292
OS -2.2803993 -38.90822292
OS -2.2711537 -38.90729836
OS -2.26098354 -38.90544924
OS -2.2480397 -38.90360012
OS -2.23509586 -38.89990188
OS -2.22122746 -38.89527908
OS -2.20735906 -38.88880716
OS -2.20550994 -38.8878826
OS -2.2018117 -38.88510892
OS -2.19533978 -38.88048612
OS -2.1879433 -38.8740142
OS -2.17962226 -38.86661772
OS -2.17037666 -38.85737212
OS -2.16298018 -38.8462774
OS -2.1555837 -38.83425812
OS -2.15465914 -38.83333356
OS -2.15373458 -38.82963532
OS -2.15188546 -38.8231634
OS -2.14911178 -38.81484236
OS -2.1463381 -38.80374764
OS -2.14448898 -38.7908038
OS -2.14356442 -38.77508628
OS -2.14263986 -38.75659508
OS -2.1417153 -38.72700916
OE
OB -1.30313938 -38.5504182 H
OS -1.30868674 -38.5504182
OS -1.31238498 -38.55134276
OS -1.32255514 -38.55226732
OS -1.33457442 -38.555041
OS -1.34936738 -38.5596638
OS -1.3650849 -38.56613572
OS -1.37987786 -38.57538132
OS -1.39467082 -38.5874006
OS -1.39651994 -38.58924972
OS -1.40021818 -38.59387252
OS -1.4066901 -38.60219356
OS -1.41316202 -38.61328828
OS -1.4205585 -38.62623212
OS -1.42703042 -38.6428742
OS -1.43257778 -38.66228996
OS -1.43535146 -38.68355484
OS -1.1755501 -38.68355484
OS -1.1755501 -38.68263028
OS -1.1755501 -38.68078116
OS -1.17647466 -38.67800748
OS -1.17647466 -38.67430924
OS -1.17832378 -38.66321452
OS -1.18109746 -38.65119524
OS -1.18572026 -38.63640228
OS -1.19034306 -38.62253388
OS -1.19773954 -38.60866548
OS -1.20606058 -38.5966462
OS -1.20606058 -38.59572164
OS -1.2079097 -38.59479708
OS -1.2125325 -38.58924972
OS -1.22085354 -38.58185324
OS -1.23194826 -38.5735322
OS -1.24581666 -38.56521116
OS -1.26245874 -38.55781468
OS -1.2818745 -38.55226732
OS -1.29204466 -38.55134276
OS -1.30313938 -38.5504182
OE
SE
S P 0
OB -4.66714078 -36.5016923 I
OS -4.65465922 -36.5016923
OS -4.62553558 -36.50307914
OS -4.5950251 -36.50723966
OS -4.56174094 -36.51140018
OS -4.53123046 -36.51833438
OS -4.51597522 -36.5224949
OS -4.50349366 -36.52665542
OS -4.50210682 -36.52665542
OS -4.50071998 -36.52804226
OS -4.49239894 -36.53220278
OS -4.47991738 -36.53775014
OS -4.46466214 -36.54745802
OS -4.44802006 -36.55993958
OS -4.42999114 -36.57658166
OS -4.41334906 -36.59599742
OS -4.39670698 -36.61818686
OS -4.39670698 -36.6195737
OS -4.39532014 -36.62096054
OS -4.38977278 -36.62928158
OS -4.38422542 -36.64314998
OS -4.37590438 -36.6611789
OS -4.36897018 -36.6819815
OS -4.36203598 -36.70694462
OS -4.35787546 -36.73329458
OS -4.35648862 -36.76241822
OS -4.35648862 -36.76380506
OS -4.35648862 -36.76657874
OS -4.35648862 -36.7721261
OS -4.35787546 -36.7790603
OS -4.35787546 -36.78876818
OS -4.3592623 -36.79847606
OS -4.36480966 -36.82205234
OS -4.3731307 -36.84978914
OS -4.38422542 -36.87891278
OS -4.4008675 -36.90803642
OS -4.41196222 -36.92190482
OS -4.42305694 -36.93577322
OS -4.42444378 -36.93716006
OS -4.42583062 -36.9385469
OS -4.42999114 -36.94270742
OS -4.4355385 -36.94686794
OS -4.4424727 -36.9524153
OS -4.45079374 -36.95796266
OS -4.46188846 -36.96489686
OS -4.47298318 -36.9732179
OS -4.48685158 -36.9801521
OS -4.50210682 -36.9870863
OS -4.5187489 -36.99540734
OS -4.53677782 -37.00234154
OS -4.55758042 -37.0078889
OS -4.57838302 -37.0148231
OS -4.6019593 -37.01898362
OS -4.62692242 -37.02314414
OS -4.62414874 -37.02453098
OS -4.61860138 -37.02730466
OS -4.61028034 -37.03285202
OS -4.59918562 -37.03839938
OS -4.5742225 -37.05365462
OS -4.56174094 -37.0633625
OS -4.55064622 -37.07168354
OS -4.54787254 -37.07445722
OS -4.54093834 -37.08139142
OS -4.52984362 -37.09248614
OS -4.51597522 -37.10635454
OS -4.50071998 -37.1257703
OS -4.48269106 -37.1465729
OS -4.46466214 -37.17153602
OS -4.44524638 -37.19927282
OS -4.28021242 -37.45999874
OS -4.43831218 -37.45999874
OS -4.56451462 -37.26029378
OS -4.56451462 -37.25890694
OS -4.5672883 -37.25613326
OS -4.57006198 -37.25197274
OS -4.5742225 -37.24642538
OS -4.58393038 -37.23117014
OS -4.59641194 -37.21175438
OS -4.61166718 -37.19095178
OS -4.62692242 -37.16876234
OS -4.64217766 -37.14795974
OS -4.65604606 -37.12854398
OS -4.6574329 -37.12715714
OS -4.66159342 -37.12160978
OS -4.66852762 -37.11328874
OS -4.6782355 -37.10358086
OS -4.6990381 -37.08277826
OS -4.71013282 -37.07307038
OS -4.72122754 -37.06474934
OS -4.72261438 -37.0633625
OS -4.72538806 -37.06197566
OS -4.73093542 -37.05920198
OS -4.73925646 -37.05504146
OS -4.7475775 -37.05088094
OS -4.75728538 -37.04672042
OS -4.77947482 -37.03978622
OS -4.78086166 -37.03978622
OS -4.78363534 -37.03839938
OS -4.7891827 -37.03839938
OS -4.7961169 -37.03701254
OS -4.80582478 -37.0356257
OS -4.8169195 -37.0356257
OS -4.83217474 -37.03423886
OS -4.99582186 -37.03423886
OS -4.99582186 -37.45999874
OS -5.12341114 -37.45999874
OS -5.12341114 -36.50030546
OS -4.6782355 -36.50030546
OS -4.66714078 -36.5016923
OE
OB -1.0100437 -37.45999874 I
OS -1.13208562 -37.45999874
OS -1.13208562 -36.65701838
OS -1.4122273 -37.45999874
OS -1.52594818 -37.45999874
OS -1.80331618 -36.64314998
OS -1.80331618 -37.45999874
OS -1.9253581 -37.45999874
OS -1.9253581 -36.50030546
OS -1.73536102 -36.50030546
OS -1.50791926 -37.1812439
OS -1.50791926 -37.18263074
OS -1.50653242 -37.18540442
OS -1.50514558 -37.18956494
OS -1.5023719 -37.19649914
OS -1.49682454 -37.21314122
OS -1.48989034 -37.23394382
OS -1.48295614 -37.2575201
OS -1.4746351 -37.28109638
OS -1.4677009 -37.30328582
OS -1.46215354 -37.32270158
OS -1.4607667 -37.3199279
OS -1.45937986 -37.3129937
OS -1.45521934 -37.30051214
OS -1.44967198 -37.28387006
OS -1.44273778 -37.26168062
OS -1.4330299 -37.23533066
OS -1.42332202 -37.20482018
OS -1.41084046 -37.16876234
OS -1.18062502 -36.50030546
OS -1.0100437 -36.50030546
OS -1.0100437 -37.45999874
OE
OB -2.02382374 -37.45999874 I
OS -2.1680551 -37.45999874
OS -2.28038914 -37.16876234
OS -2.68257274 -37.16876234
OS -2.78658574 -37.45999874
OS -2.92110922 -37.45999874
OS -2.55498346 -36.50030546
OS -2.41629946 -36.50030546
OS -2.02382374 -37.45999874
OE
OB -3.02928274 -37.45999874 I
OS -3.16103254 -37.45999874
OS -3.66306862 -36.70694462
OS -3.66306862 -37.45999874
OS -3.78511054 -37.45999874
OS -3.78511054 -36.50030546
OS -3.65474758 -36.50030546
OS -3.15132466 -37.25474642
OS -3.15132466 -36.50030546
OS -3.02928274 -36.50030546
OS -3.02928274 -37.45999874
OE
OB -5.3231161 -36.61402634 I
OS -5.89033366 -36.61402634
OS -5.89033366 -36.90664958
OS -5.35917394 -36.90664958
OS -5.35917394 -37.02037046
OS -5.89033366 -37.02037046
OS -5.89033366 -37.34627786
OS -5.30092666 -37.34627786
OS -5.30092666 -37.45999874
OS -6.01792294 -37.45999874
OS -6.01792294 -36.50030546
OS -5.3231161 -36.50030546
OS -5.3231161 -36.61402634
OE
OB -0.10721086 -36.61402634 I
OS -0.67442842 -36.61402634
OS -0.67442842 -36.90664958
OS -0.1432687 -36.90664958
OS -0.1432687 -37.02037046
OS -0.67442842 -37.02037046
OS -0.67442842 -37.34627786
OS -0.08502142 -37.34627786
OS -0.08502142 -37.45999874
OS -0.8020177 -37.45999874
OS -0.8020177 -36.50030546
OS -0.10721086 -36.50030546
OS -0.10721086 -36.61402634
OE
OB -8.43241138 -37.34627786 I
OS -7.95949894 -37.34627786
OS -7.95949894 -37.45999874
OS -8.56000066 -37.45999874
OS -8.56000066 -36.50030546
OS -8.43241138 -36.50030546
OS -8.43241138 -37.34627786
OE
OB -6.51718534 -37.05365462 I
OS -6.51718534 -37.45999874
OS -6.64477462 -37.45999874
OS -6.64477462 -37.05365462
OS -7.0150609 -36.50030546
OS -6.86112166 -36.50030546
OS -6.67251142 -36.79154186
OS -6.67251142 -36.7929287
OS -6.66973774 -36.79570238
OS -6.66696406 -36.7998629
OS -6.66419038 -36.80541026
OS -6.65864302 -36.81234446
OS -6.65309566 -36.8206655
OS -6.6406141 -36.8414681
OS -6.62535886 -36.86643122
OS -6.60871678 -36.89416802
OS -6.59068786 -36.92329166
OS -6.57404578 -36.95380214
OS -6.57404578 -36.9524153
OS -6.57265894 -36.94964162
OS -6.56988526 -36.9454811
OS -6.56572474 -36.93993374
OS -6.56156422 -36.93299954
OS -6.55601686 -36.9246785
OS -6.5435353 -36.9038759
OS -6.52828006 -36.87891278
OS -6.51025114 -36.84978914
OS -6.48944854 -36.81789182
OS -6.4672591 -36.78322082
OS -6.28280938 -36.50030546
OS -6.1344175 -36.50030546
OS -6.51718534 -37.05365462
OE
OB -7.01644774 -37.45999874 I
OS -7.1606791 -37.45999874
OS -7.27301314 -37.16876234
OS -7.67519674 -37.16876234
OS -7.77920974 -37.45999874
OS -7.91373322 -37.45999874
OS -7.54760746 -36.50030546
OS -7.40892346 -36.50030546
OS -7.01644774 -37.45999874
OE
OB -7.48103914 -36.60015794 H
OS -7.48103914 -36.60154478
OS -7.48242598 -36.60431846
OS -7.48242598 -36.60986582
OS -7.48519966 -36.61541318
OS -7.4865865 -36.62512106
OS -7.48936018 -36.63482894
OS -7.49490754 -36.65840522
OS -7.50184174 -36.68614202
OS -7.51154962 -36.7166525
OS -7.5212575 -36.74993666
OS -7.53373906 -36.78460766
OS -7.63775206 -37.06474934
OS -7.3132315 -37.06474934
OS -7.41308398 -36.80124974
OS -7.41308398 -36.7998629
OS -7.41447082 -36.79570238
OS -7.4172445 -36.78876818
OS -7.42001818 -36.78044714
OS -7.4241787 -36.77073926
OS -7.42833922 -36.7582577
OS -7.43249974 -36.7443893
OS -7.4380471 -36.7305209
OS -7.44914182 -36.69862358
OS -7.46023654 -36.66533942
OS -7.47133126 -36.63205526
OS -7.48103914 -36.60015794
OE
OB -4.69349074 -36.60709214 H
OS -4.99582186 -36.60709214
OS -4.99582186 -36.9246785
OS -4.71013282 -36.9246785
OS -4.69349074 -36.92329166
OS -4.67407498 -36.92190482
OS -4.65188554 -36.92051798
OS -4.6296961 -36.9177443
OS -4.60750666 -36.91358378
OS -4.5880909 -36.90803642
OS -4.58531722 -36.90664958
OS -4.57976986 -36.9038759
OS -4.57144882 -36.89971538
OS -4.5603541 -36.89416802
OS -4.54787254 -36.88584698
OS -4.53539098 -36.8761391
OS -4.52290942 -36.86365754
OS -4.51320154 -36.84978914
OS -4.5118147 -36.8484023
OS -4.50904102 -36.84285494
OS -4.5048805 -36.8345339
OS -4.49933314 -36.82343918
OS -4.49517262 -36.81095762
OS -4.4910121 -36.79708922
OS -4.48823842 -36.78044714
OS -4.48685158 -36.76380506
OS -4.48685158 -36.76241822
OS -4.48685158 -36.76103138
OS -4.48823842 -36.75271034
OS -4.48962526 -36.74022878
OS -4.49239894 -36.7235867
OS -4.49933314 -36.70694462
OS -4.50765418 -36.68752886
OS -4.52013574 -36.66949994
OS -4.53677782 -36.65147102
OS -4.5395515 -36.65008418
OS -4.5464857 -36.64453682
OS -4.55758042 -36.63760262
OS -4.57560934 -36.62928158
OS -4.59641194 -36.62096054
OS -4.62414874 -36.61402634
OS -4.65604606 -36.60847898
OS -4.69349074 -36.60709214
OE
OB -2.48841514 -36.60015794 H
OS -2.48841514 -36.60154478
OS -2.48980198 -36.60431846
OS -2.48980198 -36.60986582
OS -2.49257566 -36.61541318
OS -2.4939625 -36.62512106
OS -2.49673618 -36.63482894
OS -2.50228354 -36.65840522
OS -2.50921774 -36.68614202
OS -2.51892562 -36.7166525
OS -2.5286335 -36.74993666
OS -2.54111506 -36.78460766
OS -2.64512806 -37.06474934
OS -2.3206075 -37.06474934
OS -2.42045998 -36.80124974
OS -2.42045998 -36.7998629
OS -2.42184682 -36.79570238
OS -2.4246205 -36.78876818
OS -2.42739418 -36.78044714
OS -2.4315547 -36.77073926
OS -2.43571522 -36.7582577
OS -2.43987574 -36.7443893
OS -2.4454231 -36.7305209
OS -2.45651782 -36.69862358
OS -2.46761254 -36.66533942
OS -2.47870726 -36.63205526
OS -2.48841514 -36.60015794
OE
SE
S P 0
OB 35.73690338 -37.45999874 I
OS 35.61486146 -37.45999874
OS 35.61486146 -36.65701838
OS 35.33471978 -37.45999874
OS 35.2209989 -37.45999874
OS 34.9436309 -36.64314998
OS 34.9436309 -37.45999874
OS 34.82158898 -37.45999874
OS 34.82158898 -36.50030546
OS 35.01158606 -36.50030546
OS 35.23902782 -37.1812439
OS 35.23902782 -37.18263074
OS 35.24041466 -37.18540442
OS 35.2418015 -37.18956494
OS 35.24457518 -37.19649914
OS 35.25012254 -37.21314122
OS 35.25705674 -37.23394382
OS 35.26399094 -37.2575201
OS 35.27231198 -37.28109638
OS 35.27924618 -37.30328582
OS 35.28479354 -37.32270158
OS 35.28618038 -37.3199279
OS 35.28756722 -37.3129937
OS 35.29172774 -37.30051214
OS 35.2972751 -37.28387006
OS 35.3042093 -37.26168062
OS 35.31391718 -37.23533066
OS 35.32362506 -37.20482018
OS 35.33610662 -37.16876234
OS 35.56632206 -36.50030546
OS 35.73690338 -36.50030546
OS 35.73690338 -37.45999874
OE
OB 34.61356298 -37.05504146 I
OS 34.61356298 -37.0564283
OS 34.61356298 -37.06197566
OS 34.61356298 -37.06890986
OS 34.61356298 -37.07861774
OS 34.61217614 -37.0910993
OS 34.61217614 -37.1049677
OS 34.6107893 -37.12160978
OS 34.60940246 -37.13825186
OS 34.60524194 -37.17569654
OS 34.59969458 -37.21452806
OS 34.59137354 -37.25197274
OS 34.58582618 -37.27000166
OS 34.58027882 -37.28664374
OS 34.58027882 -37.28803058
OS 34.57889198 -37.29080426
OS 34.5761183 -37.29496478
OS 34.57334462 -37.30051214
OS 34.56502358 -37.31576738
OS 34.55254202 -37.33518314
OS 34.53589994 -37.35737258
OS 34.51648418 -37.37956202
OS 34.49152106 -37.4031383
OS 34.46101058 -37.4239409
OS 34.45962374 -37.4239409
OS 34.45685006 -37.42671458
OS 34.45268954 -37.42810142
OS 34.44575534 -37.43226194
OS 34.4374343 -37.43642246
OS 34.42633958 -37.44058298
OS 34.41524486 -37.4447435
OS 34.40137646 -37.45029086
OS 34.38612122 -37.45583822
OS 34.36947914 -37.45999874
OS 34.35145022 -37.46415926
OS 34.33064762 -37.46831978
OS 34.30984502 -37.47109346
OS 34.28765558 -37.47386714
OS 34.23772934 -37.47664082
OS 34.22524778 -37.47664082
OS 34.2155399 -37.47525398
OS 34.20444518 -37.47525398
OS 34.19057678 -37.47386714
OS 34.17532154 -37.4724803
OS 34.1600663 -37.47109346
OS 34.1253953 -37.4655461
OS 34.08795062 -37.45722506
OS 34.05189278 -37.44613034
OS 34.01722178 -37.4308751
OS 34.01583494 -37.4308751
OS 34.01306126 -37.42810142
OS 34.00890074 -37.42532774
OS 34.00335338 -37.42255406
OS 33.98809814 -37.41145934
OS 33.97006922 -37.3962041
OS 33.94926662 -37.37678834
OS 33.92985086 -37.3545989
OS 33.9104351 -37.3268621
OS 33.89517986 -37.29635162
OS 33.89517986 -37.29496478
OS 33.89379302 -37.2921911
OS 33.89240618 -37.28664374
OS 33.8896325 -37.27970954
OS 33.88685882 -37.2713885
OS 33.88408514 -37.26029378
OS 33.87992462 -37.24781222
OS 33.87715094 -37.23255698
OS 33.87437726 -37.2159149
OS 33.87021674 -37.19788598
OS 33.86744306 -37.17847022
OS 33.86466938 -37.15766762
OS 33.8618957 -37.13409134
OS 33.86050886 -37.10912822
OS 33.85912202 -37.08277826
OS 33.85912202 -37.05504146
OS 33.85912202 -36.50030546
OS 33.9867113 -36.50030546
OS 33.9867113 -37.05504146
OS 33.9867113 -37.0564283
OS 33.9867113 -37.06058882
OS 33.9867113 -37.06752302
OS 33.9867113 -37.07584406
OS 33.98809814 -37.08555194
OS 33.98809814 -37.0980335
OS 33.98948498 -37.12438346
OS 33.99225866 -37.15489394
OS 33.99641918 -37.18540442
OS 34.00196654 -37.21452806
OS 34.00474022 -37.22700962
OS 34.00890074 -37.23949118
OS 34.01028758 -37.24226486
OS 34.01306126 -37.24919906
OS 34.01999546 -37.25890694
OS 34.0283165 -37.27277534
OS 34.03802438 -37.28664374
OS 34.05189278 -37.30189898
OS 34.06853486 -37.31715422
OS 34.08795062 -37.32963578
OS 34.0907243 -37.33102262
OS 34.0976585 -37.33518314
OS 34.11014006 -37.33934366
OS 34.12678214 -37.34489102
OS 34.1461979 -37.35182522
OS 34.17116102 -37.35598574
OS 34.19751098 -37.36014626
OS 34.22663462 -37.3615331
OS 34.24050302 -37.3615331
OS 34.24882406 -37.36014626
OS 34.26130562 -37.36014626
OS 34.27378718 -37.35875942
OS 34.30429766 -37.35321206
OS 34.33758182 -37.34627786
OS 34.36947914 -37.33518314
OS 34.39998962 -37.3199279
OS 34.41385802 -37.31022002
OS 34.42633958 -37.2991253
OS 34.42772642 -37.29773846
OS 34.42911326 -37.29635162
OS 34.43188694 -37.2921911
OS 34.43604746 -37.28664374
OS 34.44020798 -37.2783227
OS 34.44575534 -37.27000166
OS 34.4513027 -37.2575201
OS 34.45685006 -37.24503854
OS 34.46239742 -37.2297833
OS 34.46655794 -37.21175438
OS 34.4721053 -37.19095178
OS 34.47626582 -37.16876234
OS 34.48042634 -37.14379922
OS 34.48320002 -37.11744926
OS 34.4859737 -37.08693878
OS 34.4859737 -37.05504146
OS 34.4859737 -36.50030546
OS 34.61356298 -36.50030546
OS 34.61356298 -37.05504146
OE
OB 33.64416182 -37.45999874 I
OS 33.51241202 -37.45999874
OS 33.01037594 -36.70694462
OS 33.01037594 -37.45999874
OS 32.88833402 -37.45999874
OS 32.88833402 -36.50030546
OS 33.01869698 -36.50030546
OS 33.5221199 -37.25474642
OS 33.5221199 -36.50030546
OS 33.64416182 -36.50030546
OS 33.64416182 -37.45999874
OE
OB 38.19022334 -36.5016923 I
OS 38.2027049 -36.5016923
OS 38.23182854 -36.50307914
OS 38.26233902 -36.50723966
OS 38.29562318 -36.51140018
OS 38.32613366 -36.51833438
OS 38.3413889 -36.5224949
OS 38.35387046 -36.52665542
OS 38.3552573 -36.52665542
OS 38.35664414 -36.52804226
OS 38.36496518 -36.53220278
OS 38.37744674 -36.53775014
OS 38.39270198 -36.54745802
OS 38.40934406 -36.55993958
OS 38.42737298 -36.57658166
OS 38.44401506 -36.59599742
OS 38.46065714 -36.61818686
OS 38.46065714 -36.6195737
OS 38.46204398 -36.62096054
OS 38.46759134 -36.62928158
OS 38.4731387 -36.64314998
OS 38.48145974 -36.6611789
OS 38.48839394 -36.6819815
OS 38.49532814 -36.70694462
OS 38.49948866 -36.73329458
OS 38.5008755 -36.76241822
OS 38.5008755 -36.76380506
OS 38.5008755 -36.76657874
OS 38.5008755 -36.7721261
OS 38.49948866 -36.7790603
OS 38.49948866 -36.78876818
OS 38.49810182 -36.79847606
OS 38.49255446 -36.82205234
OS 38.48423342 -36.84978914
OS 38.4731387 -36.87891278
OS 38.45649662 -36.90803642
OS 38.4454019 -36.92190482
OS 38.43430718 -36.93577322
OS 38.43292034 -36.93716006
OS 38.4315335 -36.9385469
OS 38.42737298 -36.94270742
OS 38.42182562 -36.94686794
OS 38.41489142 -36.9524153
OS 38.40657038 -36.95796266
OS 38.39547566 -36.96489686
OS 38.38438094 -36.9732179
OS 38.37051254 -36.9801521
OS 38.3552573 -36.9870863
OS 38.33861522 -36.99540734
OS 38.3205863 -37.00234154
OS 38.2997837 -37.0078889
OS 38.2789811 -37.0148231
OS 38.25540482 -37.01898362
OS 38.2304417 -37.02314414
OS 38.23321538 -37.02453098
OS 38.23876274 -37.02730466
OS 38.24708378 -37.03285202
OS 38.2581785 -37.03839938
OS 38.28314162 -37.05365462
OS 38.29562318 -37.0633625
OS 38.3067179 -37.07168354
OS 38.30949158 -37.07445722
OS 38.31642578 -37.08139142
OS 38.3275205 -37.09248614
OS 38.3413889 -37.10635454
OS 38.35664414 -37.1257703
OS 38.37467306 -37.1465729
OS 38.39270198 -37.17153602
OS 38.41211774 -37.19927282
OS 38.5771517 -37.45999874
OS 38.41905194 -37.45999874
OS 38.2928495 -37.26029378
OS 38.2928495 -37.25890694
OS 38.29007582 -37.25613326
OS 38.28730214 -37.25197274
OS 38.28314162 -37.24642538
OS 38.27343374 -37.23117014
OS 38.26095218 -37.21175438
OS 38.24569694 -37.19095178
OS 38.2304417 -37.16876234
OS 38.21518646 -37.14795974
OS 38.20131806 -37.12854398
OS 38.19993122 -37.12715714
OS 38.1957707 -37.12160978
OS 38.1888365 -37.11328874
OS 38.17912862 -37.10358086
OS 38.15832602 -37.08277826
OS 38.1472313 -37.07307038
OS 38.13613658 -37.06474934
OS 38.13474974 -37.0633625
OS 38.13197606 -37.06197566
OS 38.1264287 -37.05920198
OS 38.11810766 -37.05504146
OS 38.10978662 -37.05088094
OS 38.10007874 -37.04672042
OS 38.0778893 -37.03978622
OS 38.07650246 -37.03978622
OS 38.07372878 -37.03839938
OS 38.06818142 -37.03839938
OS 38.06124722 -37.03701254
OS 38.05153934 -37.0356257
OS 38.04044462 -37.0356257
OS 38.02518938 -37.03423886
OS 37.86154226 -37.03423886
OS 37.86154226 -37.45999874
OS 37.73395298 -37.45999874
OS 37.73395298 -36.50030546
OS 38.17912862 -36.50030546
OS 38.19022334 -36.5016923
OE
OB 37.53424802 -36.61402634 I
OS 36.96703046 -36.61402634
OS 36.96703046 -36.90664958
OS 37.49819018 -36.90664958
OS 37.49819018 -37.02037046
OS 36.96703046 -37.02037046
OS 36.96703046 -37.34627786
OS 37.55643746 -37.34627786
OS 37.55643746 -37.45999874
OS 36.83944118 -37.45999874
OS 36.83944118 -36.50030546
OS 37.53424802 -36.50030546
OS 37.53424802 -36.61402634
OE
OB 36.32492354 -36.5016923 I
OS 36.33601826 -36.5016923
OS 36.36098138 -36.50446598
OS 36.38871818 -36.50723966
OS 36.41784182 -36.51278702
OS 36.44696546 -36.51972122
OS 36.47331542 -36.5294291
OS 36.47470226 -36.5294291
OS 36.4760891 -36.53081594
OS 36.48441014 -36.53497646
OS 36.4968917 -36.54191066
OS 36.5107601 -36.55161854
OS 36.52740218 -36.5641001
OS 36.5454311 -36.57935534
OS 36.56207318 -36.5987711
OS 36.57732842 -36.6195737
OS 36.57871526 -36.62234738
OS 36.58287578 -36.63066842
OS 36.58980998 -36.64176314
OS 36.59674418 -36.65840522
OS 36.60367838 -36.67782098
OS 36.61061258 -36.69862358
OS 36.6147731 -36.72219986
OS 36.61615994 -36.74577614
OS 36.61615994 -36.74854982
OS 36.61615994 -36.75548402
OS 36.6147731 -36.76796558
OS 36.61199942 -36.78322082
OS 36.6078389 -36.80124974
OS 36.6009047 -36.8206655
OS 36.59258366 -36.84008126
OS 36.58148894 -36.86088386
OS 36.5801021 -36.86365754
OS 36.57594158 -36.8692049
OS 36.56762054 -36.88029962
OS 36.55652582 -36.89139434
OS 36.54265742 -36.90526274
OS 36.52601534 -36.92051798
OS 36.50521274 -36.93438638
OS 36.48163646 -36.94825478
OS 36.4830233 -36.94825478
OS 36.48579698 -36.94964162
OS 36.4899575 -36.95102846
OS 36.49550486 -36.95380214
OS 36.51214694 -36.9593495
OS 36.5315627 -36.96905738
OS 36.5523653 -36.98153894
OS 36.57594158 -36.99679418
OS 36.59674418 -37.0148231
OS 36.61615994 -37.03701254
OS 36.61754678 -37.03978622
OS 36.62309414 -37.04810726
OS 36.63141518 -37.06058882
OS 36.63973622 -37.0772309
OS 36.64805726 -37.09942034
OS 36.6563783 -37.12299662
OS 36.66192566 -37.15073342
OS 36.6633125 -37.1812439
OS 36.6633125 -37.18263074
OS 36.6633125 -37.18401758
OS 36.6633125 -37.19233862
OS 36.66192566 -37.20620702
OS 36.65915198 -37.2228491
OS 36.6563783 -37.24226486
OS 36.65083094 -37.26306746
OS 36.64389674 -37.2852569
OS 36.63418886 -37.30744634
OS 36.63280202 -37.31022002
OS 36.6286415 -37.31715422
OS 36.62309414 -37.3268621
OS 36.6147731 -37.3407305
OS 36.60367838 -37.3545989
OS 36.59258366 -37.36985414
OS 36.57871526 -37.38510938
OS 36.56346002 -37.39759094
OS 36.56207318 -37.39897778
OS 36.55652582 -37.4031383
OS 36.54681794 -37.40868566
OS 36.53433638 -37.41423302
OS 36.51908114 -37.42255406
OS 36.50105222 -37.4308751
OS 36.48163646 -37.4378093
OS 36.45806018 -37.4447435
OS 36.4552865 -37.4447435
OS 36.44696546 -37.44751718
OS 36.43309706 -37.44890402
OS 36.41506814 -37.4516777
OS 36.3928787 -37.45445138
OS 36.36652874 -37.45722506
OS 36.3374051 -37.4586119
OS 36.30412094 -37.45999874
OS 35.93799518 -37.45999874
OS 35.93799518 -36.50030546
OS 36.31521566 -36.50030546
OS 36.32492354 -36.5016923
OE
OB 32.3849111 -36.61402634 I
OS 32.06871158 -36.61402634
OS 32.06871158 -37.45999874
OS 31.9411223 -37.45999874
OS 31.9411223 -36.61402634
OS 31.62492278 -36.61402634
OS 31.62492278 -36.50030546
OS 32.3849111 -36.50030546
OS 32.3849111 -36.61402634
OE
OB 30.62639798 -37.45999874 I
OS 30.48216662 -37.45999874
OS 30.36983258 -37.16876234
OS 29.96764898 -37.16876234
OS 29.86363598 -37.45999874
OS 29.7291125 -37.45999874
OS 30.09523826 -36.50030546
OS 30.23392226 -36.50030546
OS 30.62639798 -37.45999874
OE
OB 29.3546657 -36.5016923 I
OS 29.37824198 -36.50307914
OS 29.4032051 -36.50446598
OS 29.42678138 -36.50723966
OS 29.44758398 -36.51001334
OS 29.45035766 -36.51001334
OS 29.46006554 -36.51278702
OS 29.4725471 -36.5155607
OS 29.48918918 -36.51972122
OS 29.5072181 -36.52665542
OS 29.52663386 -36.53497646
OS 29.54743646 -36.54468434
OS 29.56546538 -36.55577906
OS 29.56823906 -36.5571659
OS 29.57378642 -36.56132642
OS 29.58210746 -36.56964746
OS 29.59320218 -36.57935534
OS 29.60568374 -36.5918369
OS 29.6181653 -36.60847898
OS 29.6320337 -36.6265079
OS 29.64312842 -36.6473105
OS 29.64451526 -36.65008418
OS 29.64728894 -36.65701838
OS 29.6528363 -36.66949994
OS 29.65838366 -36.68614202
OS 29.66254418 -36.70555778
OS 29.66809154 -36.72774722
OS 29.67086522 -36.75271034
OS 29.67225206 -36.7790603
OS 29.67225206 -36.78044714
OS 29.67225206 -36.78460766
OS 29.67225206 -36.79015502
OS 29.67086522 -36.7998629
OS 29.66947838 -36.80957078
OS 29.66809154 -36.82205234
OS 29.66531786 -36.83592074
OS 29.66254418 -36.85117598
OS 29.6528363 -36.8830733
OS 29.64728894 -36.89971538
OS 29.6389679 -36.9177443
OS 29.62926002 -36.93577322
OS 29.61955214 -36.9524153
OS 29.60707058 -36.96905738
OS 29.59320218 -36.98569946
OS 29.59181534 -36.9870863
OS 29.58904166 -36.98985998
OS 29.58488114 -36.9940205
OS 29.57794694 -36.99818102
OS 29.5696259 -37.00511522
OS 29.55853118 -37.01204942
OS 29.54466278 -37.02037046
OS 29.52940754 -37.02730466
OS 29.51137862 -37.0356257
OS 29.49057602 -37.04394674
OS 29.46838658 -37.05088094
OS 29.44203662 -37.0564283
OS 29.41429982 -37.06197566
OS 29.38378934 -37.06613618
OS 29.34911834 -37.06890986
OS 29.3130605 -37.0702967
OS 29.06758982 -37.0702967
OS 29.06758982 -37.45999874
OS 28.94000054 -37.45999874
OS 28.94000054 -36.50030546
OS 29.3338631 -36.50030546
OS 29.3546657 -36.5016923
OE
OB 31.18668134 -36.5016923 I
OS 31.1991629 -36.5016923
OS 31.22828654 -36.50307914
OS 31.25879702 -36.50723966
OS 31.29208118 -36.51140018
OS 31.32259166 -36.51833438
OS 31.3378469 -36.5224949
OS 31.35032846 -36.52665542
OS 31.3517153 -36.52665542
OS 31.35310214 -36.52804226
OS 31.36142318 -36.53220278
OS 31.37390474 -36.53775014
OS 31.38915998 -36.54745802
OS 31.40580206 -36.55993958
OS 31.42383098 -36.57658166
OS 31.44047306 -36.59599742
OS 31.45711514 -36.61818686
OS 31.45711514 -36.6195737
OS 31.45850198 -36.62096054
OS 31.46404934 -36.62928158
OS 31.4695967 -36.64314998
OS 31.47791774 -36.6611789
OS 31.48485194 -36.6819815
OS 31.49178614 -36.70694462
OS 31.49594666 -36.73329458
OS 31.4973335 -36.76241822
OS 31.4973335 -36.76380506
OS 31.4973335 -36.76657874
OS 31.4973335 -36.7721261
OS 31.49594666 -36.7790603
OS 31.49594666 -36.78876818
OS 31.49455982 -36.79847606
OS 31.48901246 -36.82205234
OS 31.48069142 -36.84978914
OS 31.4695967 -36.87891278
OS 31.45295462 -36.90803642
OS 31.4418599 -36.92190482
OS 31.43076518 -36.93577322
OS 31.42937834 -36.93716006
OS 31.4279915 -36.9385469
OS 31.42383098 -36.94270742
OS 31.41828362 -36.94686794
OS 31.41134942 -36.9524153
OS 31.40302838 -36.95796266
OS 31.39193366 -36.96489686
OS 31.38083894 -36.9732179
OS 31.36697054 -36.9801521
OS 31.3517153 -36.9870863
OS 31.33507322 -36.99540734
OS 31.3170443 -37.00234154
OS 31.2962417 -37.0078889
OS 31.2754391 -37.0148231
OS 31.25186282 -37.01898362
OS 31.2268997 -37.02314414
OS 31.22967338 -37.02453098
OS 31.23522074 -37.02730466
OS 31.24354178 -37.03285202
OS 31.2546365 -37.03839938
OS 31.27959962 -37.05365462
OS 31.29208118 -37.0633625
OS 31.3031759 -37.07168354
OS 31.30594958 -37.07445722
OS 31.31288378 -37.08139142
OS 31.3239785 -37.09248614
OS 31.3378469 -37.10635454
OS 31.35310214 -37.1257703
OS 31.37113106 -37.1465729
OS 31.38915998 -37.17153602
OS 31.40857574 -37.19927282
OS 31.5736097 -37.45999874
OS 31.41550994 -37.45999874
OS 31.2893075 -37.26029378
OS 31.2893075 -37.25890694
OS 31.28653382 -37.25613326
OS 31.28376014 -37.25197274
OS 31.27959962 -37.24642538
OS 31.26989174 -37.23117014
OS 31.25741018 -37.21175438
OS 31.24215494 -37.19095178
OS 31.2268997 -37.16876234
OS 31.21164446 -37.14795974
OS 31.19777606 -37.12854398
OS 31.19638922 -37.12715714
OS 31.1922287 -37.12160978
OS 31.1852945 -37.11328874
OS 31.17558662 -37.10358086
OS 31.15478402 -37.08277826
OS 31.1436893 -37.07307038
OS 31.13259458 -37.06474934
OS 31.13120774 -37.0633625
OS 31.12843406 -37.06197566
OS 31.1228867 -37.05920198
OS 31.11456566 -37.05504146
OS 31.10624462 -37.05088094
OS 31.09653674 -37.04672042
OS 31.0743473 -37.03978622
OS 31.07296046 -37.03978622
OS 31.07018678 -37.03839938
OS 31.06463942 -37.03839938
OS 31.05770522 -37.03701254
OS 31.04799734 -37.0356257
OS 31.03690262 -37.0356257
OS 31.02164738 -37.03423886
OS 30.85800026 -37.03423886
OS 30.85800026 -37.45999874
OS 30.73041098 -37.45999874
OS 30.73041098 -36.50030546
OS 31.17558662 -36.50030546
OS 31.18668134 -36.5016923
OE
OB 38.16387338 -36.60709214 H
OS 37.86154226 -36.60709214
OS 37.86154226 -36.9246785
OS 38.1472313 -36.9246785
OS 38.16387338 -36.92329166
OS 38.18328914 -36.92190482
OS 38.20547858 -36.92051798
OS 38.22766802 -36.9177443
OS 38.24985746 -36.91358378
OS 38.26927322 -36.90803642
OS 38.2720469 -36.90664958
OS 38.27759426 -36.9038759
OS 38.2859153 -36.89971538
OS 38.29701002 -36.89416802
OS 38.30949158 -36.88584698
OS 38.32197314 -36.8761391
OS 38.3344547 -36.86365754
OS 38.34416258 -36.84978914
OS 38.34554942 -36.8484023
OS 38.3483231 -36.84285494
OS 38.35248362 -36.8345339
OS 38.35803098 -36.82343918
OS 38.3621915 -36.81095762
OS 38.36635202 -36.79708922
OS 38.3691257 -36.78044714
OS 38.37051254 -36.76380506
OS 38.37051254 -36.76241822
OS 38.37051254 -36.76103138
OS 38.3691257 -36.75271034
OS 38.36773886 -36.74022878
OS 38.36496518 -36.7235867
OS 38.35803098 -36.70694462
OS 38.34970994 -36.68752886
OS 38.33722838 -36.66949994
OS 38.3205863 -36.65147102
OS 38.31781262 -36.65008418
OS 38.31087842 -36.64453682
OS 38.2997837 -36.63760262
OS 38.28175478 -36.62928158
OS 38.26095218 -36.62096054
OS 38.23321538 -36.61402634
OS 38.20131806 -36.60847898
OS 38.16387338 -36.60709214
OE
OB 29.34218414 -36.61402634 H
OS 29.06758982 -36.61402634
OS 29.06758982 -36.95657582
OS 29.32554206 -36.95657582
OS 29.33524994 -36.95518898
OS 29.34495782 -36.95518898
OS 29.35605254 -36.95380214
OS 29.3824025 -36.95102846
OS 29.41152614 -36.9454811
OS 29.44064978 -36.93716006
OS 29.46699974 -36.92606534
OS 29.4794813 -36.91913114
OS 29.48918918 -36.9108101
OS 29.49196286 -36.90803642
OS 29.49751022 -36.90248906
OS 29.50583126 -36.89139434
OS 29.51553914 -36.87752594
OS 29.52524702 -36.85949702
OS 29.53356806 -36.83730758
OS 29.53911542 -36.81234446
OS 29.5418891 -36.78322082
OS 29.5418891 -36.78183398
OS 29.5418891 -36.78044714
OS 29.5418891 -36.77351294
OS 29.54050226 -36.76103138
OS 29.53772858 -36.74716298
OS 29.5349549 -36.73190774
OS 29.52940754 -36.71387882
OS 29.5210865 -36.69723674
OS 29.51137862 -36.68059466
OS 29.50999178 -36.67920782
OS 29.50583126 -36.67366046
OS 29.49889706 -36.66672626
OS 29.49057602 -36.65701838
OS 29.47809446 -36.6473105
OS 29.46422606 -36.63898946
OS 29.44897082 -36.63066842
OS 29.4309419 -36.62373422
OS 29.42955506 -36.62373422
OS 29.4240077 -36.62234738
OS 29.41568666 -36.62096054
OS 29.40459194 -36.61818686
OS 29.38794986 -36.61680002
OS 29.36714726 -36.61541318
OS 29.34218414 -36.61402634
OE
OB 30.16180658 -36.60015794 H
OS 30.16180658 -36.60154478
OS 30.16041974 -36.60431846
OS 30.16041974 -36.60986582
OS 30.15764606 -36.61541318
OS 30.15625922 -36.62512106
OS 30.15348554 -36.63482894
OS 30.14793818 -36.65840522
OS 30.14100398 -36.68614202
OS 30.1312961 -36.7166525
OS 30.12158822 -36.74993666
OS 30.10910666 -36.78460766
OS 30.00509366 -37.06474934
OS 30.32961422 -37.06474934
OS 30.22976174 -36.80124974
OS 30.22976174 -36.7998629
OS 30.2283749 -36.79570238
OS 30.22560122 -36.78876818
OS 30.22282754 -36.78044714
OS 30.21866702 -36.77073926
OS 30.2145065 -36.7582577
OS 30.21034598 -36.7443893
OS 30.20479862 -36.7305209
OS 30.1937039 -36.69862358
OS 30.18260918 -36.66533942
OS 30.17151446 -36.63205526
OS 30.16180658 -36.60015794
OE
OB 31.16033138 -36.60709214 H
OS 30.85800026 -36.60709214
OS 30.85800026 -36.9246785
OS 31.1436893 -36.9246785
OS 31.16033138 -36.92329166
OS 31.17974714 -36.92190482
OS 31.20193658 -36.92051798
OS 31.22412602 -36.9177443
OS 31.24631546 -36.91358378
OS 31.26573122 -36.90803642
OS 31.2685049 -36.90664958
OS 31.27405226 -36.9038759
OS 31.2823733 -36.89971538
OS 31.29346802 -36.89416802
OS 31.30594958 -36.88584698
OS 31.31843114 -36.8761391
OS 31.3309127 -36.86365754
OS 31.34062058 -36.84978914
OS 31.34200742 -36.8484023
OS 31.3447811 -36.84285494
OS 31.34894162 -36.8345339
OS 31.35448898 -36.82343918
OS 31.3586495 -36.81095762
OS 31.36281002 -36.79708922
OS 31.3655837 -36.78044714
OS 31.36697054 -36.76380506
OS 31.36697054 -36.76241822
OS 31.36697054 -36.76103138
OS 31.3655837 -36.75271034
OS 31.36419686 -36.74022878
OS 31.36142318 -36.7235867
OS 31.35448898 -36.70694462
OS 31.34616794 -36.68752886
OS 31.33368638 -36.66949994
OS 31.3170443 -36.65147102
OS 31.31427062 -36.65008418
OS 31.30733642 -36.64453682
OS 31.2962417 -36.63760262
OS 31.27821278 -36.62928158
OS 31.25741018 -36.62096054
OS 31.22967338 -36.61402634
OS 31.19777606 -36.60847898
OS 31.16033138 -36.60709214
OE
OB 36.29302622 -36.61402634 H
OS 36.06558446 -36.61402634
OS 36.06558446 -36.90248906
OS 36.30134726 -36.90248906
OS 36.31937618 -36.90110222
OS 36.33879194 -36.89971538
OS 36.3582077 -36.89832854
OS 36.37762346 -36.89555486
OS 36.3928787 -36.89278118
OS 36.39565238 -36.89139434
OS 36.40119974 -36.8900075
OS 36.40952078 -36.88584698
OS 36.4206155 -36.88029962
OS 36.43171022 -36.87475226
OS 36.44419178 -36.86643122
OS 36.45667334 -36.8553365
OS 36.46638122 -36.84424178
OS 36.46776806 -36.84285494
OS 36.47054174 -36.83869442
OS 36.47470226 -36.83037338
OS 36.47886278 -36.8206655
OS 36.4830233 -36.80957078
OS 36.48718382 -36.79570238
OS 36.4899575 -36.7790603
OS 36.49134434 -36.76103138
OS 36.49134434 -36.7582577
OS 36.49134434 -36.75271034
OS 36.4899575 -36.7443893
OS 36.48857066 -36.73329458
OS 36.48579698 -36.71942618
OS 36.48163646 -36.70555778
OS 36.4760891 -36.69168938
OS 36.46776806 -36.67782098
OS 36.46638122 -36.67643414
OS 36.46360754 -36.67227362
OS 36.45806018 -36.66533942
OS 36.45112598 -36.65840522
OS 36.4414181 -36.65008418
OS 36.43032338 -36.64176314
OS 36.41645498 -36.6334421
OS 36.40119974 -36.62789474
OS 36.3998129 -36.62789474
OS 36.3928787 -36.62512106
OS 36.38317082 -36.62373422
OS 36.36791558 -36.62096054
OS 36.34711298 -36.61818686
OS 36.3235367 -36.61680002
OS 36.29302622 -36.61402634
OE
OB 36.31798934 -37.01620994 H
OS 36.06558446 -37.01620994
OS 36.06558446 -37.34627786
OS 36.33879194 -37.34627786
OS 36.36791558 -37.34489102
OS 36.38039714 -37.34350418
OS 36.39149186 -37.34211734
OS 36.3928787 -37.34211734
OS 36.39842606 -37.3407305
OS 36.4067471 -37.33934366
OS 36.41645498 -37.33656998
OS 36.44003126 -37.32824894
OS 36.46360754 -37.31715422
OS 36.46499438 -37.31576738
OS 36.4691549 -37.3129937
OS 36.47470226 -37.30883318
OS 36.48163646 -37.30328582
OS 36.48857066 -37.29496478
OS 36.49827854 -37.28664374
OS 36.50521274 -37.27554902
OS 36.51353378 -37.26306746
OS 36.51492062 -37.26168062
OS 36.51630746 -37.2575201
OS 36.51908114 -37.24919906
OS 36.52324166 -37.23949118
OS 36.52740218 -37.22839646
OS 36.53017586 -37.21452806
OS 36.5315627 -37.19788598
OS 36.53294954 -37.1812439
OS 36.53294954 -37.17847022
OS 36.53294954 -37.17292286
OS 36.5315627 -37.16182814
OS 36.52878902 -37.14934658
OS 36.52601534 -37.13547818
OS 36.52046798 -37.12022294
OS 36.51353378 -37.1049677
OS 36.5038259 -37.08971246
OS 36.50243906 -37.08832562
OS 36.49827854 -37.08277826
OS 36.49273118 -37.07584406
OS 36.48441014 -37.06752302
OS 36.47331542 -37.05781514
OS 36.45944702 -37.04810726
OS 36.44419178 -37.03978622
OS 36.42616286 -37.03285202
OS 36.42338918 -37.03146518
OS 36.41784182 -37.03007834
OS 36.40536026 -37.02730466
OS 36.39010502 -37.02453098
OS 36.37068926 -37.0217573
OS 36.34711298 -37.01898362
OS 36.31798934 -37.01620994
OE
SE
S P 0
OB 40.9056459 -38.32112732 I
OS 40.92136342 -38.32205188
OS 40.9380055 -38.32297644
OS 40.95372302 -38.32482556
OS 40.96759142 -38.32667468
OS 40.96944054 -38.32667468
OS 40.97591246 -38.3285238
OS 40.9842335 -38.33037292
OS 40.99532822 -38.3331466
OS 41.0073475 -38.3377694
OS 41.02029134 -38.34331676
OS 41.03415974 -38.34978868
OS 41.04617902 -38.35718516
OS 41.04802814 -38.35810972
OS 41.05172638 -38.3608834
OS 41.05727374 -38.36643076
OS 41.06467022 -38.37290268
OS 41.07299126 -38.38122372
OS 41.0813123 -38.39231844
OS 41.0905579 -38.40433772
OS 41.09795438 -38.41820612
OS 41.09887894 -38.42005524
OS 41.10072806 -38.42467804
OS 41.1044263 -38.43299908
OS 41.10812454 -38.4440938
OS 41.11089822 -38.45703764
OS 41.11459646 -38.4718306
OS 41.11644558 -38.48847268
OS 41.11737014 -38.50603932
OS 41.11737014 -38.50696388
OS 41.11737014 -38.50973756
OS 41.11737014 -38.5134358
OS 41.11644558 -38.51990772
OS 41.11552102 -38.52637964
OS 41.11459646 -38.53470068
OS 41.11274734 -38.54394628
OS 41.11089822 -38.55411644
OS 41.1044263 -38.57538132
OS 41.10072806 -38.58647604
OS 41.0951807 -38.59849532
OS 41.08870878 -38.6105146
OS 41.08223686 -38.62160932
OS 41.07391582 -38.63270404
OS 41.06467022 -38.64379876
OS 41.06374566 -38.64472332
OS 41.06189654 -38.64657244
OS 41.05912286 -38.64934612
OS 41.05450006 -38.6521198
OS 41.0489527 -38.6567426
OS 41.04155622 -38.6613654
OS 41.03231062 -38.66691276
OS 41.02214046 -38.67153556
OS 41.01012118 -38.67708292
OS 40.99625278 -38.68263028
OS 40.98145982 -38.68725308
OS 40.96389318 -38.69095132
OS 40.94540198 -38.69464956
OS 40.92506166 -38.69742324
OS 40.90194766 -38.69927236
OS 40.8779091 -38.70019692
OS 40.71426198 -38.70019692
OS 40.71426198 -38.95999828
OS 40.62920246 -38.95999828
OS 40.62920246 -38.32020276
OS 40.8917775 -38.32020276
OS 40.9056459 -38.32112732
OE
OB 40.49791494 -38.98403684 I
OS 40.49791494 -38.9849614
OS 40.49791494 -38.98773508
OS 40.49791494 -38.99235788
OS 40.49791494 -38.99790524
OS 40.49699038 -39.00530172
OS 40.49699038 -39.0126982
OS 40.49514126 -39.0311894
OS 40.49236758 -39.05060516
OS 40.48866934 -39.07094548
OS 40.48312198 -39.08851212
OS 40.47942374 -39.09683316
OS 40.4757255 -39.10330508
OS 40.4757255 -39.10422964
OS 40.47480094 -39.1051542
OS 40.47017814 -39.109777
OS 40.46278166 -39.11717348
OS 40.45353606 -39.12549452
OS 40.44059222 -39.13381556
OS 40.42395014 -39.14028748
OS 40.40453438 -39.14583484
OS 40.39343966 -39.1467594
OS 40.38142038 -39.14768396
OS 40.37587302 -39.14768396
OS 40.37032566 -39.1467594
OS 40.36200462 -39.1467594
OS 40.35275902 -39.14583484
OS 40.34258886 -39.14398572
OS 40.32039942 -39.13843836
OS 40.33519238 -39.07187004
OS 40.33611694 -39.07187004
OS 40.33889062 -39.0727946
OS 40.34351342 -39.07371916
OS 40.34813622 -39.07464372
OS 40.3601555 -39.0774174
OS 40.36570286 -39.07834196
OS 40.37494846 -39.07834196
OS 40.37957126 -39.0774174
OS 40.38511862 -39.07649284
OS 40.39066598 -39.07464372
OS 40.39621334 -39.07094548
OS 40.40268526 -39.06724724
OS 40.40730806 -39.06169988
OS 40.40823262 -39.06077532
OS 40.40915718 -39.05800164
OS 40.4110063 -39.05337884
OS 40.41377998 -39.04598236
OS 40.4156291 -39.0358122
OS 40.41655366 -39.02841572
OS 40.41747822 -39.0219438
OS 40.41840278 -39.01362276
OS 40.41840278 -39.0034526
OS 40.41932734 -38.99328244
OS 40.41932734 -38.98218772
OS 40.41932734 -38.49586916
OS 40.49791494 -38.49586916
OS 40.49791494 -38.98403684
OE
OB 41.51770462 -38.3100326 I
OS 41.52602566 -38.31095716
OS 41.53619582 -38.31188172
OS 41.54636598 -38.31280628
OS 41.55838526 -38.31557996
OS 41.58334838 -38.32112732
OS 41.61108518 -38.32944836
OS 41.62495358 -38.33499572
OS 41.63789742 -38.34146764
OS 41.65084126 -38.34978868
OS 41.6637851 -38.35810972
OS 41.66470966 -38.35903428
OS 41.66655878 -38.35995884
OS 41.67025702 -38.36273252
OS 41.67487982 -38.36735532
OS 41.67950262 -38.37197812
OS 41.68597454 -38.37845004
OS 41.69244646 -38.38584652
OS 41.69984294 -38.393243
OS 41.70723942 -38.4024886
OS 41.7146359 -38.41358332
OS 41.72295694 -38.42467804
OS 41.73035342 -38.43669732
OS 41.73682534 -38.45056572
OS 41.74422182 -38.46443412
OS 41.74976918 -38.47922708
OS 41.75531654 -38.49586916
OS 41.67210614 -38.51528492
OS 41.67210614 -38.51436036
OS 41.67118158 -38.51251124
OS 41.66933246 -38.508813
OS 41.66748334 -38.5041902
OS 41.66563422 -38.49864284
OS 41.66286054 -38.49124636
OS 41.65546406 -38.4764534
OS 41.64621846 -38.45981132
OS 41.63512374 -38.44316924
OS 41.62125534 -38.42745172
OS 41.60646238 -38.41358332
OS 41.60461326 -38.4117342
OS 41.5990659 -38.40803596
OS 41.5898203 -38.40341316
OS 41.57780102 -38.39694124
OS 41.5620835 -38.39139388
OS 41.54451686 -38.38584652
OS 41.52325198 -38.38214828
OS 41.50013798 -38.38122372
OS 41.4927415 -38.38122372
OS 41.4881187 -38.38214828
OS 41.48164678 -38.38214828
OS 41.4742503 -38.38307284
OS 41.45668366 -38.38584652
OS 41.4372679 -38.38954476
OS 41.41692758 -38.39601668
OS 41.3956627 -38.40526228
OS 41.37624694 -38.41728156
OS 41.37532238 -38.41728156
OS 41.37439782 -38.41913068
OS 41.3679259 -38.42375348
OS 41.35960486 -38.43114996
OS 41.3494347 -38.44224468
OS 41.33741542 -38.45611308
OS 41.3263207 -38.4718306
OS 41.31615054 -38.49124636
OS 41.30690494 -38.51251124
OS 41.30690494 -38.5134358
OS 41.30598038 -38.51528492
OS 41.30505582 -38.5180586
OS 41.30413126 -38.5226814
OS 41.30228214 -38.52822876
OS 41.30043302 -38.53470068
OS 41.29765934 -38.5504182
OS 41.2939611 -38.5689094
OS 41.29026286 -38.58924972
OS 41.28841374 -38.61143916
OS 41.28748918 -38.63547772
OS 41.28748918 -38.63640228
OS 41.28748918 -38.63917596
OS 41.28748918 -38.64379876
OS 41.28748918 -38.64934612
OS 41.28841374 -38.65581804
OS 41.28841374 -38.66413908
OS 41.2893383 -38.67338468
OS 41.29026286 -38.68355484
OS 41.29303654 -38.70574428
OS 41.29765934 -38.72978284
OS 41.3032067 -38.7538214
OS 41.31060318 -38.77785996
OS 41.31060318 -38.77878452
OS 41.31152774 -38.78063364
OS 41.31337686 -38.78340732
OS 41.31522598 -38.78803012
OS 41.32077334 -38.79912484
OS 41.32909438 -38.81206868
OS 41.33926454 -38.82686164
OS 41.35220838 -38.84257916
OS 41.36700134 -38.85644756
OS 41.38456798 -38.8693914
OS 41.38549254 -38.8693914
OS 41.38734166 -38.87031596
OS 41.39011534 -38.87216508
OS 41.39381358 -38.8740142
OS 41.39843638 -38.87586332
OS 41.40398374 -38.878637
OS 41.41692758 -38.88418436
OS 41.43356966 -38.88973172
OS 41.45206086 -38.89435452
OS 41.47240118 -38.89805276
OS 41.49366606 -38.89897732
OS 41.50013798 -38.89897732
OS 41.50568534 -38.89805276
OS 41.51215726 -38.89805276
OS 41.51862918 -38.8971282
OS 41.53527126 -38.89342996
OS 41.55468702 -38.88880716
OS 41.57410278 -38.88141068
OS 41.5944431 -38.87124052
OS 41.60461326 -38.86569316
OS 41.61385886 -38.85829668
OS 41.61478342 -38.85737212
OS 41.61570798 -38.85644756
OS 41.61848166 -38.85367388
OS 41.6221799 -38.8509002
OS 41.62587814 -38.8462774
OS 41.63050094 -38.84073004
OS 41.6360483 -38.83518268
OS 41.6406711 -38.8277862
OS 41.64621846 -38.81946516
OS 41.65269038 -38.81021956
OS 41.65823774 -38.80097396
OS 41.6637851 -38.78987924
OS 41.6684079 -38.77785996
OS 41.6730307 -38.76491612
OS 41.6776535 -38.75104772
OS 41.68135174 -38.73625476
OS 41.76641126 -38.75751964
OS 41.76641126 -38.7584442
OS 41.7654867 -38.76214244
OS 41.76363758 -38.7676898
OS 41.7608639 -38.77508628
OS 41.75809022 -38.78340732
OS 41.75439198 -38.79357748
OS 41.74976918 -38.8046722
OS 41.74422182 -38.81669148
OS 41.73127798 -38.84257916
OS 41.7146359 -38.86846684
OS 41.70446574 -38.88141068
OS 41.69429558 -38.89435452
OS 41.68320086 -38.90544924
OS 41.67025702 -38.91654396
OS 41.66933246 -38.91746852
OS 41.66748334 -38.91931764
OS 41.66286054 -38.92116676
OS 41.65823774 -38.924865
OS 41.65084126 -38.9294878
OS 41.64344478 -38.9341106
OS 41.63327462 -38.9387334
OS 41.62310446 -38.9433562
OS 41.61108518 -38.94890356
OS 41.59814134 -38.95352636
OS 41.58427294 -38.95814916
OS 41.56947998 -38.96277196
OS 41.55376246 -38.9664702
OS 41.53712038 -38.96831932
OS 41.51955374 -38.97016844
OS 41.50106254 -38.971093
OS 41.49089238 -38.971093
OS 41.4834959 -38.97016844
OS 41.47517486 -38.97016844
OS 41.4650047 -38.96924388
OS 41.45390998 -38.96739476
OS 41.44096614 -38.96554564
OS 41.4141539 -38.96092284
OS 41.3864171 -38.95352636
OS 41.3586803 -38.9433562
OS 41.34573646 -38.93688428
OS 41.33279262 -38.9294878
OS 41.33186806 -38.92856324
OS 41.33001894 -38.92763868
OS 41.3263207 -38.924865
OS 41.32262246 -38.92116676
OS 41.3170751 -38.91746852
OS 41.31060318 -38.91192116
OS 41.3032067 -38.90544924
OS 41.29581022 -38.89805276
OS 41.28841374 -38.88973172
OS 41.2800927 -38.88141068
OS 41.26345062 -38.8601458
OS 41.2477331 -38.83518268
OS 41.2338647 -38.80744588
OS 41.2338647 -38.80652132
OS 41.23201558 -38.80374764
OS 41.23109102 -38.79912484
OS 41.22831734 -38.79357748
OS 41.22646822 -38.786181
OS 41.22369454 -38.7769354
OS 41.2199963 -38.76676524
OS 41.21722262 -38.75567052
OS 41.21444894 -38.74365124
OS 41.2107507 -38.72978284
OS 41.2061279 -38.70112148
OS 41.20242966 -38.66876188
OS 41.20058054 -38.63547772
OS 41.20058054 -38.63455316
OS 41.20058054 -38.63085492
OS 41.20058054 -38.62530756
OS 41.2015051 -38.61883564
OS 41.2015051 -38.60959004
OS 41.20242966 -38.60034444
OS 41.20335422 -38.58832516
OS 41.20520334 -38.57630588
OS 41.20982614 -38.54949364
OS 41.21629806 -38.51990772
OS 41.22554366 -38.4903218
OS 41.2384875 -38.46166044
OS 41.23941206 -38.46073588
OS 41.24033662 -38.4579622
OS 41.24218574 -38.45426396
OS 41.24588398 -38.44964116
OS 41.24958222 -38.44316924
OS 41.25420502 -38.43577276
OS 41.2662243 -38.41913068
OS 41.28194182 -38.40063948
OS 41.30043302 -38.38214828
OS 41.3216979 -38.36365708
OS 41.34666102 -38.34793956
OS 41.34758558 -38.347015
OS 41.35035926 -38.34609044
OS 41.3540575 -38.34424132
OS 41.3586803 -38.34146764
OS 41.36607678 -38.33869396
OS 41.37347326 -38.33592028
OS 41.38271886 -38.33222204
OS 41.39288902 -38.3285238
OS 41.40398374 -38.32482556
OS 41.41600302 -38.32112732
OS 41.4418907 -38.31557996
OS 41.47147662 -38.31095716
OS 41.5019871 -38.30910804
OS 41.5112327 -38.30910804
OS 41.51770462 -38.3100326
OE
OB 42.90454462 -39.1375138 I
OS 42.38401734 -39.1375138
OS 42.38401734 -39.08111564
OS 42.90454462 -39.08111564
OS 42.90454462 -39.1375138
OE
OB 42.12514054 -38.32112732 I
OS 42.13253702 -38.32112732
OS 42.1491791 -38.32297644
OS 42.1676703 -38.32482556
OS 42.18708606 -38.3285238
OS 42.20650182 -38.3331466
OS 42.22406846 -38.33961852
OS 42.22499302 -38.33961852
OS 42.22591758 -38.34054308
OS 42.23146494 -38.34331676
OS 42.23978598 -38.34793956
OS 42.24903158 -38.35441148
OS 42.2601263 -38.36273252
OS 42.27214558 -38.37290268
OS 42.2832403 -38.38584652
OS 42.29341046 -38.39971492
OS 42.29433502 -38.40156404
OS 42.2971087 -38.4071114
OS 42.3017315 -38.41450788
OS 42.3063543 -38.4256026
OS 42.3109771 -38.43854644
OS 42.3155999 -38.45241484
OS 42.31837358 -38.46813236
OS 42.31929814 -38.48384988
OS 42.31929814 -38.485699
OS 42.31929814 -38.4903218
OS 42.31837358 -38.49864284
OS 42.31652446 -38.508813
OS 42.31375078 -38.52083228
OS 42.30912798 -38.53377612
OS 42.30358062 -38.54671996
OS 42.29618414 -38.56058836
OS 42.29525958 -38.56243748
OS 42.2924859 -38.56613572
OS 42.28693854 -38.5735322
OS 42.27954206 -38.58092868
OS 42.27029646 -38.59017428
OS 42.25920174 -38.60034444
OS 42.24533334 -38.60959004
OS 42.22961582 -38.61883564
OS 42.23054038 -38.61883564
OS 42.2323895 -38.6197602
OS 42.23516318 -38.62068476
OS 42.23886142 -38.62253388
OS 42.24995614 -38.62623212
OS 42.26289998 -38.63270404
OS 42.27676838 -38.64102508
OS 42.2924859 -38.65119524
OS 42.3063543 -38.66321452
OS 42.31929814 -38.67800748
OS 42.3202227 -38.6798566
OS 42.32392094 -38.68540396
OS 42.3294683 -38.693725
OS 42.33501566 -38.70481972
OS 42.34056302 -38.71961268
OS 42.34611038 -38.7353302
OS 42.34980862 -38.7538214
OS 42.35073318 -38.77416172
OS 42.35073318 -38.77508628
OS 42.35073318 -38.77601084
OS 42.35073318 -38.7815582
OS 42.34980862 -38.7908038
OS 42.3479595 -38.80189852
OS 42.34611038 -38.81484236
OS 42.34241214 -38.82871076
OS 42.33778934 -38.84350372
OS 42.33131742 -38.85829668
OS 42.33039286 -38.8601458
OS 42.32761918 -38.8647686
OS 42.32392094 -38.87124052
OS 42.31837358 -38.88048612
OS 42.3109771 -38.88973172
OS 42.30358062 -38.89990188
OS 42.29433502 -38.91007204
OS 42.28416486 -38.91839308
OS 42.2832403 -38.91931764
OS 42.27954206 -38.92209132
OS 42.27307014 -38.92578956
OS 42.2647491 -38.9294878
OS 42.25457894 -38.93503516
OS 42.24255966 -38.94058252
OS 42.22961582 -38.94520532
OS 42.2138983 -38.94982812
OS 42.21204918 -38.94982812
OS 42.20650182 -38.95167724
OS 42.19725622 -38.9526018
OS 42.18523694 -38.95445092
OS 42.17044398 -38.95630004
OS 42.15287734 -38.95814916
OS 42.13346158 -38.95907372
OS 42.11127214 -38.95999828
OS 41.8671883 -38.95999828
OS 41.8671883 -38.32020276
OS 42.11866862 -38.32020276
OS 42.12514054 -38.32112732
OE
OB 40.30745558 -38.48662356 I
OS 40.31762574 -38.48847268
OS 40.32964502 -38.49217092
OS 40.34258886 -38.49679372
OS 40.35738182 -38.50326564
OS 40.37309934 -38.51158668
OS 40.34443798 -38.58370236
OS 40.34351342 -38.5827778
OS 40.33981518 -38.58092868
OS 40.33426782 -38.578155
OS 40.32687134 -38.57538132
OS 40.3185503 -38.57260764
OS 40.30838014 -38.56983396
OS 40.29820998 -38.56798484
OS 40.28803982 -38.56706028
OS 40.28341702 -38.56706028
OS 40.27879422 -38.56798484
OS 40.2723223 -38.5689094
OS 40.26585038 -38.57075852
OS 40.25752934 -38.5735322
OS 40.2492083 -38.57723044
OS 40.24181182 -38.5827778
OS 40.24088726 -38.58370236
OS 40.23811358 -38.58555148
OS 40.2353399 -38.58924972
OS 40.2307171 -38.59387252
OS 40.2260943 -38.60034444
OS 40.2214715 -38.60774092
OS 40.2168487 -38.61606196
OS 40.21315046 -38.62623212
OS 40.2122259 -38.62808124
OS 40.21130134 -38.6336286
OS 40.20945222 -38.64194964
OS 40.20667854 -38.65304436
OS 40.20390486 -38.66691276
OS 40.20205574 -38.68263028
OS 40.20113118 -38.69927236
OS 40.20020662 -38.71776356
OS 40.20020662 -38.95999828
OS 40.12161902 -38.95999828
OS 40.12161902 -38.49586916
OS 40.19281014 -38.49586916
OS 40.19281014 -38.56613572
OS 40.1937347 -38.56521116
OS 40.19743294 -38.55873924
OS 40.20205574 -38.5504182
OS 40.20945222 -38.54024804
OS 40.2168487 -38.53007788
OS 40.22516974 -38.51898316
OS 40.23349078 -38.50973756
OS 40.24181182 -38.50234108
OS 40.24273638 -38.50141652
OS 40.24551006 -38.4995674
OS 40.25105742 -38.49679372
OS 40.25660478 -38.49402004
OS 40.26400126 -38.49124636
OS 40.27324686 -38.48847268
OS 40.28249246 -38.48662356
OS 40.29266262 -38.485699
OS 40.29913454 -38.485699
OS 40.30745558 -38.48662356
OE
OB 39.48829542 -38.95999828 I
OS 39.3986131 -38.95999828
OS 39.3986131 -38.87031596
OS 39.48829542 -38.87031596
OS 39.48829542 -38.95999828
OE
OB 38.6404739 -38.95999828 I
OS 38.55171614 -38.95999828
OS 38.30393406 -38.32020276
OS 38.39639006 -38.32020276
OS 38.56281086 -38.78525644
OS 38.56281086 -38.786181
OS 38.56373542 -38.78803012
OS 38.56465998 -38.7908038
OS 38.5665091 -38.79450204
OS 38.56743366 -38.8000494
OS 38.56928278 -38.80559676
OS 38.57390558 -38.81946516
OS 38.57945294 -38.83518268
OS 38.5850003 -38.85274932
OS 38.59609502 -38.88973172
OS 38.59609502 -38.88880716
OS 38.59701958 -38.88695804
OS 38.59794414 -38.88418436
OS 38.5988687 -38.88048612
OS 38.60164238 -38.87031596
OS 38.60626518 -38.85644756
OS 38.61088798 -38.84073004
OS 38.61643534 -38.8231634
OS 38.62290726 -38.8046722
OS 38.63030374 -38.78525644
OS 38.80412102 -38.32020276
OS 38.8901051 -38.32020276
OS 38.6404739 -38.95999828
OE
OB 39.27564662 -38.42745172 I
OS 39.25438174 -38.54671996
OS 39.20538006 -38.54671996
OS 39.1859643 -38.42745172
OS 39.1859643 -38.32020276
OS 39.27564662 -38.32020276
OS 39.27564662 -38.42745172
OE
OB 40.49791494 -38.4117342 I
OS 40.41932734 -38.4117342
OS 40.41932734 -38.32020276
OS 40.49791494 -38.32020276
OS 40.49791494 -38.4117342
OE
OB 39.84517558 -38.48662356 I
OS 39.8516475 -38.48754812
OS 39.8655159 -38.48939724
OS 39.88215798 -38.49309548
OS 39.89972462 -38.49864284
OS 39.91729126 -38.50696388
OS 39.9348579 -38.51713404
OS 39.93578246 -38.51713404
OS 39.93670702 -38.51898316
OS 39.94225438 -38.5226814
OS 39.95057542 -38.53007788
OS 39.96074558 -38.53932348
OS 39.9718403 -38.55134276
OS 39.98293502 -38.56613572
OS 39.99402974 -38.58370236
OS 40.00327534 -38.60311812
OS 40.00327534 -38.60404268
OS 40.0041999 -38.6058918
OS 40.00512446 -38.60866548
OS 40.00697358 -38.61236372
OS 40.0088227 -38.61791108
OS 40.01067182 -38.624383
OS 40.01529462 -38.63917596
OS 40.01991742 -38.65766716
OS 40.02361566 -38.67800748
OS 40.02638934 -38.70112148
OS 40.0273139 -38.72516004
OS 40.0273139 -38.7260846
OS 40.0273139 -38.72793372
OS 40.0273139 -38.73163196
OS 40.0273139 -38.73717932
OS 40.02638934 -38.74365124
OS 40.02638934 -38.75104772
OS 40.02454022 -38.7676898
OS 40.02084198 -38.78803012
OS 40.01621918 -38.809295
OS 40.00974726 -38.83148444
OS 40.00142622 -38.85367388
OS 40.00142622 -38.85459844
OS 40.00050166 -38.85644756
OS 39.99865254 -38.85922124
OS 39.99680342 -38.86291948
OS 39.9903315 -38.87308964
OS 39.98201046 -38.88603348
OS 39.9718403 -38.89990188
OS 39.95889646 -38.91377028
OS 39.9441035 -38.92763868
OS 39.92653686 -38.94058252
OS 39.9256123 -38.94058252
OS 39.92468774 -38.94150708
OS 39.92191406 -38.9433562
OS 39.91821582 -38.94520532
OS 39.90897022 -38.94982812
OS 39.89602638 -38.95537548
OS 39.88030886 -38.96092284
OS 39.86366678 -38.96554564
OS 39.84425102 -38.96924388
OS 39.82483526 -38.97016844
OS 39.81836334 -38.97016844
OS 39.81096686 -38.96924388
OS 39.80172126 -38.96831932
OS 39.79062654 -38.9664702
OS 39.77860726 -38.96369652
OS 39.76658798 -38.95999828
OS 39.7545687 -38.95445092
OS 39.75364414 -38.95352636
OS 39.74902134 -38.95167724
OS 39.74347398 -38.947979
OS 39.7360775 -38.94243164
OS 39.72868102 -38.93688428
OS 39.71943542 -38.9294878
OS 39.71111438 -38.92116676
OS 39.7037179 -38.91192116
OS 39.7037179 -39.1375138
OS 39.6251303 -39.1375138
OS 39.6251303 -38.49586916
OS 39.69632142 -38.49586916
OS 39.69632142 -38.55689012
OS 39.69724598 -38.555041
OS 39.70094422 -38.55134276
OS 39.70556702 -38.54487084
OS 39.7129635 -38.53747436
OS 39.72128454 -38.52822876
OS 39.73053014 -38.51990772
OS 39.74162486 -38.51158668
OS 39.75271958 -38.5041902
OS 39.7545687 -38.50326564
OS 39.75826694 -38.50141652
OS 39.76566342 -38.49864284
OS 39.77490902 -38.4949446
OS 39.78600374 -38.49124636
OS 39.79894758 -38.48847268
OS 39.81374054 -38.48662356
OS 39.83038262 -38.485699
OS 39.84055278 -38.485699
OS 39.84517558 -38.48662356
OE
OB 44.92193454 -38.40988508 I
OS 44.84334694 -38.40988508
OS 44.84334694 -38.32020276
OS 44.92193454 -38.32020276
OS 44.92193454 -38.40988508
OE
OB 45.24553054 -38.48662356 I
OS 45.25385158 -38.48754812
OS 45.26309718 -38.48939724
OS 45.27326734 -38.49124636
OS 45.28528662 -38.49309548
OS 45.31024974 -38.50141652
OS 45.32319358 -38.50603932
OS 45.33613742 -38.51251124
OS 45.34908126 -38.51898316
OS 45.3620251 -38.52822876
OS 45.37404438 -38.53747436
OS 45.38606366 -38.54856908
OS 45.38698822 -38.54949364
OS 45.38883734 -38.55134276
OS 45.39161102 -38.555041
OS 45.39530926 -38.5596638
OS 45.39993206 -38.56613572
OS 45.40547942 -38.57445676
OS 45.41102678 -38.58370236
OS 45.41657414 -38.59387252
OS 45.4221215 -38.60496724
OS 45.42766886 -38.61883564
OS 45.43321622 -38.63270404
OS 45.43783902 -38.64842156
OS 45.44153726 -38.66506364
OS 45.44431094 -38.68263028
OS 45.44616006 -38.70112148
OS 45.44708462 -38.7214618
OS 45.44708462 -38.72238636
OS 45.44708462 -38.72516004
OS 45.44708462 -38.72978284
OS 45.44708462 -38.73625476
OS 45.44616006 -38.74365124
OS 45.4452355 -38.75289684
OS 45.4452355 -38.76214244
OS 45.44338638 -38.7723126
OS 45.4406127 -38.7954266
OS 45.43506534 -38.8185406
OS 45.42859342 -38.8416546
OS 45.41934782 -38.86291948
OS 45.41934782 -38.86384404
OS 45.41842326 -38.8647686
OS 45.41657414 -38.86754228
OS 45.41472502 -38.87124052
OS 45.4082531 -38.88048612
OS 45.39993206 -38.89158084
OS 45.38883734 -38.90452468
OS 45.37496894 -38.91746852
OS 45.35925142 -38.93041236
OS 45.34076022 -38.94243164
OS 45.33983566 -38.94243164
OS 45.3389111 -38.9433562
OS 45.33613742 -38.94520532
OS 45.33151462 -38.94705444
OS 45.32689182 -38.94890356
OS 45.32134446 -38.95075268
OS 45.30747606 -38.95630004
OS 45.29175854 -38.96092284
OS 45.27234278 -38.96554564
OS 45.25200246 -38.96924388
OS 45.22981302 -38.97016844
OS 45.22056742 -38.97016844
OS 45.21317094 -38.96924388
OS 45.2048499 -38.96831932
OS 45.1956043 -38.9664702
OS 45.18450958 -38.96462108
OS 45.17341486 -38.96277196
OS 45.14845174 -38.95537548
OS 45.13458334 -38.94982812
OS 45.1216395 -38.94428076
OS 45.10869566 -38.93688428
OS 45.09575182 -38.92856324
OS 45.08373254 -38.91931764
OS 45.07171326 -38.90822292
OS 45.0707887 -38.90729836
OS 45.06893958 -38.90544924
OS 45.0661659 -38.901751
OS 45.06246766 -38.89620364
OS 45.05784486 -38.88973172
OS 45.05322206 -38.88233524
OS 45.0476747 -38.87308964
OS 45.04212734 -38.86199492
OS 45.03657998 -38.84997564
OS 45.03103262 -38.83610724
OS 45.02640982 -38.82131428
OS 45.02178702 -38.80559676
OS 45.01808878 -38.78803012
OS 45.0153151 -38.76953892
OS 45.01346598 -38.7491986
OS 45.01254142 -38.72793372
OS 45.01254142 -38.7260846
OS 45.01254142 -38.72238636
OS 45.01346598 -38.71591444
OS 45.01346598 -38.70666884
OS 45.01439054 -38.69649868
OS 45.01623966 -38.68355484
OS 45.01808878 -38.670611
OS 45.02178702 -38.65581804
OS 45.02548526 -38.64102508
OS 45.03010806 -38.62530756
OS 45.03565542 -38.60866548
OS 45.0430519 -38.59294796
OS 45.05044838 -38.578155
OS 45.06061854 -38.56336204
OS 45.0707887 -38.54949364
OS 45.08373254 -38.53747436
OS 45.0846571 -38.5365498
OS 45.08650622 -38.53562524
OS 45.09020446 -38.53285156
OS 45.09482726 -38.52915332
OS 45.10037462 -38.52545508
OS 45.1077711 -38.52083228
OS 45.11516758 -38.51620948
OS 45.12441318 -38.51158668
OS 45.13458334 -38.50696388
OS 45.14567806 -38.50234108
OS 45.17064118 -38.49402004
OS 45.19930254 -38.48754812
OS 45.2140955 -38.48662356
OS 45.22981302 -38.485699
OS 45.23905862 -38.485699
OS 45.24553054 -38.48662356
OE
OB 44.92193454 -38.95999828 I
OS 44.84334694 -38.95999828
OS 44.84334694 -38.49586916
OS 44.92193454 -38.49586916
OS 44.92193454 -38.95999828
OE
OB 46.10722046 -38.42745172 I
OS 46.08595558 -38.54671996
OS 46.0369539 -38.54671996
OS 46.01753814 -38.42745172
OS 46.01753814 -38.32020276
OS 46.10722046 -38.32020276
OS 46.10722046 -38.42745172
OE
OB 45.77160518 -38.48662356 I
OS 45.78177534 -38.48754812
OS 45.79379462 -38.48939724
OS 45.80673846 -38.49217092
OS 45.82060686 -38.49586916
OS 45.8335507 -38.50141652
OS 45.83539982 -38.50234108
OS 45.83909806 -38.5041902
OS 45.84556998 -38.50696388
OS 45.85296646 -38.51158668
OS 45.86221206 -38.51713404
OS 45.8705331 -38.52453052
OS 45.87885414 -38.531927
OS 45.88625062 -38.5411726
OS 45.88717518 -38.54209716
OS 45.8890243 -38.5457954
OS 45.89179798 -38.5504182
OS 45.89642078 -38.55689012
OS 45.90011902 -38.56613572
OS 45.90381726 -38.57538132
OS 45.90844006 -38.58647604
OS 45.91121374 -38.59849532
OS 45.91121374 -38.59941988
OS 45.9121383 -38.60311812
OS 45.91306286 -38.60866548
OS 45.91398742 -38.61606196
OS 45.91398742 -38.62715668
OS 45.91491198 -38.64010052
OS 45.91583654 -38.65581804
OS 45.91583654 -38.6752338
OS 45.91583654 -38.95999828
OS 45.83724894 -38.95999828
OS 45.83724894 -38.67893204
OS 45.83724894 -38.67800748
OS 45.83724894 -38.67708292
OS 45.83724894 -38.670611
OS 45.83724894 -38.66228996
OS 45.83632438 -38.6521198
OS 45.83539982 -38.64010052
OS 45.8335507 -38.62808124
OS 45.83077702 -38.61698652
OS 45.82800334 -38.60681636
OS 45.82800334 -38.6058918
OS 45.82615422 -38.60311812
OS 45.82338054 -38.59849532
OS 45.82060686 -38.59294796
OS 45.81598406 -38.5874006
OS 45.8104367 -38.58092868
OS 45.80304022 -38.57445676
OS 45.79471918 -38.5689094
OS 45.79379462 -38.56798484
OS 45.79102094 -38.56613572
OS 45.78547358 -38.5642866
OS 45.77900166 -38.56151292
OS 45.77160518 -38.55873924
OS 45.76235958 -38.55596556
OS 45.75126486 -38.555041
OS 45.74017014 -38.55411644
OS 45.73554734 -38.55411644
OS 45.7318491 -38.555041
OS 45.7226035 -38.55596556
OS 45.71058422 -38.55781468
OS 45.69764038 -38.56243748
OS 45.68284742 -38.56798484
OS 45.66805446 -38.57538132
OS 45.65418606 -38.58647604
OS 45.65233694 -38.58832516
OS 45.6486387 -38.59294796
OS 45.64586502 -38.5966462
OS 45.64309134 -38.601269
OS 45.6393931 -38.60681636
OS 45.63661942 -38.61328828
OS 45.63292118 -38.62068476
OS 45.62922294 -38.62993036
OS 45.62644926 -38.64010052
OS 45.62367558 -38.65119524
OS 45.62182646 -38.66321452
OS 45.61997734 -38.67615836
OS 45.61812822 -38.69187588
OS 45.61812822 -38.7075934
OS 45.61812822 -38.95999828
OS 45.53954062 -38.95999828
OS 45.53954062 -38.49586916
OS 45.60980718 -38.49586916
OS 45.60980718 -38.56243748
OS 45.61073174 -38.56151292
OS 45.61258086 -38.55873924
OS 45.61535454 -38.555041
OS 45.61905278 -38.5504182
OS 45.62460014 -38.54487084
OS 45.63107206 -38.53839892
OS 45.63846854 -38.53100244
OS 45.64771414 -38.52360596
OS 45.65695974 -38.51713404
OS 45.66805446 -38.50973756
OS 45.68007374 -38.50326564
OS 45.69301758 -38.49771828
OS 45.70781054 -38.49309548
OS 45.7226035 -38.48939724
OS 45.73924558 -38.48662356
OS 45.75681222 -38.485699
OS 45.7642087 -38.485699
OS 45.77160518 -38.48662356
OE
OB 44.2756671 -38.95999828 I
OS 44.1970795 -38.95999828
OS 44.1970795 -38.49586916
OS 44.2756671 -38.49586916
OS 44.2756671 -38.95999828
OE
OB 43.4574315 -38.48662356 I
OS 43.46482798 -38.48754812
OS 43.47407358 -38.48939724
OS 43.48424374 -38.49124636
OS 43.49626302 -38.49402004
OS 43.50735774 -38.49679372
OS 43.52030158 -38.50141652
OS 43.53232086 -38.50603932
OS 43.5452647 -38.51251124
OS 43.55820854 -38.51990772
OS 43.57115238 -38.52822876
OS 43.58317166 -38.53839892
OS 43.59426638 -38.54949364
OS 43.59519094 -38.5504182
OS 43.59704006 -38.55226732
OS 43.59981374 -38.55596556
OS 43.60351198 -38.56151292
OS 43.60813478 -38.56798484
OS 43.61275758 -38.57538132
OS 43.61830494 -38.58462692
OS 43.6238523 -38.59572164
OS 43.62939966 -38.60774092
OS 43.63494702 -38.62068476
OS 43.63956982 -38.63547772
OS 43.64419262 -38.65119524
OS 43.64789086 -38.66876188
OS 43.65066454 -38.68725308
OS 43.65251366 -38.70666884
OS 43.65343822 -38.72793372
OS 43.65343822 -38.72885828
OS 43.65343822 -38.73255652
OS 43.65343822 -38.73902844
OS 43.65251366 -38.74827404
OS 43.30580366 -38.74827404
OS 43.30580366 -38.7491986
OS 43.30580366 -38.75197228
OS 43.30672822 -38.75567052
OS 43.30672822 -38.76121788
OS 43.30765278 -38.7676898
OS 43.3095019 -38.77508628
OS 43.31227558 -38.79172836
OS 43.31782294 -38.81021956
OS 43.32521942 -38.83055988
OS 43.33538958 -38.84905108
OS 43.34833342 -38.86569316
OS 43.34925798 -38.86569316
OS 43.35018254 -38.86754228
OS 43.3557299 -38.87216508
OS 43.36405094 -38.878637
OS 43.37514566 -38.88510892
OS 43.38993862 -38.8925054
OS 43.4065807 -38.89897732
OS 43.4250719 -38.90360012
OS 43.43524206 -38.90452468
OS 43.44633678 -38.90544924
OS 43.45373326 -38.90544924
OS 43.4620543 -38.90452468
OS 43.47222446 -38.90267556
OS 43.48331918 -38.89990188
OS 43.49626302 -38.89620364
OS 43.5082823 -38.89065628
OS 43.52030158 -38.8832598
OS 43.52122614 -38.88233524
OS 43.52584894 -38.878637
OS 43.5313963 -38.87308964
OS 43.53786822 -38.86569316
OS 43.5452647 -38.855523
OS 43.55358574 -38.84257916
OS 43.56190678 -38.8277862
OS 43.56930326 -38.81021956
OS 43.65066454 -38.82038972
OS 43.65066454 -38.82131428
OS 43.64973998 -38.8231634
OS 43.64881542 -38.82686164
OS 43.6469663 -38.832409
OS 43.64419262 -38.83795636
OS 43.64141894 -38.84535284
OS 43.63402246 -38.86107036
OS 43.62477686 -38.878637
OS 43.61183302 -38.8971282
OS 43.59704006 -38.91469484
OS 43.57854886 -38.93133692
OS 43.5776243 -38.93133692
OS 43.57577518 -38.93318604
OS 43.5730015 -38.93503516
OS 43.56930326 -38.93780884
OS 43.5637559 -38.94058252
OS 43.55820854 -38.9433562
OS 43.55081206 -38.94705444
OS 43.54249102 -38.95075268
OS 43.53324542 -38.95445092
OS 43.52399982 -38.95814916
OS 43.50088582 -38.96369652
OS 43.47499814 -38.96831932
OS 43.44633678 -38.97016844
OS 43.43616662 -38.97016844
OS 43.4296947 -38.96924388
OS 43.42137366 -38.96831932
OS 43.4112035 -38.9664702
OS 43.40010878 -38.96462108
OS 43.3880895 -38.96277196
OS 43.36220182 -38.95537548
OS 43.34833342 -38.94982812
OS 43.33538958 -38.94428076
OS 43.32152118 -38.93688428
OS 43.30857734 -38.92856324
OS 43.29655806 -38.91931764
OS 43.28453878 -38.90822292
OS 43.28361422 -38.90729836
OS 43.2817651 -38.90544924
OS 43.27899142 -38.901751
OS 43.27529318 -38.89620364
OS 43.27067038 -38.88973172
OS 43.26604758 -38.88233524
OS 43.26050022 -38.87308964
OS 43.25495286 -38.86291948
OS 43.2494055 -38.8509002
OS 43.24385814 -38.83795636
OS 43.23923534 -38.8231634
OS 43.23461254 -38.80744588
OS 43.2309143 -38.7908038
OS 43.22814062 -38.7723126
OS 43.2262915 -38.75289684
OS 43.22536694 -38.73255652
OS 43.22536694 -38.73163196
OS 43.22536694 -38.72700916
OS 43.22536694 -38.7214618
OS 43.2262915 -38.71314076
OS 43.22721606 -38.7029706
OS 43.22814062 -38.69187588
OS 43.22998974 -38.67893204
OS 43.23276342 -38.6659882
OS 43.2401599 -38.63640228
OS 43.2447827 -38.62160932
OS 43.25033006 -38.6058918
OS 43.25772654 -38.59109884
OS 43.26604758 -38.57723044
OS 43.27529318 -38.56336204
OS 43.28546334 -38.5504182
OS 43.2863879 -38.54949364
OS 43.28823702 -38.54764452
OS 43.29193526 -38.54487084
OS 43.29655806 -38.54024804
OS 43.30210542 -38.53562524
OS 43.3095019 -38.53007788
OS 43.31782294 -38.52360596
OS 43.3279931 -38.5180586
OS 43.33816326 -38.51158668
OS 43.35018254 -38.50603932
OS 43.36312638 -38.50049196
OS 43.37699478 -38.49586916
OS 43.39178774 -38.49124636
OS 43.40750526 -38.48847268
OS 43.42414734 -38.48662356
OS 43.44171398 -38.485699
OS 43.45095958 -38.485699
OS 43.4574315 -38.48662356
OE
OB 43.13938286 -38.48662356 I
OS 43.14955302 -38.48847268
OS 43.1615723 -38.49217092
OS 43.17451614 -38.49679372
OS 43.1893091 -38.50326564
OS 43.20502662 -38.51158668
OS 43.17636526 -38.58370236
OS 43.1754407 -38.5827778
OS 43.17174246 -38.58092868
OS 43.1661951 -38.578155
OS 43.15879862 -38.57538132
OS 43.15047758 -38.57260764
OS 43.14030742 -38.56983396
OS 43.13013726 -38.56798484
OS 43.1199671 -38.56706028
OS 43.1153443 -38.56706028
OS 43.1107215 -38.56798484
OS 43.10424958 -38.5689094
OS 43.09777766 -38.57075852
OS 43.08945662 -38.5735322
OS 43.08113558 -38.57723044
OS 43.0737391 -38.5827778
OS 43.07281454 -38.58370236
OS 43.07004086 -38.58555148
OS 43.06726718 -38.58924972
OS 43.06264438 -38.59387252
OS 43.05802158 -38.60034444
OS 43.05339878 -38.60774092
OS 43.04877598 -38.61606196
OS 43.04507774 -38.62623212
OS 43.04415318 -38.62808124
OS 43.04322862 -38.6336286
OS 43.0413795 -38.64194964
OS 43.03860582 -38.65304436
OS 43.03583214 -38.66691276
OS 43.03398302 -38.68263028
OS 43.03305846 -38.69927236
OS 43.0321339 -38.71776356
OS 43.0321339 -38.95999828
OS 42.9535463 -38.95999828
OS 42.9535463 -38.49586916
OS 43.02473742 -38.49586916
OS 43.02473742 -38.56613572
OS 43.02566198 -38.56521116
OS 43.02936022 -38.55873924
OS 43.03398302 -38.5504182
OS 43.0413795 -38.54024804
OS 43.04877598 -38.53007788
OS 43.05709702 -38.51898316
OS 43.06541806 -38.50973756
OS 43.0737391 -38.50234108
OS 43.07466366 -38.50141652
OS 43.07743734 -38.4995674
OS 43.0829847 -38.49679372
OS 43.08853206 -38.49402004
OS 43.09592854 -38.49124636
OS 43.10517414 -38.48847268
OS 43.11441974 -38.48662356
OS 43.1245899 -38.485699
OS 43.13106182 -38.485699
OS 43.13938286 -38.48662356
OE
OB 43.95022198 -38.95999828 I
OS 43.87533262 -38.95999828
OS 43.70059078 -38.49586916
OS 43.78380118 -38.49586916
OS 43.88365366 -38.77416172
OS 43.88365366 -38.77508628
OS 43.88457822 -38.77601084
OS 43.88550278 -38.77878452
OS 43.88642734 -38.7815582
OS 43.88920102 -38.7908038
OS 43.89289926 -38.80282308
OS 43.89752206 -38.81669148
OS 43.90306942 -38.832409
OS 43.90769222 -38.84997564
OS 43.91323958 -38.86754228
OS 43.91416414 -38.86569316
OS 43.9150887 -38.86107036
OS 43.91786238 -38.85367388
OS 43.92063606 -38.84257916
OS 43.92525886 -38.83055988
OS 43.92988166 -38.81484236
OS 43.93635358 -38.79820028
OS 43.9428255 -38.77970908
OS 44.04545166 -38.49586916
OS 44.12681294 -38.49586916
OS 43.95022198 -38.95999828
OE
OB 44.2756671 -38.40988508 I
OS 44.1970795 -38.40988508
OS 44.1970795 -38.32020276
OS 44.2756671 -38.32020276
OS 44.2756671 -38.40988508
OE
OB 44.5669035 -38.48662356 I
OS 44.5807719 -38.48754812
OS 44.59556486 -38.48939724
OS 44.61128238 -38.49309548
OS 44.62792446 -38.49679372
OS 44.64364198 -38.50234108
OS 44.64456654 -38.50234108
OS 44.6454911 -38.50326564
OS 44.6501139 -38.50511476
OS 44.65751038 -38.508813
OS 44.66675598 -38.5134358
OS 44.67692614 -38.51990772
OS 44.6870963 -38.5273042
OS 44.6963419 -38.53562524
OS 44.70466294 -38.54487084
OS 44.7055875 -38.5457954
OS 44.70743662 -38.54949364
OS 44.71113486 -38.55596556
OS 44.71575766 -38.56336204
OS 44.72038046 -38.57445676
OS 44.72500326 -38.58647604
OS 44.7287015 -38.60034444
OS 44.73239974 -38.61606196
OS 44.65566126 -38.62623212
OS 44.65566126 -38.624383
OS 44.6547367 -38.62068476
OS 44.65288758 -38.61421284
OS 44.6501139 -38.6058918
OS 44.6454911 -38.59757076
OS 44.63994374 -38.58832516
OS 44.63347182 -38.57907956
OS 44.62422622 -38.57075852
OS 44.62330166 -38.56983396
OS 44.61960342 -38.56798484
OS 44.61405606 -38.5642866
OS 44.60573502 -38.56058836
OS 44.59648942 -38.55689012
OS 44.58447014 -38.55319188
OS 44.56967718 -38.55134276
OS 44.55395966 -38.5504182
OS 44.54471406 -38.5504182
OS 44.53546846 -38.55134276
OS 44.52344918 -38.55226732
OS 44.5114299 -38.555041
OS 44.49848606 -38.55781468
OS 44.48646678 -38.56243748
OS 44.47629662 -38.5689094
OS 44.47537206 -38.56983396
OS 44.47259838 -38.57168308
OS 44.46890014 -38.57538132
OS 44.4652019 -38.58092868
OS 44.4605791 -38.58647604
OS 44.45688086 -38.59387252
OS 44.45410718 -38.60219356
OS 44.45318262 -38.6105146
OS 44.45318262 -38.61143916
OS 44.45318262 -38.61328828
OS 44.45410718 -38.61606196
OS 44.45410718 -38.6197602
OS 44.45688086 -38.6290058
OS 44.46242822 -38.6382514
OS 44.46335278 -38.63917596
OS 44.46427734 -38.64010052
OS 44.46612646 -38.6428742
OS 44.4698247 -38.64564788
OS 44.47352294 -38.64842156
OS 44.4790703 -38.6521198
OS 44.48554222 -38.65489348
OS 44.4929387 -38.65859172
OS 44.49386326 -38.65859172
OS 44.49571238 -38.65951628
OS 44.49941062 -38.66044084
OS 44.50588254 -38.66321452
OS 44.51512814 -38.6659882
OS 44.52714742 -38.66876188
OS 44.5345439 -38.67153556
OS 44.54286494 -38.67338468
OS 44.55211054 -38.67615836
OS 44.5622807 -38.67893204
OS 44.56320526 -38.67893204
OS 44.56597894 -38.6798566
OS 44.57060174 -38.68078116
OS 44.5761491 -38.68263028
OS 44.58262102 -38.6844794
OS 44.59094206 -38.68632852
OS 44.6085087 -38.69187588
OS 44.62792446 -38.69742324
OS 44.64734022 -38.70389516
OS 44.66490686 -38.71036708
OS 44.67230334 -38.71314076
OS 44.67877526 -38.71591444
OS 44.68062438 -38.716839
OS 44.68432262 -38.71868812
OS 44.68986998 -38.7214618
OS 44.69819102 -38.7260846
OS 44.70651206 -38.73163196
OS 44.7148331 -38.73902844
OS 44.72315414 -38.74734948
OS 44.73055062 -38.75659508
OS 44.73147518 -38.75751964
OS 44.7333243 -38.76121788
OS 44.73702254 -38.76676524
OS 44.74072078 -38.77508628
OS 44.74349446 -38.78525644
OS 44.7471927 -38.79635116
OS 44.74904182 -38.809295
OS 44.74996638 -38.82408796
OS 44.74996638 -38.82593708
OS 44.74996638 -38.83055988
OS 44.74904182 -38.83795636
OS 44.7471927 -38.84812652
OS 44.74441902 -38.85922124
OS 44.73979622 -38.87124052
OS 44.73424886 -38.88510892
OS 44.72685238 -38.89805276
OS 44.72592782 -38.89990188
OS 44.72222958 -38.90360012
OS 44.71760678 -38.91007204
OS 44.7102103 -38.91746852
OS 44.70004014 -38.92578956
OS 44.68894542 -38.93503516
OS 44.67600158 -38.9433562
OS 44.66028406 -38.95167724
OS 44.6593595 -38.95167724
OS 44.65843494 -38.9526018
OS 44.65288758 -38.95445092
OS 44.64364198 -38.9572246
OS 44.6316227 -38.96092284
OS 44.61682974 -38.96462108
OS 44.60018766 -38.96739476
OS 44.58262102 -38.96924388
OS 44.5622807 -38.97016844
OS 44.55395966 -38.97016844
OS 44.54748774 -38.96924388
OS 44.54009126 -38.96924388
OS 44.53084566 -38.96831932
OS 44.52160006 -38.96739476
OS 44.5114299 -38.96554564
OS 44.48924046 -38.96092284
OS 44.46612646 -38.95445092
OS 44.44393702 -38.94520532
OS 44.43376686 -38.93965796
OS 44.42452126 -38.93318604
OS 44.4235967 -38.93226148
OS 44.42267214 -38.93133692
OS 44.41712478 -38.92578956
OS 44.40880374 -38.91746852
OS 44.39955814 -38.90452468
OS 44.38938798 -38.88880716
OS 44.37921782 -38.87031596
OS 44.37089678 -38.84720196
OS 44.36442486 -38.82131428
OS 44.4420879 -38.809295
OS 44.4420879 -38.81021956
OS 44.4420879 -38.81114412
OS 44.44393702 -38.81669148
OS 44.44578614 -38.82593708
OS 44.44948438 -38.83610724
OS 44.45410718 -38.84720196
OS 44.45965454 -38.85922124
OS 44.46797558 -38.87124052
OS 44.47814574 -38.88141068
OS 44.47999486 -38.88233524
OS 44.4836931 -38.88510892
OS 44.49108958 -38.88880716
OS 44.50033518 -38.89342996
OS 44.51235446 -38.89805276
OS 44.52622286 -38.901751
OS 44.54286494 -38.90452468
OS 44.5622807 -38.90544924
OS 44.5715263 -38.90544924
OS 44.5807719 -38.90452468
OS 44.59279118 -38.90267556
OS 44.60573502 -38.89990188
OS 44.61960342 -38.89620364
OS 44.6316227 -38.89158084
OS 44.64271742 -38.88418436
OS 44.64364198 -38.8832598
OS 44.64734022 -38.88048612
OS 44.65103846 -38.87586332
OS 44.65658582 -38.8693914
OS 44.66120862 -38.86199492
OS 44.66583142 -38.85274932
OS 44.6686051 -38.84350372
OS 44.66952966 -38.832409
OS 44.66952966 -38.83148444
OS 44.66952966 -38.8277862
OS 44.6686051 -38.8231634
OS 44.66675598 -38.81669148
OS 44.6639823 -38.81021956
OS 44.6593595 -38.80374764
OS 44.65381214 -38.79635116
OS 44.6454911 -38.7908038
OS 44.64456654 -38.78987924
OS 44.64179286 -38.78895468
OS 44.63717006 -38.786181
OS 44.62977358 -38.78340732
OS 44.61867886 -38.77970908
OS 44.61220694 -38.7769354
OS 44.60481046 -38.77508628
OS 44.59648942 -38.7723126
OS 44.58724382 -38.76953892
OS 44.57707366 -38.76676524
OS 44.56505438 -38.76399156
OS 44.56412982 -38.76399156
OS 44.56135614 -38.763067
OS 44.55673334 -38.76214244
OS 44.55118598 -38.76029332
OS 44.5437895 -38.7584442
OS 44.53546846 -38.75567052
OS 44.51790182 -38.75104772
OS 44.4975615 -38.7445758
OS 44.47814574 -38.73902844
OS 44.45965454 -38.73255652
OS 44.4513335 -38.72885828
OS 44.44486158 -38.7260846
OS 44.44301246 -38.72516004
OS 44.43931422 -38.72331092
OS 44.43376686 -38.71961268
OS 44.42637038 -38.71498988
OS 44.41804934 -38.70851796
OS 44.4097283 -38.70112148
OS 44.40140726 -38.69280044
OS 44.39401078 -38.68263028
OS 44.39308622 -38.68170572
OS 44.3912371 -38.67800748
OS 44.38846342 -38.67153556
OS 44.38568974 -38.66413908
OS 44.38291606 -38.65489348
OS 44.38014238 -38.64379876
OS 44.37829326 -38.63270404
OS 44.3773687 -38.6197602
OS 44.3773687 -38.61791108
OS 44.3773687 -38.61421284
OS 44.37829326 -38.60866548
OS 44.37921782 -38.60034444
OS 44.38106694 -38.5920234
OS 44.38291606 -38.58185324
OS 44.3866143 -38.57260764
OS 44.3912371 -38.56243748
OS 44.39216166 -38.56151292
OS 44.39401078 -38.55781468
OS 44.39678446 -38.55319188
OS 44.40140726 -38.54671996
OS 44.40695462 -38.54024804
OS 44.41342654 -38.531927
OS 44.42082302 -38.52453052
OS 44.43006862 -38.5180586
OS 44.43099318 -38.51713404
OS 44.43376686 -38.51620948
OS 44.4374651 -38.5134358
OS 44.44301246 -38.51066212
OS 44.45040894 -38.50696388
OS 44.45872998 -38.50326564
OS 44.46890014 -38.4995674
OS 44.47999486 -38.49586916
OS 44.48184398 -38.4949446
OS 44.48554222 -38.49402004
OS 44.49201414 -38.49217092
OS 44.50033518 -38.4903218
OS 44.51050534 -38.48847268
OS 44.52160006 -38.48754812
OS 44.5345439 -38.485699
OS 44.55673334 -38.485699
OS 44.5669035 -38.48662356
OE
OB 33.15968222 -38.32112732 I
OS 33.17539974 -38.32205188
OS 33.19204182 -38.32297644
OS 33.20775934 -38.32482556
OS 33.22162774 -38.32667468
OS 33.22347686 -38.32667468
OS 33.22994878 -38.3285238
OS 33.23826982 -38.33037292
OS 33.24936454 -38.3331466
OS 33.26138382 -38.3377694
OS 33.27432766 -38.34331676
OS 33.28819606 -38.34978868
OS 33.30021534 -38.35718516
OS 33.30206446 -38.35810972
OS 33.3057627 -38.3608834
OS 33.31131006 -38.36643076
OS 33.31870654 -38.37290268
OS 33.32702758 -38.38122372
OS 33.33534862 -38.39231844
OS 33.34459422 -38.40433772
OS 33.3519907 -38.41820612
OS 33.35291526 -38.42005524
OS 33.35476438 -38.42467804
OS 33.35846262 -38.43299908
OS 33.36216086 -38.4440938
OS 33.36493454 -38.45703764
OS 33.36863278 -38.4718306
OS 33.3704819 -38.48847268
OS 33.37140646 -38.50603932
OS 33.37140646 -38.50696388
OS 33.37140646 -38.50973756
OS 33.37140646 -38.5134358
OS 33.3704819 -38.51990772
OS 33.36955734 -38.52637964
OS 33.36863278 -38.53470068
OS 33.36678366 -38.54394628
OS 33.36493454 -38.55411644
OS 33.35846262 -38.57538132
OS 33.35476438 -38.58647604
OS 33.34921702 -38.59849532
OS 33.3427451 -38.6105146
OS 33.33627318 -38.62160932
OS 33.32795214 -38.63270404
OS 33.31870654 -38.64379876
OS 33.31778198 -38.64472332
OS 33.31593286 -38.64657244
OS 33.31315918 -38.64934612
OS 33.30853638 -38.6521198
OS 33.30298902 -38.6567426
OS 33.29559254 -38.6613654
OS 33.28634694 -38.66691276
OS 33.27617678 -38.67153556
OS 33.2641575 -38.67708292
OS 33.2502891 -38.68263028
OS 33.23549614 -38.68725308
OS 33.2179295 -38.69095132
OS 33.1994383 -38.69464956
OS 33.17909798 -38.69742324
OS 33.15598398 -38.69927236
OS 33.13194542 -38.70019692
OS 32.9682983 -38.70019692
OS 32.9682983 -38.95999828
OS 32.88323878 -38.95999828
OS 32.88323878 -38.32020276
OS 33.14581382 -38.32020276
OS 33.15968222 -38.32112732
OE
OB 32.75195126 -38.98403684 I
OS 32.75195126 -38.9849614
OS 32.75195126 -38.98773508
OS 32.75195126 -38.99235788
OS 32.75195126 -38.99790524
OS 32.7510267 -39.00530172
OS 32.7510267 -39.0126982
OS 32.74917758 -39.0311894
OS 32.7464039 -39.05060516
OS 32.74270566 -39.07094548
OS 32.7371583 -39.08851212
OS 32.73346006 -39.09683316
OS 32.72976182 -39.10330508
OS 32.72976182 -39.10422964
OS 32.72883726 -39.1051542
OS 32.72421446 -39.109777
OS 32.71681798 -39.11717348
OS 32.70757238 -39.12549452
OS 32.69462854 -39.13381556
OS 32.67798646 -39.14028748
OS 32.6585707 -39.14583484
OS 32.64747598 -39.1467594
OS 32.6354567 -39.14768396
OS 32.62990934 -39.14768396
OS 32.62436198 -39.1467594
OS 32.61604094 -39.1467594
OS 32.60679534 -39.14583484
OS 32.59662518 -39.14398572
OS 32.57443574 -39.13843836
OS 32.5892287 -39.07187004
OS 32.59015326 -39.07187004
OS 32.59292694 -39.0727946
OS 32.59754974 -39.07371916
OS 32.60217254 -39.07464372
OS 32.61419182 -39.0774174
OS 32.61973918 -39.07834196
OS 32.62898478 -39.07834196
OS 32.63360758 -39.0774174
OS 32.63915494 -39.07649284
OS 32.6447023 -39.07464372
OS 32.65024966 -39.07094548
OS 32.65672158 -39.06724724
OS 32.66134438 -39.06169988
OS 32.66226894 -39.06077532
OS 32.6631935 -39.05800164
OS 32.66504262 -39.05337884
OS 32.6678163 -39.04598236
OS 32.66966542 -39.0358122
OS 32.67058998 -39.02841572
OS 32.67151454 -39.0219438
OS 32.6724391 -39.01362276
OS 32.6724391 -39.0034526
OS 32.67336366 -38.99328244
OS 32.67336366 -38.98218772
OS 32.67336366 -38.49586916
OS 32.75195126 -38.49586916
OS 32.75195126 -38.98403684
OE
OB 33.77174094 -38.3100326 I
OS 33.78006198 -38.31095716
OS 33.79023214 -38.31188172
OS 33.8004023 -38.31280628
OS 33.81242158 -38.31557996
OS 33.8373847 -38.32112732
OS 33.8651215 -38.32944836
OS 33.8789899 -38.33499572
OS 33.89193374 -38.34146764
OS 33.90487758 -38.34978868
OS 33.91782142 -38.35810972
OS 33.91874598 -38.35903428
OS 33.9205951 -38.35995884
OS 33.92429334 -38.36273252
OS 33.92891614 -38.36735532
OS 33.93353894 -38.37197812
OS 33.94001086 -38.37845004
OS 33.94648278 -38.38584652
OS 33.95387926 -38.393243
OS 33.96127574 -38.4024886
OS 33.96867222 -38.41358332
OS 33.97699326 -38.42467804
OS 33.98438974 -38.43669732
OS 33.99086166 -38.45056572
OS 33.99825814 -38.46443412
OS 34.0038055 -38.47922708
OS 34.00935286 -38.49586916
OS 33.92614246 -38.51528492
OS 33.92614246 -38.51436036
OS 33.9252179 -38.51251124
OS 33.92336878 -38.508813
OS 33.92151966 -38.5041902
OS 33.91967054 -38.49864284
OS 33.91689686 -38.49124636
OS 33.90950038 -38.4764534
OS 33.90025478 -38.45981132
OS 33.88916006 -38.44316924
OS 33.87529166 -38.42745172
OS 33.8604987 -38.41358332
OS 33.85864958 -38.4117342
OS 33.85310222 -38.40803596
OS 33.84385662 -38.40341316
OS 33.83183734 -38.39694124
OS 33.81611982 -38.39139388
OS 33.79855318 -38.38584652
OS 33.7772883 -38.38214828
OS 33.7541743 -38.38122372
OS 33.74677782 -38.38122372
OS 33.74215502 -38.38214828
OS 33.7356831 -38.38214828
OS 33.72828662 -38.38307284
OS 33.71071998 -38.38584652
OS 33.69130422 -38.38954476
OS 33.6709639 -38.39601668
OS 33.64969902 -38.40526228
OS 33.63028326 -38.41728156
OS 33.6293587 -38.41728156
OS 33.62843414 -38.41913068
OS 33.62196222 -38.42375348
OS 33.61364118 -38.43114996
OS 33.60347102 -38.44224468
OS 33.59145174 -38.45611308
OS 33.58035702 -38.4718306
OS 33.57018686 -38.49124636
OS 33.56094126 -38.51251124
OS 33.56094126 -38.5134358
OS 33.5600167 -38.51528492
OS 33.55909214 -38.5180586
OS 33.55816758 -38.5226814
OS 33.55631846 -38.52822876
OS 33.55446934 -38.53470068
OS 33.55169566 -38.5504182
OS 33.54799742 -38.5689094
OS 33.54429918 -38.58924972
OS 33.54245006 -38.61143916
OS 33.5415255 -38.63547772
OS 33.5415255 -38.63640228
OS 33.5415255 -38.63917596
OS 33.5415255 -38.64379876
OS 33.5415255 -38.64934612
OS 33.54245006 -38.65581804
OS 33.54245006 -38.66413908
OS 33.54337462 -38.67338468
OS 33.54429918 -38.68355484
OS 33.54707286 -38.70574428
OS 33.55169566 -38.72978284
OS 33.55724302 -38.7538214
OS 33.5646395 -38.77785996
OS 33.5646395 -38.77878452
OS 33.56556406 -38.78063364
OS 33.56741318 -38.78340732
OS 33.5692623 -38.78803012
OS 33.57480966 -38.79912484
OS 33.5831307 -38.81206868
OS 33.59330086 -38.82686164
OS 33.6062447 -38.84257916
OS 33.62103766 -38.85644756
OS 33.6386043 -38.8693914
OS 33.63952886 -38.8693914
OS 33.64137798 -38.87031596
OS 33.64415166 -38.87216508
OS 33.6478499 -38.8740142
OS 33.6524727 -38.87586332
OS 33.65802006 -38.878637
OS 33.6709639 -38.88418436
OS 33.68760598 -38.88973172
OS 33.70609718 -38.89435452
OS 33.7264375 -38.89805276
OS 33.74770238 -38.89897732
OS 33.7541743 -38.89897732
OS 33.75972166 -38.89805276
OS 33.76619358 -38.89805276
OS 33.7726655 -38.8971282
OS 33.78930758 -38.89342996
OS 33.80872334 -38.88880716
OS 33.8281391 -38.88141068
OS 33.84847942 -38.87124052
OS 33.85864958 -38.86569316
OS 33.86789518 -38.85829668
OS 33.86881974 -38.85737212
OS 33.8697443 -38.85644756
OS 33.87251798 -38.85367388
OS 33.87621622 -38.8509002
OS 33.87991446 -38.8462774
OS 33.88453726 -38.84073004
OS 33.89008462 -38.83518268
OS 33.89470742 -38.8277862
OS 33.90025478 -38.81946516
OS 33.9067267 -38.81021956
OS 33.91227406 -38.80097396
OS 33.91782142 -38.78987924
OS 33.92244422 -38.77785996
OS 33.92706702 -38.76491612
OS 33.93168982 -38.75104772
OS 33.93538806 -38.73625476
OS 34.02044758 -38.75751964
OS 34.02044758 -38.7584442
OS 34.01952302 -38.76214244
OS 34.0176739 -38.7676898
OS 34.01490022 -38.77508628
OS 34.01212654 -38.78340732
OS 34.0084283 -38.79357748
OS 34.0038055 -38.8046722
OS 33.99825814 -38.81669148
OS 33.9853143 -38.84257916
OS 33.96867222 -38.86846684
OS 33.95850206 -38.88141068
OS 33.9483319 -38.89435452
OS 33.93723718 -38.90544924
OS 33.92429334 -38.91654396
OS 33.92336878 -38.91746852
OS 33.92151966 -38.91931764
OS 33.91689686 -38.92116676
OS 33.91227406 -38.924865
OS 33.90487758 -38.9294878
OS 33.8974811 -38.9341106
OS 33.88731094 -38.9387334
OS 33.87714078 -38.9433562
OS 33.8651215 -38.94890356
OS 33.85217766 -38.95352636
OS 33.83830926 -38.95814916
OS 33.8235163 -38.96277196
OS 33.80779878 -38.9664702
OS 33.7911567 -38.96831932
OS 33.77359006 -38.97016844
OS 33.75509886 -38.971093
OS 33.7449287 -38.971093
OS 33.73753222 -38.97016844
OS 33.72921118 -38.97016844
OS 33.71904102 -38.96924388
OS 33.7079463 -38.96739476
OS 33.69500246 -38.96554564
OS 33.66819022 -38.96092284
OS 33.64045342 -38.95352636
OS 33.61271662 -38.9433562
OS 33.59977278 -38.93688428
OS 33.58682894 -38.9294878
OS 33.58590438 -38.92856324
OS 33.58405526 -38.92763868
OS 33.58035702 -38.924865
OS 33.57665878 -38.92116676
OS 33.57111142 -38.91746852
OS 33.5646395 -38.91192116
OS 33.55724302 -38.90544924
OS 33.54984654 -38.89805276
OS 33.54245006 -38.88973172
OS 33.53412902 -38.88141068
OS 33.51748694 -38.8601458
OS 33.50176942 -38.83518268
OS 33.48790102 -38.80744588
OS 33.48790102 -38.80652132
OS 33.4860519 -38.80374764
OS 33.48512734 -38.79912484
OS 33.48235366 -38.79357748
OS 33.48050454 -38.786181
OS 33.47773086 -38.7769354
OS 33.47403262 -38.76676524
OS 33.47125894 -38.75567052
OS 33.46848526 -38.74365124
OS 33.46478702 -38.72978284
OS 33.46016422 -38.70112148
OS 33.45646598 -38.66876188
OS 33.45461686 -38.63547772
OS 33.45461686 -38.63455316
OS 33.45461686 -38.63085492
OS 33.45461686 -38.62530756
OS 33.45554142 -38.61883564
OS 33.45554142 -38.60959004
OS 33.45646598 -38.60034444
OS 33.45739054 -38.58832516
OS 33.45923966 -38.57630588
OS 33.46386246 -38.54949364
OS 33.47033438 -38.51990772
OS 33.47957998 -38.4903218
OS 33.49252382 -38.46166044
OS 33.49344838 -38.46073588
OS 33.49437294 -38.4579622
OS 33.49622206 -38.45426396
OS 33.4999203 -38.44964116
OS 33.50361854 -38.44316924
OS 33.50824134 -38.43577276
OS 33.52026062 -38.41913068
OS 33.53597814 -38.40063948
OS 33.55446934 -38.38214828
OS 33.57573422 -38.36365708
OS 33.60069734 -38.34793956
OS 33.6016219 -38.347015
OS 33.60439558 -38.34609044
OS 33.60809382 -38.34424132
OS 33.61271662 -38.34146764
OS 33.6201131 -38.33869396
OS 33.62750958 -38.33592028
OS 33.63675518 -38.33222204
OS 33.64692534 -38.3285238
OS 33.65802006 -38.32482556
OS 33.67003934 -38.32112732
OS 33.69592702 -38.31557996
OS 33.72551294 -38.31095716
OS 33.75602342 -38.30910804
OS 33.76526902 -38.30910804
OS 33.77174094 -38.3100326
OE
OB 35.15858094 -39.1375138 I
OS 34.63805366 -39.1375138
OS 34.63805366 -39.08111564
OS 35.15858094 -39.08111564
OS 35.15858094 -39.1375138
OE
OB 34.37917686 -38.32112732 I
OS 34.38657334 -38.32112732
OS 34.40321542 -38.32297644
OS 34.42170662 -38.32482556
OS 34.44112238 -38.3285238
OS 34.46053814 -38.3331466
OS 34.47810478 -38.33961852
OS 34.47902934 -38.33961852
OS 34.4799539 -38.34054308
OS 34.48550126 -38.34331676
OS 34.4938223 -38.34793956
OS 34.5030679 -38.35441148
OS 34.51416262 -38.36273252
OS 34.5261819 -38.37290268
OS 34.53727662 -38.38584652
OS 34.54744678 -38.39971492
OS 34.54837134 -38.40156404
OS 34.55114502 -38.4071114
OS 34.55576782 -38.41450788
OS 34.56039062 -38.4256026
OS 34.56501342 -38.43854644
OS 34.56963622 -38.45241484
OS 34.5724099 -38.46813236
OS 34.57333446 -38.48384988
OS 34.57333446 -38.485699
OS 34.57333446 -38.4903218
OS 34.5724099 -38.49864284
OS 34.57056078 -38.508813
OS 34.5677871 -38.52083228
OS 34.5631643 -38.53377612
OS 34.55761694 -38.54671996
OS 34.55022046 -38.56058836
OS 34.5492959 -38.56243748
OS 34.54652222 -38.56613572
OS 34.54097486 -38.5735322
OS 34.53357838 -38.58092868
OS 34.52433278 -38.59017428
OS 34.51323806 -38.60034444
OS 34.49936966 -38.60959004
OS 34.48365214 -38.61883564
OS 34.4845767 -38.61883564
OS 34.48642582 -38.6197602
OS 34.4891995 -38.62068476
OS 34.49289774 -38.62253388
OS 34.50399246 -38.62623212
OS 34.5169363 -38.63270404
OS 34.5308047 -38.64102508
OS 34.54652222 -38.65119524
OS 34.56039062 -38.66321452
OS 34.57333446 -38.67800748
OS 34.57425902 -38.6798566
OS 34.57795726 -38.68540396
OS 34.58350462 -38.693725
OS 34.58905198 -38.70481972
OS 34.59459934 -38.71961268
OS 34.6001467 -38.7353302
OS 34.60384494 -38.7538214
OS 34.6047695 -38.77416172
OS 34.6047695 -38.77508628
OS 34.6047695 -38.77601084
OS 34.6047695 -38.7815582
OS 34.60384494 -38.7908038
OS 34.60199582 -38.80189852
OS 34.6001467 -38.81484236
OS 34.59644846 -38.82871076
OS 34.59182566 -38.84350372
OS 34.58535374 -38.85829668
OS 34.58442918 -38.8601458
OS 34.5816555 -38.8647686
OS 34.57795726 -38.87124052
OS 34.5724099 -38.88048612
OS 34.56501342 -38.88973172
OS 34.55761694 -38.89990188
OS 34.54837134 -38.91007204
OS 34.53820118 -38.91839308
OS 34.53727662 -38.91931764
OS 34.53357838 -38.92209132
OS 34.52710646 -38.92578956
OS 34.51878542 -38.9294878
OS 34.50861526 -38.93503516
OS 34.49659598 -38.94058252
OS 34.48365214 -38.94520532
OS 34.46793462 -38.94982812
OS 34.4660855 -38.94982812
OS 34.46053814 -38.95167724
OS 34.45129254 -38.9526018
OS 34.43927326 -38.95445092
OS 34.4244803 -38.95630004
OS 34.40691366 -38.95814916
OS 34.3874979 -38.95907372
OS 34.36530846 -38.95999828
OS 34.12122462 -38.95999828
OS 34.12122462 -38.32020276
OS 34.37270494 -38.32020276
OS 34.37917686 -38.32112732
OE
OB 31.74233174 -38.95999828 I
OS 31.65264942 -38.95999828
OS 31.65264942 -38.87031596
OS 31.74233174 -38.87031596
OS 31.74233174 -38.95999828
OE
OB 31.52968294 -38.42745172 I
OS 31.50841806 -38.54671996
OS 31.45941638 -38.54671996
OS 31.44000062 -38.42745172
OS 31.44000062 -38.32020276
OS 31.52968294 -38.32020276
OS 31.52968294 -38.42745172
OE
OB 32.0992119 -38.48662356 I
OS 32.10568382 -38.48754812
OS 32.11955222 -38.48939724
OS 32.1361943 -38.49309548
OS 32.15376094 -38.49864284
OS 32.17132758 -38.50696388
OS 32.18889422 -38.51713404
OS 32.18981878 -38.51713404
OS 32.19074334 -38.51898316
OS 32.1962907 -38.5226814
OS 32.20461174 -38.53007788
OS 32.2147819 -38.53932348
OS 32.22587662 -38.55134276
OS 32.23697134 -38.56613572
OS 32.24806606 -38.58370236
OS 32.25731166 -38.60311812
OS 32.25731166 -38.60404268
OS 32.25823622 -38.6058918
OS 32.25916078 -38.60866548
OS 32.2610099 -38.61236372
OS 32.26285902 -38.61791108
OS 32.26470814 -38.624383
OS 32.26933094 -38.63917596
OS 32.27395374 -38.65766716
OS 32.27765198 -38.67800748
OS 32.28042566 -38.70112148
OS 32.28135022 -38.72516004
OS 32.28135022 -38.7260846
OS 32.28135022 -38.72793372
OS 32.28135022 -38.73163196
OS 32.28135022 -38.73717932
OS 32.28042566 -38.74365124
OS 32.28042566 -38.75104772
OS 32.27857654 -38.7676898
OS 32.2748783 -38.78803012
OS 32.2702555 -38.809295
OS 32.26378358 -38.83148444
OS 32.25546254 -38.85367388
OS 32.25546254 -38.85459844
OS 32.25453798 -38.85644756
OS 32.25268886 -38.85922124
OS 32.25083974 -38.86291948
OS 32.24436782 -38.87308964
OS 32.23604678 -38.88603348
OS 32.22587662 -38.89990188
OS 32.21293278 -38.91377028
OS 32.19813982 -38.92763868
OS 32.18057318 -38.94058252
OS 32.17964862 -38.94058252
OS 32.17872406 -38.94150708
OS 32.17595038 -38.9433562
OS 32.17225214 -38.94520532
OS 32.16300654 -38.94982812
OS 32.1500627 -38.95537548
OS 32.13434518 -38.96092284
OS 32.1177031 -38.96554564
OS 32.09828734 -38.96924388
OS 32.07887158 -38.97016844
OS 32.07239966 -38.97016844
OS 32.06500318 -38.96924388
OS 32.05575758 -38.96831932
OS 32.04466286 -38.9664702
OS 32.03264358 -38.96369652
OS 32.0206243 -38.95999828
OS 32.00860502 -38.95445092
OS 32.00768046 -38.95352636
OS 32.00305766 -38.95167724
OS 31.9975103 -38.947979
OS 31.99011382 -38.94243164
OS 31.98271734 -38.93688428
OS 31.97347174 -38.9294878
OS 31.9651507 -38.92116676
OS 31.95775422 -38.91192116
OS 31.95775422 -39.1375138
OS 31.87916662 -39.1375138
OS 31.87916662 -38.49586916
OS 31.95035774 -38.49586916
OS 31.95035774 -38.55689012
OS 31.9512823 -38.555041
OS 31.95498054 -38.55134276
OS 31.95960334 -38.54487084
OS 31.96699982 -38.53747436
OS 31.97532086 -38.52822876
OS 31.98456646 -38.51990772
OS 31.99566118 -38.51158668
OS 32.0067559 -38.5041902
OS 32.00860502 -38.50326564
OS 32.01230326 -38.50141652
OS 32.01969974 -38.49864284
OS 32.02894534 -38.4949446
OS 32.04004006 -38.49124636
OS 32.0529839 -38.48847268
OS 32.06777686 -38.48662356
OS 32.08441894 -38.485699
OS 32.0945891 -38.485699
OS 32.0992119 -38.48662356
OE
OB 32.5614919 -38.48662356 I
OS 32.57166206 -38.48847268
OS 32.58368134 -38.49217092
OS 32.59662518 -38.49679372
OS 32.61141814 -38.50326564
OS 32.62713566 -38.51158668
OS 32.5984743 -38.58370236
OS 32.59754974 -38.5827778
OS 32.5938515 -38.58092868
OS 32.58830414 -38.578155
OS 32.58090766 -38.57538132
OS 32.57258662 -38.57260764
OS 32.56241646 -38.56983396
OS 32.5522463 -38.56798484
OS 32.54207614 -38.56706028
OS 32.53745334 -38.56706028
OS 32.53283054 -38.56798484
OS 32.52635862 -38.5689094
OS 32.5198867 -38.57075852
OS 32.51156566 -38.5735322
OS 32.50324462 -38.57723044
OS 32.49584814 -38.5827778
OS 32.49492358 -38.58370236
OS 32.4921499 -38.58555148
OS 32.48937622 -38.58924972
OS 32.48475342 -38.59387252
OS 32.48013062 -38.60034444
OS 32.47550782 -38.60774092
OS 32.47088502 -38.61606196
OS 32.46718678 -38.62623212
OS 32.46626222 -38.62808124
OS 32.46533766 -38.6336286
OS 32.46348854 -38.64194964
OS 32.46071486 -38.65304436
OS 32.45794118 -38.66691276
OS 32.45609206 -38.68263028
OS 32.4551675 -38.69927236
OS 32.45424294 -38.71776356
OS 32.45424294 -38.95999828
OS 32.37565534 -38.95999828
OS 32.37565534 -38.49586916
OS 32.44684646 -38.49586916
OS 32.44684646 -38.56613572
OS 32.44777102 -38.56521116
OS 32.45146926 -38.55873924
OS 32.45609206 -38.5504182
OS 32.46348854 -38.54024804
OS 32.47088502 -38.53007788
OS 32.47920606 -38.51898316
OS 32.4875271 -38.50973756
OS 32.49584814 -38.50234108
OS 32.4967727 -38.50141652
OS 32.49954638 -38.4995674
OS 32.50509374 -38.49679372
OS 32.5106411 -38.49402004
OS 32.51803758 -38.49124636
OS 32.52728318 -38.48847268
OS 32.53652878 -38.48662356
OS 32.54669894 -38.485699
OS 32.55317086 -38.485699
OS 32.5614919 -38.48662356
OE
OB 32.75195126 -38.4117342 I
OS 32.67336366 -38.4117342
OS 32.67336366 -38.32020276
OS 32.75195126 -38.32020276
OS 32.75195126 -38.4117342
OE
OB 36.56668582 -38.95999828 I
OS 36.47885262 -38.95999828
OS 36.1441619 -38.4579622
OS 36.1441619 -38.95999828
OS 36.06280062 -38.95999828
OS 36.06280062 -38.32020276
OS 36.14970926 -38.32020276
OS 36.48532454 -38.8231634
OS 36.48532454 -38.32020276
OS 36.56668582 -38.32020276
OS 36.56668582 -38.95999828
OE
OB 35.74382742 -38.32112732 I
OS 35.75954494 -38.32205188
OS 35.77618702 -38.32297644
OS 35.79190454 -38.32482556
OS 35.80577294 -38.32667468
OS 35.80762206 -38.32667468
OS 35.81409398 -38.3285238
OS 35.82241502 -38.33037292
OS 35.83350974 -38.3331466
OS 35.84552902 -38.3377694
OS 35.85847286 -38.34331676
OS 35.87234126 -38.34978868
OS 35.88436054 -38.35718516
OS 35.88620966 -38.35810972
OS 35.8899079 -38.3608834
OS 35.89545526 -38.36643076
OS 35.90285174 -38.37290268
OS 35.91117278 -38.38122372
OS 35.91949382 -38.39231844
OS 35.92873942 -38.40433772
OS 35.9361359 -38.41820612
OS 35.93706046 -38.42005524
OS 35.93890958 -38.42467804
OS 35.94260782 -38.43299908
OS 35.94630606 -38.4440938
OS 35.94907974 -38.45703764
OS 35.95277798 -38.4718306
OS 35.9546271 -38.48847268
OS 35.95555166 -38.50603932
OS 35.95555166 -38.50696388
OS 35.95555166 -38.50973756
OS 35.95555166 -38.5134358
OS 35.9546271 -38.51990772
OS 35.95370254 -38.52637964
OS 35.95277798 -38.53470068
OS 35.95092886 -38.54394628
OS 35.94907974 -38.55411644
OS 35.94260782 -38.57538132
OS 35.93890958 -38.58647604
OS 35.93336222 -38.59849532
OS 35.9268903 -38.6105146
OS 35.92041838 -38.62160932
OS 35.91209734 -38.63270404
OS 35.90285174 -38.64379876
OS 35.90192718 -38.64472332
OS 35.90007806 -38.64657244
OS 35.89730438 -38.64934612
OS 35.89268158 -38.6521198
OS 35.88713422 -38.6567426
OS 35.87973774 -38.6613654
OS 35.87049214 -38.66691276
OS 35.86032198 -38.67153556
OS 35.8483027 -38.67708292
OS 35.8344343 -38.68263028
OS 35.81964134 -38.68725308
OS 35.8020747 -38.69095132
OS 35.7835835 -38.69464956
OS 35.76324318 -38.69742324
OS 35.74012918 -38.69927236
OS 35.71609062 -38.70019692
OS 35.5524435 -38.70019692
OS 35.5524435 -38.95999828
OS 35.46738398 -38.95999828
OS 35.46738398 -38.32020276
OS 35.72995902 -38.32020276
OS 35.74382742 -38.32112732
OE
OB 36.76916446 -38.42745172 I
OS 36.74789958 -38.54671996
OS 36.6988979 -38.54671996
OS 36.67948214 -38.42745172
OS 36.67948214 -38.32020276
OS 36.76916446 -38.32020276
OS 36.76916446 -38.42745172
OE
OB 38.2382903 -38.39601668 I
OS 37.86014526 -38.39601668
OS 37.86014526 -38.59109884
OS 38.21425174 -38.59109884
OS 38.21425174 -38.66691276
OS 37.86014526 -38.66691276
OS 37.86014526 -38.88418436
OS 38.25308326 -38.88418436
OS 38.25308326 -38.95999828
OS 37.77508574 -38.95999828
OS 37.77508574 -38.32020276
OS 38.2382903 -38.32020276
OS 38.2382903 -38.39601668
OE
OB 37.4339231 -38.32112732 I
OS 37.44224414 -38.32112732
OS 37.4616599 -38.32205188
OS 37.48200022 -38.32482556
OS 37.50418966 -38.32759924
OS 37.52452998 -38.33222204
OS 37.53470014 -38.33499572
OS 37.54302118 -38.3377694
OS 37.54394574 -38.3377694
OS 37.5448703 -38.33869396
OS 37.55041766 -38.34146764
OS 37.5587387 -38.34516588
OS 37.56890886 -38.3516378
OS 37.58000358 -38.35995884
OS 37.59202286 -38.37105356
OS 37.60311758 -38.3839974
OS 37.6142123 -38.39879036
OS 37.6142123 -38.39971492
OS 37.61513686 -38.40063948
OS 37.6188351 -38.40618684
OS 37.62253334 -38.41543244
OS 37.6280807 -38.42745172
OS 37.6327035 -38.44132012
OS 37.6373263 -38.4579622
OS 37.64009998 -38.47552884
OS 37.64102454 -38.4949446
OS 37.64102454 -38.49586916
OS 37.64102454 -38.49771828
OS 37.64102454 -38.50141652
OS 37.64009998 -38.50603932
OS 37.64009998 -38.51251124
OS 37.63917542 -38.51898316
OS 37.63547718 -38.53470068
OS 37.62992982 -38.55319188
OS 37.62253334 -38.57260764
OS 37.61143862 -38.5920234
OS 37.60404214 -38.601269
OS 37.59664566 -38.6105146
OS 37.5957211 -38.61143916
OS 37.59479654 -38.61236372
OS 37.59202286 -38.6151374
OS 37.58832462 -38.61791108
OS 37.58370182 -38.62160932
OS 37.57815446 -38.62530756
OS 37.57075798 -38.62993036
OS 37.5633615 -38.63547772
OS 37.5541159 -38.64010052
OS 37.54394574 -38.64472332
OS 37.53285102 -38.65027068
OS 37.52083174 -38.65489348
OS 37.50696334 -38.65859172
OS 37.49309494 -38.66321452
OS 37.47737742 -38.6659882
OS 37.46073534 -38.66876188
OS 37.46258446 -38.66968644
OS 37.4662827 -38.67153556
OS 37.47183006 -38.6752338
OS 37.47922654 -38.67893204
OS 37.49586862 -38.6891022
OS 37.50418966 -38.69557412
OS 37.51158614 -38.70112148
OS 37.51343526 -38.7029706
OS 37.51805806 -38.7075934
OS 37.52545454 -38.71498988
OS 37.53470014 -38.72423548
OS 37.5448703 -38.73717932
OS 37.55688958 -38.75104772
OS 37.56890886 -38.7676898
OS 37.5818527 -38.786181
OS 37.69187534 -38.95999828
OS 37.5864755 -38.95999828
OS 37.50234054 -38.82686164
OS 37.50234054 -38.82593708
OS 37.50049142 -38.82408796
OS 37.4986423 -38.82131428
OS 37.49586862 -38.81761604
OS 37.4893967 -38.80744588
OS 37.48107566 -38.79450204
OS 37.4709055 -38.78063364
OS 37.46073534 -38.76584068
OS 37.45056518 -38.75197228
OS 37.44131958 -38.73902844
OS 37.44039502 -38.73810388
OS 37.43762134 -38.73440564
OS 37.43299854 -38.72885828
OS 37.42652662 -38.72238636
OS 37.41265822 -38.70851796
OS 37.40526174 -38.70204604
OS 37.39786526 -38.69649868
OS 37.3969407 -38.69557412
OS 37.39509158 -38.69464956
OS 37.39139334 -38.69280044
OS 37.38584598 -38.69002676
OS 37.38029862 -38.68725308
OS 37.3738267 -38.6844794
OS 37.35903374 -38.6798566
OS 37.35810918 -38.6798566
OS 37.35626006 -38.67893204
OS 37.35256182 -38.67893204
OS 37.34793902 -38.67800748
OS 37.3414671 -38.67708292
OS 37.33407062 -38.67708292
OS 37.32390046 -38.67615836
OS 37.21480238 -38.67615836
OS 37.21480238 -38.95999828
OS 37.12974286 -38.95999828
OS 37.12974286 -38.32020276
OS 37.42652662 -38.32020276
OS 37.4339231 -38.32112732
OE
OB 35.31760526 -38.95999828 I
OS 35.23254574 -38.95999828
OS 35.23254574 -38.32020276
OS 35.31760526 -38.32020276
OS 35.31760526 -38.95999828
OE
OB 42.12051774 -38.66413908 H
OS 41.95224782 -38.66413908
OS 41.95224782 -38.88418436
OS 42.13438614 -38.88418436
OS 42.1538019 -38.8832598
OS 42.16212294 -38.88233524
OS 42.16951942 -38.88141068
OS 42.17044398 -38.88141068
OS 42.17414222 -38.88048612
OS 42.17968958 -38.87956156
OS 42.1861615 -38.87771244
OS 42.20187902 -38.87216508
OS 42.21759654 -38.8647686
OS 42.2185211 -38.86384404
OS 42.22129478 -38.86199492
OS 42.22499302 -38.85922124
OS 42.22961582 -38.855523
OS 42.23423862 -38.84997564
OS 42.24071054 -38.84442828
OS 42.24533334 -38.8370318
OS 42.2508807 -38.82871076
OS 42.25180526 -38.8277862
OS 42.25272982 -38.82501252
OS 42.25457894 -38.81946516
OS 42.25735262 -38.81299324
OS 42.2601263 -38.80559676
OS 42.26197542 -38.79635116
OS 42.26289998 -38.78525644
OS 42.26382454 -38.77416172
OS 42.26382454 -38.7723126
OS 42.26382454 -38.76861436
OS 42.26289998 -38.76121788
OS 42.26105086 -38.75289684
OS 42.25920174 -38.74365124
OS 42.2555035 -38.73348108
OS 42.2508807 -38.72331092
OS 42.24440878 -38.71314076
OS 42.24348422 -38.7122162
OS 42.24071054 -38.70851796
OS 42.2370123 -38.70389516
OS 42.23146494 -38.6983478
OS 42.22406846 -38.69187588
OS 42.21482286 -38.68540396
OS 42.2046527 -38.6798566
OS 42.19263342 -38.6752338
OS 42.1907843 -38.67430924
OS 42.18708606 -38.67338468
OS 42.17876502 -38.67153556
OS 42.16859486 -38.66968644
OS 42.15565102 -38.66783732
OS 42.1399335 -38.6659882
OS 42.12051774 -38.66413908
OE
OB 45.22981302 -38.5504182 H
OS 45.22426566 -38.5504182
OS 45.21964286 -38.55134276
OS 45.2094727 -38.55226732
OS 45.1956043 -38.55596556
OS 45.17988678 -38.56151292
OS 45.1632447 -38.5689094
OS 45.14752718 -38.58000412
OS 45.13920614 -38.5874006
OS 45.13180966 -38.59479708
OS 45.13180966 -38.59572164
OS 45.12996054 -38.5966462
OS 45.12811142 -38.59941988
OS 45.12533774 -38.60311812
OS 45.12256406 -38.60774092
OS 45.11979038 -38.61328828
OS 45.11609214 -38.62068476
OS 45.1123939 -38.62808124
OS 45.10869566 -38.63732684
OS 45.10499742 -38.64657244
OS 45.10222374 -38.65766716
OS 45.09945006 -38.66968644
OS 45.09667638 -38.68263028
OS 45.09482726 -38.69649868
OS 45.0939027 -38.7122162
OS 45.09297814 -38.72793372
OS 45.09297814 -38.72885828
OS 45.09297814 -38.73163196
OS 45.09297814 -38.73625476
OS 45.0939027 -38.74272668
OS 45.0939027 -38.75012316
OS 45.09482726 -38.7584442
OS 45.09760094 -38.77785996
OS 45.10222374 -38.8000494
OS 45.10962022 -38.82223884
OS 45.11886582 -38.84350372
OS 45.12533774 -38.85274932
OS 45.13180966 -38.86199492
OS 45.13273422 -38.86199492
OS 45.13365878 -38.86384404
OS 45.13920614 -38.86846684
OS 45.14752718 -38.87586332
OS 45.1586219 -38.8832598
OS 45.1724903 -38.89158084
OS 45.18913238 -38.89897732
OS 45.20854814 -38.90360012
OS 45.2187183 -38.90452468
OS 45.22981302 -38.90544924
OS 45.23536038 -38.90544924
OS 45.23998318 -38.90452468
OS 45.25015334 -38.90267556
OS 45.26402174 -38.89990188
OS 45.2788147 -38.89435452
OS 45.29545678 -38.88695804
OS 45.3111743 -38.87586332
OS 45.31949534 -38.86846684
OS 45.32689182 -38.86107036
OS 45.32781638 -38.8601458
OS 45.32874094 -38.85922124
OS 45.33059006 -38.85644756
OS 45.33336374 -38.85274932
OS 45.33613742 -38.84812652
OS 45.33983566 -38.84257916
OS 45.3435339 -38.83518268
OS 45.34723214 -38.8277862
OS 45.35093038 -38.8185406
OS 45.35370406 -38.80837044
OS 45.3574023 -38.79727572
OS 45.36017598 -38.78525644
OS 45.36294966 -38.77138804
OS 45.36479878 -38.75751964
OS 45.3666479 -38.74180212
OS 45.3666479 -38.72516004
OS 45.3666479 -38.72423548
OS 45.3666479 -38.7214618
OS 45.3666479 -38.716839
OS 45.36572334 -38.71129164
OS 45.36572334 -38.70389516
OS 45.36479878 -38.69557412
OS 45.3620251 -38.67615836
OS 45.3574023 -38.65581804
OS 45.35000582 -38.6336286
OS 45.33983566 -38.61328828
OS 45.3342883 -38.60311812
OS 45.32689182 -38.59479708
OS 45.32689182 -38.59387252
OS 45.3250427 -38.59294796
OS 45.31949534 -38.5874006
OS 45.3111743 -38.58092868
OS 45.30007958 -38.57260764
OS 45.28621118 -38.5642866
OS 45.2695691 -38.55689012
OS 45.2510779 -38.55226732
OS 45.24090774 -38.55134276
OS 45.22981302 -38.5504182
OE
OB 32.07702246 -38.54764452 H
OS 32.07239966 -38.54764452
OS 32.06870142 -38.54856908
OS 32.05945582 -38.5504182
OS 32.04743654 -38.55319188
OS 32.03356814 -38.55873924
OS 32.01877518 -38.56706028
OS 32.01045414 -38.57260764
OS 32.00305766 -38.57907956
OS 31.99566118 -38.58647604
OS 31.9882647 -38.59479708
OS 31.9882647 -38.59572164
OS 31.98641558 -38.5966462
OS 31.98456646 -38.59941988
OS 31.98271734 -38.60311812
OS 31.97994366 -38.60866548
OS 31.97624542 -38.61421284
OS 31.97254718 -38.62160932
OS 31.9697735 -38.6290058
OS 31.96607526 -38.6382514
OS 31.96237702 -38.64842156
OS 31.95960334 -38.65951628
OS 31.9559051 -38.67153556
OS 31.95405598 -38.68540396
OS 31.95220686 -38.69927236
OS 31.95035774 -38.71406532
OS 31.95035774 -38.7307074
OS 31.95035774 -38.73163196
OS 31.95035774 -38.73440564
OS 31.95035774 -38.73902844
OS 31.9512823 -38.74550036
OS 31.9512823 -38.75289684
OS 31.95220686 -38.76121788
OS 31.95498054 -38.78063364
OS 31.95960334 -38.80282308
OS 31.9651507 -38.82408796
OS 31.9743963 -38.84535284
OS 31.97994366 -38.85459844
OS 31.98641558 -38.86291948
OS 31.9882647 -38.8647686
OS 31.9928875 -38.8693914
OS 32.00028398 -38.87678788
OS 32.01045414 -38.88418436
OS 32.02339798 -38.89158084
OS 32.03819094 -38.89897732
OS 32.05483302 -38.90360012
OS 32.06407862 -38.90452468
OS 32.07332422 -38.90544924
OS 32.07887158 -38.90544924
OS 32.08256982 -38.90452468
OS 32.09181542 -38.90267556
OS 32.10475926 -38.89990188
OS 32.11862766 -38.89435452
OS 32.13342062 -38.88695804
OS 32.14821358 -38.87586332
OS 32.15561006 -38.8693914
OS 32.16300654 -38.86199492
OS 32.16300654 -38.86107036
OS 32.16485566 -38.8601458
OS 32.16670478 -38.85737212
OS 32.1685539 -38.85367388
OS 32.17225214 -38.84905108
OS 32.17502582 -38.84257916
OS 32.17872406 -38.83610724
OS 32.1824223 -38.8277862
OS 32.18519598 -38.81946516
OS 32.18889422 -38.80837044
OS 32.19259246 -38.79727572
OS 32.19536614 -38.78525644
OS 32.19721526 -38.77138804
OS 32.19906438 -38.75659508
OS 32.2009135 -38.74087756
OS 32.2009135 -38.72423548
OS 32.2009135 -38.72331092
OS 32.2009135 -38.72053724
OS 32.2009135 -38.71591444
OS 32.19998894 -38.70944252
OS 32.19998894 -38.70204604
OS 32.19906438 -38.693725
OS 32.1962907 -38.67430924
OS 32.1916679 -38.65304436
OS 32.18519598 -38.63177948
OS 32.17595038 -38.6105146
OS 32.17040302 -38.60034444
OS 32.1639311 -38.5920234
OS 32.1639311 -38.59109884
OS 32.16208198 -38.59017428
OS 32.15745918 -38.58462692
OS 32.1500627 -38.578155
OS 32.13989254 -38.56983396
OS 32.1269487 -38.56151292
OS 32.11215574 -38.55411644
OS 32.09551366 -38.54949364
OS 32.08626806 -38.54856908
OS 32.07702246 -38.54764452
OE
OB 42.10387566 -38.39601668 H
OS 41.95224782 -38.39601668
OS 41.95224782 -38.58832516
OS 42.10942302 -38.58832516
OS 42.1214423 -38.5874006
OS 42.13438614 -38.58647604
OS 42.14732998 -38.58555148
OS 42.16027382 -38.58370236
OS 42.17044398 -38.58185324
OS 42.1722931 -38.58092868
OS 42.17599134 -38.58000412
OS 42.1815387 -38.57723044
OS 42.18893518 -38.5735322
OS 42.19633166 -38.56983396
OS 42.2046527 -38.5642866
OS 42.21297374 -38.55689012
OS 42.21944566 -38.54949364
OS 42.22037022 -38.54856908
OS 42.22221934 -38.5457954
OS 42.22499302 -38.54024804
OS 42.2277667 -38.53377612
OS 42.23054038 -38.52637964
OS 42.23331406 -38.51713404
OS 42.23516318 -38.50603932
OS 42.23608774 -38.49402004
OS 42.23608774 -38.49217092
OS 42.23608774 -38.48847268
OS 42.23516318 -38.48292532
OS 42.23423862 -38.47552884
OS 42.2323895 -38.46628324
OS 42.22961582 -38.45703764
OS 42.22591758 -38.44779204
OS 42.22037022 -38.43854644
OS 42.21944566 -38.43762188
OS 42.21759654 -38.4348482
OS 42.2138983 -38.4302254
OS 42.2092755 -38.4256026
OS 42.20280358 -38.42005524
OS 42.1954071 -38.41450788
OS 42.1861615 -38.40896052
OS 42.17599134 -38.40526228
OS 42.17506678 -38.40526228
OS 42.17044398 -38.40341316
OS 42.16397206 -38.4024886
OS 42.1538019 -38.40063948
OS 42.1399335 -38.39879036
OS 42.12421598 -38.3978658
OS 42.10387566 -38.39601668
OE
OB 37.41635646 -38.39139388 H
OS 37.21480238 -38.39139388
OS 37.21480238 -38.60311812
OS 37.40526174 -38.60311812
OS 37.41635646 -38.60219356
OS 37.4293003 -38.601269
OS 37.44409326 -38.60034444
OS 37.45888622 -38.59849532
OS 37.47367918 -38.59572164
OS 37.48662302 -38.5920234
OS 37.48847214 -38.59109884
OS 37.49217038 -38.58924972
OS 37.49771774 -38.58647604
OS 37.50511422 -38.5827778
OS 37.51343526 -38.57723044
OS 37.5217563 -38.57075852
OS 37.53007734 -38.56243748
OS 37.53654926 -38.55319188
OS 37.53747382 -38.55226732
OS 37.53932294 -38.54856908
OS 37.54209662 -38.54302172
OS 37.54579486 -38.53562524
OS 37.54856854 -38.5273042
OS 37.55134222 -38.5180586
OS 37.55319134 -38.50696388
OS 37.5541159 -38.49586916
OS 37.5541159 -38.4949446
OS 37.5541159 -38.49402004
OS 37.55319134 -38.48847268
OS 37.55226678 -38.48015164
OS 37.55041766 -38.46905692
OS 37.54579486 -38.4579622
OS 37.5402475 -38.44501836
OS 37.53192646 -38.43299908
OS 37.52083174 -38.4209798
OS 37.51898262 -38.42005524
OS 37.51435982 -38.416357
OS 37.50696334 -38.4117342
OS 37.49494406 -38.40618684
OS 37.48107566 -38.40063948
OS 37.46258446 -38.39601668
OS 37.44131958 -38.39231844
OS 37.41635646 -38.39139388
OE
OB 39.82298614 -38.54764452 H
OS 39.81836334 -38.54764452
OS 39.8146651 -38.54856908
OS 39.8054195 -38.5504182
OS 39.79340022 -38.55319188
OS 39.77953182 -38.55873924
OS 39.76473886 -38.56706028
OS 39.75641782 -38.57260764
OS 39.74902134 -38.57907956
OS 39.74162486 -38.58647604
OS 39.73422838 -38.59479708
OS 39.73422838 -38.59572164
OS 39.73237926 -38.5966462
OS 39.73053014 -38.59941988
OS 39.72868102 -38.60311812
OS 39.72590734 -38.60866548
OS 39.7222091 -38.61421284
OS 39.71851086 -38.62160932
OS 39.71573718 -38.6290058
OS 39.71203894 -38.6382514
OS 39.7083407 -38.64842156
OS 39.70556702 -38.65951628
OS 39.70186878 -38.67153556
OS 39.70001966 -38.68540396
OS 39.69817054 -38.69927236
OS 39.69632142 -38.71406532
OS 39.69632142 -38.7307074
OS 39.69632142 -38.73163196
OS 39.69632142 -38.73440564
OS 39.69632142 -38.73902844
OS 39.69724598 -38.74550036
OS 39.69724598 -38.75289684
OS 39.69817054 -38.76121788
OS 39.70094422 -38.78063364
OS 39.70556702 -38.80282308
OS 39.71111438 -38.82408796
OS 39.72035998 -38.84535284
OS 39.72590734 -38.85459844
OS 39.73237926 -38.86291948
OS 39.73422838 -38.8647686
OS 39.73885118 -38.8693914
OS 39.74624766 -38.87678788
OS 39.75641782 -38.88418436
OS 39.76936166 -38.89158084
OS 39.78415462 -38.89897732
OS 39.8007967 -38.90360012
OS 39.8100423 -38.90452468
OS 39.8192879 -38.90544924
OS 39.82483526 -38.90544924
OS 39.8285335 -38.90452468
OS 39.8377791 -38.90267556
OS 39.85072294 -38.89990188
OS 39.86459134 -38.89435452
OS 39.8793843 -38.88695804
OS 39.89417726 -38.87586332
OS 39.90157374 -38.8693914
OS 39.90897022 -38.86199492
OS 39.90897022 -38.86107036
OS 39.91081934 -38.8601458
OS 39.91266846 -38.85737212
OS 39.91451758 -38.85367388
OS 39.91821582 -38.84905108
OS 39.9209895 -38.84257916
OS 39.92468774 -38.83610724
OS 39.92838598 -38.8277862
OS 39.93115966 -38.81946516
OS 39.9348579 -38.80837044
OS 39.93855614 -38.79727572
OS 39.94132982 -38.78525644
OS 39.94317894 -38.77138804
OS 39.94502806 -38.75659508
OS 39.94687718 -38.74087756
OS 39.94687718 -38.72423548
OS 39.94687718 -38.72331092
OS 39.94687718 -38.72053724
OS 39.94687718 -38.71591444
OS 39.94595262 -38.70944252
OS 39.94595262 -38.70204604
OS 39.94502806 -38.693725
OS 39.94225438 -38.67430924
OS 39.93763158 -38.65304436
OS 39.93115966 -38.63177948
OS 39.92191406 -38.6105146
OS 39.9163667 -38.60034444
OS 39.90989478 -38.5920234
OS 39.90989478 -38.59109884
OS 39.90804566 -38.59017428
OS 39.90342286 -38.58462692
OS 39.89602638 -38.578155
OS 39.88585622 -38.56983396
OS 39.87291238 -38.56151292
OS 39.85811942 -38.55411644
OS 39.84147734 -38.54949364
OS 39.83223174 -38.54856908
OS 39.82298614 -38.54764452
OE
OB 35.73550638 -38.39601668 H
OS 35.5524435 -38.39601668
OS 35.5524435 -38.624383
OS 35.72441166 -38.624383
OS 35.73088358 -38.62345844
OS 35.7373555 -38.62345844
OS 35.74475198 -38.62253388
OS 35.76231862 -38.62068476
OS 35.78173438 -38.61698652
OS 35.80115014 -38.61143916
OS 35.81871678 -38.60404268
OS 35.82703782 -38.59941988
OS 35.83350974 -38.59387252
OS 35.83535886 -38.5920234
OS 35.8390571 -38.58832516
OS 35.84460446 -38.58092868
OS 35.85107638 -38.57168308
OS 35.8575483 -38.5596638
OS 35.86309566 -38.54487084
OS 35.8667939 -38.52822876
OS 35.86864302 -38.508813
OS 35.86864302 -38.50788844
OS 35.86864302 -38.50696388
OS 35.86864302 -38.50234108
OS 35.86771846 -38.49402004
OS 35.86586934 -38.48477444
OS 35.86402022 -38.47460428
OS 35.86032198 -38.462585
OS 35.85477462 -38.45149028
OS 35.8483027 -38.44039556
OS 35.84737814 -38.439471
OS 35.84460446 -38.43577276
OS 35.83998166 -38.43114996
OS 35.8344343 -38.42467804
OS 35.82611326 -38.41820612
OS 35.81686766 -38.41265876
OS 35.8066975 -38.4071114
OS 35.79467822 -38.4024886
OS 35.79375366 -38.4024886
OS 35.79005542 -38.40156404
OS 35.78450806 -38.40063948
OS 35.77711158 -38.39879036
OS 35.76601686 -38.3978658
OS 35.75214846 -38.39694124
OS 35.73550638 -38.39601668
OE
OB 43.44263854 -38.5504182 H
OS 43.43709118 -38.5504182
OS 43.43339294 -38.55134276
OS 43.42322278 -38.55226732
OS 43.4112035 -38.555041
OS 43.39641054 -38.5596638
OS 43.38069302 -38.56613572
OS 43.36590006 -38.57538132
OS 43.3511071 -38.5874006
OS 43.34925798 -38.58924972
OS 43.34555974 -38.59387252
OS 43.33908782 -38.60219356
OS 43.3326159 -38.61328828
OS 43.32521942 -38.62623212
OS 43.3187475 -38.6428742
OS 43.31320014 -38.66228996
OS 43.31042646 -38.68355484
OS 43.57022782 -38.68355484
OS 43.57022782 -38.68263028
OS 43.57022782 -38.68078116
OS 43.56930326 -38.67800748
OS 43.56930326 -38.67430924
OS 43.56745414 -38.66321452
OS 43.56468046 -38.65119524
OS 43.56005766 -38.63640228
OS 43.55543486 -38.62253388
OS 43.54803838 -38.60866548
OS 43.53971734 -38.5966462
OS 43.53971734 -38.59572164
OS 43.53786822 -38.59479708
OS 43.53324542 -38.58924972
OS 43.52492438 -38.58185324
OS 43.51382966 -38.5735322
OS 43.49996126 -38.56521116
OS 43.48331918 -38.55781468
OS 43.46390342 -38.55226732
OS 43.45373326 -38.55134276
OS 43.44263854 -38.5504182
OE
OB 34.35791198 -38.39601668 H
OS 34.20628414 -38.39601668
OS 34.20628414 -38.58832516
OS 34.36345934 -38.58832516
OS 34.37547862 -38.5874006
OS 34.38842246 -38.58647604
OS 34.4013663 -38.58555148
OS 34.41431014 -38.58370236
OS 34.4244803 -38.58185324
OS 34.42632942 -38.58092868
OS 34.43002766 -38.58000412
OS 34.43557502 -38.57723044
OS 34.4429715 -38.5735322
OS 34.45036798 -38.56983396
OS 34.45868902 -38.5642866
OS 34.46701006 -38.55689012
OS 34.47348198 -38.54949364
OS 34.47440654 -38.54856908
OS 34.47625566 -38.5457954
OS 34.47902934 -38.54024804
OS 34.48180302 -38.53377612
OS 34.4845767 -38.52637964
OS 34.48735038 -38.51713404
OS 34.4891995 -38.50603932
OS 34.49012406 -38.49402004
OS 34.49012406 -38.49217092
OS 34.49012406 -38.48847268
OS 34.4891995 -38.48292532
OS 34.48827494 -38.47552884
OS 34.48642582 -38.46628324
OS 34.48365214 -38.45703764
OS 34.4799539 -38.44779204
OS 34.47440654 -38.43854644
OS 34.47348198 -38.43762188
OS 34.47163286 -38.4348482
OS 34.46793462 -38.4302254
OS 34.46331182 -38.4256026
OS 34.4568399 -38.42005524
OS 34.44944342 -38.41450788
OS 34.44019782 -38.40896052
OS 34.43002766 -38.40526228
OS 34.4291031 -38.40526228
OS 34.4244803 -38.40341316
OS 34.41800838 -38.4024886
OS 34.40783822 -38.40063948
OS 34.39396982 -38.39879036
OS 34.3782523 -38.3978658
OS 34.35791198 -38.39601668
OE
OB 40.89732486 -38.39601668 H
OS 40.71426198 -38.39601668
OS 40.71426198 -38.624383
OS 40.88623014 -38.624383
OS 40.89270206 -38.62345844
OS 40.89917398 -38.62345844
OS 40.90657046 -38.62253388
OS 40.9241371 -38.62068476
OS 40.94355286 -38.61698652
OS 40.96296862 -38.61143916
OS 40.98053526 -38.60404268
OS 40.9888563 -38.59941988
OS 40.99532822 -38.59387252
OS 40.99717734 -38.5920234
OS 41.00087558 -38.58832516
OS 41.00642294 -38.58092868
OS 41.01289486 -38.57168308
OS 41.01936678 -38.5596638
OS 41.02491414 -38.54487084
OS 41.02861238 -38.52822876
OS 41.0304615 -38.508813
OS 41.0304615 -38.50788844
OS 41.0304615 -38.50696388
OS 41.0304615 -38.50234108
OS 41.02953694 -38.49402004
OS 41.02768782 -38.48477444
OS 41.0258387 -38.47460428
OS 41.02214046 -38.462585
OS 41.0165931 -38.45149028
OS 41.01012118 -38.44039556
OS 41.00919662 -38.439471
OS 41.00642294 -38.43577276
OS 41.00180014 -38.43114996
OS 40.99625278 -38.42467804
OS 40.98793174 -38.41820612
OS 40.97868614 -38.41265876
OS 40.96851598 -38.4071114
OS 40.9564967 -38.4024886
OS 40.95557214 -38.4024886
OS 40.9518739 -38.40156404
OS 40.94632654 -38.40063948
OS 40.93893006 -38.39879036
OS 40.92783534 -38.3978658
OS 40.91396694 -38.39694124
OS 40.89732486 -38.39601668
OE
OB 33.15136118 -38.39601668 H
OS 32.9682983 -38.39601668
OS 32.9682983 -38.624383
OS 33.14026646 -38.624383
OS 33.14673838 -38.62345844
OS 33.1532103 -38.62345844
OS 33.16060678 -38.62253388
OS 33.17817342 -38.62068476
OS 33.19758918 -38.61698652
OS 33.21700494 -38.61143916
OS 33.23457158 -38.60404268
OS 33.24289262 -38.59941988
OS 33.24936454 -38.59387252
OS 33.25121366 -38.5920234
OS 33.2549119 -38.58832516
OS 33.26045926 -38.58092868
OS 33.26693118 -38.57168308
OS 33.2734031 -38.5596638
OS 33.27895046 -38.54487084
OS 33.2826487 -38.52822876
OS 33.28449782 -38.508813
OS 33.28449782 -38.50788844
OS 33.28449782 -38.50696388
OS 33.28449782 -38.50234108
OS 33.28357326 -38.49402004
OS 33.28172414 -38.48477444
OS 33.27987502 -38.47460428
OS 33.27617678 -38.462585
OS 33.27062942 -38.45149028
OS 33.2641575 -38.44039556
OS 33.26323294 -38.439471
OS 33.26045926 -38.43577276
OS 33.25583646 -38.43114996
OS 33.2502891 -38.42467804
OS 33.24196806 -38.41820612
OS 33.23272246 -38.41265876
OS 33.2225523 -38.4071114
OS 33.21053302 -38.4024886
OS 33.20960846 -38.4024886
OS 33.20591022 -38.40156404
OS 33.20036286 -38.40063948
OS 33.19296638 -38.39879036
OS 33.18187166 -38.3978658
OS 33.16800326 -38.39694124
OS 33.15136118 -38.39601668
OE
OB 34.37455406 -38.66413908 H
OS 34.20628414 -38.66413908
OS 34.20628414 -38.88418436
OS 34.38842246 -38.88418436
OS 34.40783822 -38.8832598
OS 34.41615926 -38.88233524
OS 34.42355574 -38.88141068
OS 34.4244803 -38.88141068
OS 34.42817854 -38.88048612
OS 34.4337259 -38.87956156
OS 34.44019782 -38.87771244
OS 34.45591534 -38.87216508
OS 34.47163286 -38.8647686
OS 34.47255742 -38.86384404
OS 34.4753311 -38.86199492
OS 34.47902934 -38.85922124
OS 34.48365214 -38.855523
OS 34.48827494 -38.84997564
OS 34.49474686 -38.84442828
OS 34.49936966 -38.8370318
OS 34.50491702 -38.82871076
OS 34.50584158 -38.8277862
OS 34.50676614 -38.82501252
OS 34.50861526 -38.81946516
OS 34.51138894 -38.81299324
OS 34.51416262 -38.80559676
OS 34.51601174 -38.79635116
OS 34.5169363 -38.78525644
OS 34.51786086 -38.77416172
OS 34.51786086 -38.7723126
OS 34.51786086 -38.76861436
OS 34.5169363 -38.76121788
OS 34.51508718 -38.75289684
OS 34.51323806 -38.74365124
OS 34.50953982 -38.73348108
OS 34.50491702 -38.72331092
OS 34.4984451 -38.71314076
OS 34.49752054 -38.7122162
OS 34.49474686 -38.70851796
OS 34.49104862 -38.70389516
OS 34.48550126 -38.6983478
OS 34.47810478 -38.69187588
OS 34.46885918 -38.68540396
OS 34.45868902 -38.6798566
OS 34.44666974 -38.6752338
OS 34.44482062 -38.67430924
OS 34.44112238 -38.67338468
OS 34.43280134 -38.67153556
OS 34.42263118 -38.66968644
OS 34.40968734 -38.66783732
OS 34.39396982 -38.6659882
OS 34.37455406 -38.66413908
OE
SE
S P 0
OB 48.49040086 -36.61402634 I
OS 48.17420134 -36.61402634
OS 48.17420134 -37.45999874
OS 48.04661206 -37.45999874
OS 48.04661206 -36.61402634
OS 47.73041254 -36.61402634
OS 47.73041254 -36.50030546
OS 48.49040086 -36.50030546
OS 48.49040086 -36.61402634
OE
OB 47.69990206 -37.45999874 I
OS 47.5556707 -37.45999874
OS 47.44333666 -37.16876234
OS 47.04115306 -37.16876234
OS 46.93714006 -37.45999874
OS 46.80261658 -37.45999874
OS 47.16874234 -36.50030546
OS 47.30742634 -36.50030546
OS 47.69990206 -37.45999874
OE
OB 49.31834434 -36.61402634 I
OS 48.75112678 -36.61402634
OS 48.75112678 -36.90664958
OS 49.2822865 -36.90664958
OS 49.2822865 -37.02037046
OS 48.75112678 -37.02037046
OS 48.75112678 -37.34627786
OS 49.34053378 -37.34627786
OS 49.34053378 -37.45999874
OS 48.6235375 -37.45999874
OS 48.6235375 -36.50030546
OS 49.31834434 -36.50030546
OS 49.31834434 -36.61402634
OE
OB 46.33386466 -36.5016923 I
OS 46.36160146 -36.50307914
OS 46.38933826 -36.50585282
OS 46.41707506 -36.51001334
OS 46.44065134 -36.51417386
OS 46.44203818 -36.51417386
OS 46.44481186 -36.5155607
OS 46.44897238 -36.5155607
OS 46.45451974 -36.51833438
OS 46.46977498 -36.5224949
OS 46.48919074 -36.5294291
OS 46.51138018 -36.53913698
OS 46.53495646 -36.55161854
OS 46.55853274 -36.56548694
OS 46.58072218 -36.58351586
OS 46.58210902 -36.5849027
OS 46.58349586 -36.58628954
OS 46.58765638 -36.59045006
OS 46.59320374 -36.59461058
OS 46.60707214 -36.60847898
OS 46.62371422 -36.62789474
OS 46.64174314 -36.65147102
OS 46.6611589 -36.67920782
OS 46.67918782 -36.71110514
OS 46.69444306 -36.74716298
OS 46.69444306 -36.74854982
OS 46.6958299 -36.7513235
OS 46.69860358 -36.75687086
OS 46.69999042 -36.7651919
OS 46.70415094 -36.77489978
OS 46.70692462 -36.7859945
OS 46.7096983 -36.79847606
OS 46.71385882 -36.8137313
OS 46.71801934 -36.82898654
OS 46.72079302 -36.84701546
OS 46.72772722 -36.88584698
OS 46.73188774 -36.92883902
OS 46.73327458 -36.97599158
OS 46.73327458 -36.97737842
OS 46.73327458 -36.9801521
OS 46.73327458 -36.9870863
OS 46.73327458 -36.9940205
OS 46.73188774 -37.00372838
OS 46.73188774 -37.0148231
OS 46.7305009 -37.04117306
OS 46.72634038 -37.07168354
OS 46.72217986 -37.10358086
OS 46.71524566 -37.13686502
OS 46.70692462 -37.17014918
OS 46.70692462 -37.17153602
OS 46.70553778 -37.1743097
OS 46.70415094 -37.17847022
OS 46.7027641 -37.18401758
OS 46.69721674 -37.19927282
OS 46.6888957 -37.21868858
OS 46.68057466 -37.24087802
OS 46.66947994 -37.26306746
OS 46.65561154 -37.28664374
OS 46.64174314 -37.30883318
OS 46.6403563 -37.31160686
OS 46.63480894 -37.31854106
OS 46.6264879 -37.32824894
OS 46.61539318 -37.3407305
OS 46.60291162 -37.3545989
OS 46.58765638 -37.3684673
OS 46.57240114 -37.38372254
OS 46.55437222 -37.3962041
OS 46.55159854 -37.39759094
OS 46.54605118 -37.40175146
OS 46.5363433 -37.40729882
OS 46.5224749 -37.41423302
OS 46.50583282 -37.42255406
OS 46.48641706 -37.42948826
OS 46.46422762 -37.4378093
OS 46.4392645 -37.4447435
OS 46.43649082 -37.4447435
OS 46.4323303 -37.44613034
OS 46.42816978 -37.44751718
OS 46.41430138 -37.44890402
OS 46.39488562 -37.4516777
OS 46.37269618 -37.45445138
OS 46.34634622 -37.45722506
OS 46.31722258 -37.4586119
OS 46.28532526 -37.45999874
OS 45.9400021 -37.45999874
OS 45.9400021 -36.50030546
OS 46.30890154 -36.50030546
OS 46.33386466 -36.5016923
OE
OB 46.28948578 -36.61402634 H
OS 46.06759138 -36.61402634
OS 46.06759138 -37.34627786
OS 46.29503314 -37.34627786
OS 46.30474102 -37.34489102
OS 46.32554362 -37.34350418
OS 46.3491199 -37.34211734
OS 46.37408302 -37.33934366
OS 46.39904614 -37.33518314
OS 46.41984874 -37.32963578
OS 46.42262242 -37.32824894
OS 46.42955662 -37.3268621
OS 46.4392645 -37.32270158
OS 46.45174606 -37.31715422
OS 46.46561446 -37.30883318
OS 46.47948286 -37.30051214
OS 46.49335126 -37.29080426
OS 46.50721966 -37.27970954
OS 46.5086065 -37.27693586
OS 46.51415386 -37.2713885
OS 46.5224749 -37.26168062
OS 46.53218278 -37.24781222
OS 46.5432775 -37.2297833
OS 46.55575906 -37.2089807
OS 46.56685378 -37.18540442
OS 46.57656166 -37.15905446
OS 46.57656166 -37.15766762
OS 46.5779485 -37.15489394
OS 46.57933534 -37.15073342
OS 46.58072218 -37.14518606
OS 46.58210902 -37.13825186
OS 46.5848827 -37.12854398
OS 46.58765638 -37.1188361
OS 46.59043006 -37.10774138
OS 46.59459058 -37.08000458
OS 46.5987511 -37.04810726
OS 46.60152478 -37.01204942
OS 46.60291162 -36.9732179
OS 46.60291162 -36.97183106
OS 46.60291162 -36.9662837
OS 46.60291162 -36.9593495
OS 46.60152478 -36.94825478
OS 46.60152478 -36.93577322
OS 46.60013794 -36.92190482
OS 46.5987511 -36.90526274
OS 46.59736426 -36.88862066
OS 46.59043006 -36.85117598
OS 46.58210902 -36.81234446
OS 46.56962746 -36.77628662
OS 46.56130642 -36.7582577
OS 46.55298538 -36.74300246
OS 46.55298538 -36.74161562
OS 46.5502117 -36.73884194
OS 46.54743802 -36.73468142
OS 46.54466434 -36.72913406
OS 46.53356962 -36.71526566
OS 46.51970122 -36.69862358
OS 46.5016723 -36.68059466
OS 46.4808697 -36.66256574
OS 46.45729342 -36.6473105
OS 46.4323303 -36.63482894
OS 46.42955662 -36.6334421
OS 46.42262242 -36.63205526
OS 46.41014086 -36.62789474
OS 46.39211194 -36.62373422
OS 46.3699225 -36.62096054
OS 46.3421857 -36.61680002
OS 46.32554362 -36.61541318
OS 46.3075147 -36.61541318
OS 46.28948578 -36.61402634
OE
OB 47.23531066 -36.60015794 H
OS 47.23531066 -36.60154478
OS 47.23392382 -36.60431846
OS 47.23392382 -36.60986582
OS 47.23115014 -36.61541318
OS 47.2297633 -36.62512106
OS 47.22698962 -36.63482894
OS 47.22144226 -36.65840522
OS 47.21450806 -36.68614202
OS 47.20480018 -36.7166525
OS 47.1950923 -36.74993666
OS 47.18261074 -36.78460766
OS 47.07859774 -37.06474934
OS 47.4031183 -37.06474934
OS 47.30326582 -36.80124974
OS 47.30326582 -36.7998629
OS 47.30187898 -36.79570238
OS 47.2991053 -36.78876818
OS 47.29633162 -36.78044714
OS 47.2921711 -36.77073926
OS 47.28801058 -36.7582577
OS 47.28385006 -36.7443893
OS 47.2783027 -36.7305209
OS 47.26720798 -36.69862358
OS 47.25611326 -36.66533942
OS 47.24501854 -36.63205526
OS 47.23531066 -36.60015794
OE
SE
S P 0
OB 53.64989524 -38.94890356 I
OS 53.57130764 -38.94890356
OS 53.57130764 -38.4487166
OS 53.57038308 -38.44964116
OS 53.56576028 -38.4533394
OS 53.56021292 -38.45888676
OS 53.55096732 -38.46535868
OS 53.54079716 -38.47367972
OS 53.52785332 -38.48292532
OS 53.51306036 -38.49309548
OS 53.49641828 -38.50326564
OS 53.49549372 -38.50326564
OS 53.49456916 -38.5041902
OS 53.4890218 -38.50788844
OS 53.4797762 -38.51251124
OS 53.46868148 -38.5180586
OS 53.45573764 -38.52453052
OS 53.44186924 -38.53100244
OS 53.42800084 -38.53747436
OS 53.41413244 -38.54302172
OS 53.41413244 -38.4672078
OS 53.415057 -38.4672078
OS 53.41690612 -38.46535868
OS 53.42060436 -38.46443412
OS 53.42522716 -38.46166044
OS 53.43077452 -38.45888676
OS 53.43724644 -38.45518852
OS 53.45296396 -38.44594292
OS 53.47145516 -38.43577276
OS 53.48994636 -38.42282892
OS 53.50936212 -38.40803596
OS 53.52877788 -38.39231844
OS 53.52970244 -38.39139388
OS 53.530627 -38.39046932
OS 53.53340068 -38.38769564
OS 53.53709892 -38.38492196
OS 53.54541996 -38.37567636
OS 53.55651468 -38.36458164
OS 53.5676094 -38.3516378
OS 53.57962868 -38.33684484
OS 53.58979884 -38.32205188
OS 53.59904444 -38.30633436
OS 53.64989524 -38.30633436
OS 53.64989524 -38.94890356
OE
OB 54.07334372 -38.30725892 I
OS 54.0807402 -38.30818348
OS 54.08906124 -38.30910804
OS 54.09830684 -38.3100326
OS 54.10755244 -38.31280628
OS 54.12974188 -38.31835364
OS 54.15193132 -38.32667468
OS 54.16302604 -38.33222204
OS 54.17412076 -38.33869396
OS 54.18429092 -38.347015
OS 54.19446108 -38.35533604
OS 54.19538564 -38.3562606
OS 54.1963102 -38.35718516
OS 54.19908388 -38.35995884
OS 54.20278212 -38.36365708
OS 54.20648036 -38.36920444
OS 54.21110316 -38.3747518
OS 54.22034876 -38.3886202
OS 54.22959436 -38.40618684
OS 54.2379154 -38.42652716
OS 54.24438732 -38.44964116
OS 54.24531188 -38.46166044
OS 54.24623644 -38.47460428
OS 54.24623644 -38.47552884
OS 54.24623644 -38.4764534
OS 54.24623644 -38.48200076
OS 54.24531188 -38.4903218
OS 54.24346276 -38.50049196
OS 54.24068908 -38.5134358
OS 54.23606628 -38.52637964
OS 54.23051892 -38.53932348
OS 54.22219788 -38.55226732
OS 54.22127332 -38.55411644
OS 54.21757508 -38.55781468
OS 54.21202772 -38.56336204
OS 54.20463124 -38.57075852
OS 54.19446108 -38.57907956
OS 54.1824418 -38.5874006
OS 54.1685734 -38.59572164
OS 54.15193132 -38.60311812
OS 54.15285588 -38.60311812
OS 54.154705 -38.60404268
OS 54.15747868 -38.60496724
OS 54.16117692 -38.60681636
OS 54.17227164 -38.61143916
OS 54.18521548 -38.61791108
OS 54.19908388 -38.62715668
OS 54.21387684 -38.63732684
OS 54.22774524 -38.65027068
OS 54.24068908 -38.66506364
OS 54.24068908 -38.6659882
OS 54.24161364 -38.66691276
OS 54.24531188 -38.67246012
OS 54.25085924 -38.68170572
OS 54.2564066 -38.693725
OS 54.26195396 -38.70851796
OS 54.26750132 -38.7260846
OS 54.27119956 -38.74550036
OS 54.27212412 -38.76676524
OS 54.27212412 -38.7676898
OS 54.27212412 -38.77046348
OS 54.27212412 -38.77508628
OS 54.27119956 -38.78063364
OS 54.270275 -38.78710556
OS 54.26935044 -38.7954266
OS 54.26750132 -38.8046722
OS 54.26472764 -38.81484236
OS 54.25825572 -38.83610724
OS 54.25363292 -38.84812652
OS 54.247161 -38.85922124
OS 54.24068908 -38.87124052
OS 54.2332926 -38.88233524
OS 54.224047 -38.89342996
OS 54.21387684 -38.90452468
OS 54.21295228 -38.90544924
OS 54.21110316 -38.90729836
OS 54.20832948 -38.91007204
OS 54.20370668 -38.91284572
OS 54.19723476 -38.91746852
OS 54.19076284 -38.92209132
OS 54.1824418 -38.92671412
OS 54.1731962 -38.93226148
OS 54.16302604 -38.93780884
OS 54.15100676 -38.94243164
OS 54.13806292 -38.94705444
OS 54.12511908 -38.95167724
OS 54.11032612 -38.95445092
OS 54.0946086 -38.9572246
OS 54.07889108 -38.95907372
OS 54.06132444 -38.95999828
OS 54.05207884 -38.95999828
OS 54.04560692 -38.95907372
OS 54.03728588 -38.95814916
OS 54.02804028 -38.9572246
OS 54.01787012 -38.95537548
OS 54.0067754 -38.9526018
OS 53.98181228 -38.94612988
OS 53.96886844 -38.94150708
OS 53.95684916 -38.93688428
OS 53.94390532 -38.93041236
OS 53.93096148 -38.92301588
OS 53.9189422 -38.91469484
OS 53.90784748 -38.90452468
OS 53.90692292 -38.90360012
OS 53.9050738 -38.901751
OS 53.90230012 -38.89897732
OS 53.89860188 -38.89435452
OS 53.89490364 -38.88880716
OS 53.88935628 -38.88233524
OS 53.88473348 -38.87493876
OS 53.87918612 -38.86569316
OS 53.87363876 -38.85644756
OS 53.86901596 -38.84535284
OS 53.85977036 -38.82223884
OS 53.85607212 -38.80837044
OS 53.85329844 -38.79450204
OS 53.85144932 -38.77970908
OS 53.85052476 -38.76491612
OS 53.85052476 -38.76399156
OS 53.85052476 -38.76214244
OS 53.85052476 -38.7584442
OS 53.85144932 -38.75474596
OS 53.85144932 -38.7491986
OS 53.85237388 -38.74272668
OS 53.854223 -38.72793372
OS 53.85792124 -38.71129164
OS 53.8634686 -38.69464956
OS 53.87178964 -38.67708292
OS 53.8819598 -38.66044084
OS 53.8819598 -38.65951628
OS 53.88380892 -38.65859172
OS 53.88750716 -38.65396892
OS 53.89490364 -38.64657244
OS 53.9050738 -38.63732684
OS 53.91801764 -38.62808124
OS 53.93373516 -38.61791108
OS 53.9513018 -38.60959004
OS 53.97256668 -38.60311812
OS 53.97164212 -38.60311812
OS 53.97071756 -38.60219356
OS 53.96794388 -38.601269
OS 53.96424564 -38.59941988
OS 53.9559246 -38.59572164
OS 53.94482988 -38.59017428
OS 53.9328106 -38.5827778
OS 53.92079132 -38.5735322
OS 53.9096966 -38.56336204
OS 53.89952644 -38.55226732
OS 53.89860188 -38.5504182
OS 53.8958282 -38.54671996
OS 53.89212996 -38.53932348
OS 53.88843172 -38.53007788
OS 53.88380892 -38.5180586
OS 53.88011068 -38.5041902
OS 53.877337 -38.48847268
OS 53.87641244 -38.4718306
OS 53.87641244 -38.47090604
OS 53.87641244 -38.46905692
OS 53.87641244 -38.46535868
OS 53.877337 -38.45981132
OS 53.87826156 -38.45426396
OS 53.87918612 -38.44686748
OS 53.88288436 -38.43114996
OS 53.88843172 -38.41265876
OS 53.89767732 -38.393243
OS 53.90322468 -38.38307284
OS 53.9096966 -38.37290268
OS 53.91801764 -38.36365708
OS 53.92633868 -38.35441148
OS 53.92726324 -38.35348692
OS 53.92911236 -38.35256236
OS 53.93188604 -38.34978868
OS 53.93558428 -38.347015
OS 53.94020708 -38.34331676
OS 53.946679 -38.33961852
OS 53.95407548 -38.33499572
OS 53.96147196 -38.33037292
OS 53.97071756 -38.32575012
OS 53.98088772 -38.32112732
OS 53.99198244 -38.31742908
OS 54.00400172 -38.31373084
OS 54.0298894 -38.30818348
OS 54.04468236 -38.30725892
OS 54.05947532 -38.30633436
OS 54.06779636 -38.30633436
OS 54.07334372 -38.30725892
OE
OB 53.23846604 -38.94890356 I
OS 53.14878372 -38.94890356
OS 53.14878372 -38.85922124
OS 53.23846604 -38.85922124
OS 53.23846604 -38.94890356
OE
OB 53.00177868 -38.39231844 I
OS 52.74567556 -38.39231844
OS 52.71146684 -38.56521116
OS 52.7123914 -38.5642866
OS 52.71424052 -38.56336204
OS 52.7170142 -38.56151292
OS 52.721637 -38.55873924
OS 52.72718436 -38.55596556
OS 52.73365628 -38.55226732
OS 52.74844924 -38.54487084
OS 52.76694044 -38.53747436
OS 52.78728076 -38.53100244
OS 52.8094702 -38.52637964
OS 52.82056492 -38.52453052
OS 52.84090524 -38.52453052
OS 52.8464526 -38.52545508
OS 52.85384908 -38.52637964
OS 52.86217012 -38.5273042
OS 52.87141572 -38.52915332
OS 52.88158588 -38.531927
OS 52.90377532 -38.53839892
OS 52.9157946 -38.54302172
OS 52.92781388 -38.54949364
OS 52.93983316 -38.55596556
OS 52.95185244 -38.56336204
OS 52.96294716 -38.57260764
OS 52.97404188 -38.5827778
OS 52.97496644 -38.58370236
OS 52.97681556 -38.58555148
OS 52.97958924 -38.58832516
OS 52.98328748 -38.59294796
OS 52.98791028 -38.59941988
OS 52.99253308 -38.6058918
OS 52.99808044 -38.61421284
OS 53.0036278 -38.62345844
OS 53.0082506 -38.6336286
OS 53.01379796 -38.64472332
OS 53.01842076 -38.65766716
OS 53.02304356 -38.670611
OS 53.0267418 -38.6844794
OS 53.02951548 -38.70019692
OS 53.0313646 -38.71591444
OS 53.03228916 -38.73255652
OS 53.03228916 -38.73348108
OS 53.03228916 -38.73625476
OS 53.03228916 -38.74087756
OS 53.0313646 -38.74734948
OS 53.03044004 -38.75474596
OS 53.02951548 -38.763067
OS 53.02766636 -38.77323716
OS 53.02581724 -38.78340732
OS 53.02026988 -38.80744588
OS 53.01102428 -38.832409
OS 53.00547692 -38.84535284
OS 52.99808044 -38.85737212
OS 52.99068396 -38.87031596
OS 52.98143836 -38.88233524
OS 52.9805138 -38.8832598
OS 52.97866468 -38.88603348
OS 52.97496644 -38.88973172
OS 52.97034364 -38.89435452
OS 52.96387172 -38.89990188
OS 52.95647524 -38.90729836
OS 52.94722964 -38.91377028
OS 52.93705948 -38.92116676
OS 52.92596476 -38.92856324
OS 52.91302092 -38.93503516
OS 52.89915252 -38.94150708
OS 52.88435956 -38.947979
OS 52.86864204 -38.9526018
OS 52.8510754 -38.95630004
OS 52.8325842 -38.95907372
OS 52.81316844 -38.95999828
OS 52.8048474 -38.95999828
OS 52.79837548 -38.95907372
OS 52.790979 -38.95814916
OS 52.78265796 -38.9572246
OS 52.7724878 -38.95630004
OS 52.76231764 -38.95352636
OS 52.73920364 -38.947979
OS 52.71608964 -38.93965796
OS 52.70407036 -38.9341106
OS 52.69205108 -38.92763868
OS 52.68095636 -38.9202422
OS 52.66986164 -38.91192116
OS 52.66893708 -38.9109966
OS 52.66708796 -38.91007204
OS 52.66523884 -38.9063738
OS 52.6615406 -38.90267556
OS 52.6569178 -38.89805276
OS 52.652295 -38.8925054
OS 52.64674764 -38.88510892
OS 52.64212484 -38.87678788
OS 52.63657748 -38.86846684
OS 52.63103012 -38.85829668
OS 52.62085996 -38.83610724
OS 52.61253892 -38.81021956
OS 52.60976524 -38.79635116
OS 52.60791612 -38.7815582
OS 52.69020196 -38.77508628
OS 52.69020196 -38.77601084
OS 52.69020196 -38.77785996
OS 52.69112652 -38.78063364
OS 52.69205108 -38.78525644
OS 52.69482476 -38.7954266
OS 52.698523 -38.809295
OS 52.70407036 -38.8231634
OS 52.71146684 -38.83888092
OS 52.72071244 -38.85274932
OS 52.73180716 -38.86569316
OS 52.73365628 -38.86661772
OS 52.73735452 -38.87031596
OS 52.744751 -38.87493876
OS 52.75492116 -38.88048612
OS 52.76601588 -38.88603348
OS 52.77988428 -38.89065628
OS 52.7956018 -38.89435452
OS 52.81316844 -38.89527908
OS 52.8187158 -38.89527908
OS 52.82241404 -38.89435452
OS 52.83350876 -38.89342996
OS 52.8464526 -38.88973172
OS 52.86217012 -38.88510892
OS 52.87788764 -38.87771244
OS 52.89452972 -38.86661772
OS 52.9019262 -38.8601458
OS 52.90932268 -38.85274932
OS 52.91024724 -38.85182476
OS 52.9111718 -38.8509002
OS 52.91302092 -38.84812652
OS 52.9157946 -38.84535284
OS 52.92226652 -38.83518268
OS 52.929663 -38.82223884
OS 52.93613492 -38.80652132
OS 52.94260684 -38.78710556
OS 52.94722964 -38.76399156
OS 52.94907876 -38.75197228
OS 52.94907876 -38.73902844
OS 52.94907876 -38.73810388
OS 52.94907876 -38.73625476
OS 52.94907876 -38.73255652
OS 52.9481542 -38.72793372
OS 52.9481542 -38.72238636
OS 52.94722964 -38.71591444
OS 52.94445596 -38.70112148
OS 52.93983316 -38.68355484
OS 52.93336124 -38.6659882
OS 52.92411564 -38.64934612
OS 52.9111718 -38.6336286
OS 52.9111718 -38.63270404
OS 52.90932268 -38.63177948
OS 52.90469988 -38.62715668
OS 52.89637884 -38.62068476
OS 52.88528412 -38.61328828
OS 52.87049116 -38.60681636
OS 52.85384908 -38.60034444
OS 52.83443332 -38.59572164
OS 52.8233386 -38.59387252
OS 52.80577196 -38.59387252
OS 52.79837548 -38.59479708
OS 52.78912988 -38.59572164
OS 52.77803516 -38.59849532
OS 52.76694044 -38.601269
OS 52.75492116 -38.6058918
OS 52.74290188 -38.61143916
OS 52.74197732 -38.61236372
OS 52.73827908 -38.61421284
OS 52.73273172 -38.61883564
OS 52.72533524 -38.62345844
OS 52.71793876 -38.62993036
OS 52.71054228 -38.6382514
OS 52.70222124 -38.64657244
OS 52.69574932 -38.6567426
OS 52.62178452 -38.64657244
OS 52.68373004 -38.31742908
OS 53.00177868 -38.31742908
OS 53.00177868 -38.39231844
OE
OB 53.23846604 -38.57445676 I
OS 53.14878372 -38.57445676
OS 53.14878372 -38.48477444
OS 53.23846604 -38.48477444
OS 53.23846604 -38.57445676
OE
OB 54.48199924 -38.57445676 I
OS 54.39231692 -38.57445676
OS 54.39231692 -38.48477444
OS 54.48199924 -38.48477444
OS 54.48199924 -38.57445676
OE
OB 56.14990548 -38.3100326 I
OS 56.165623 -38.31095716
OS 56.18226508 -38.31188172
OS 56.1979826 -38.31373084
OS 56.211851 -38.31557996
OS 56.21370012 -38.31557996
OS 56.22017204 -38.31742908
OS 56.22849308 -38.3192782
OS 56.2395878 -38.32205188
OS 56.25160708 -38.32667468
OS 56.26455092 -38.33222204
OS 56.27841932 -38.33869396
OS 56.2904386 -38.34609044
OS 56.29228772 -38.347015
OS 56.29598596 -38.34978868
OS 56.30153332 -38.35533604
OS 56.3089298 -38.36180796
OS 56.31725084 -38.370129
OS 56.32557188 -38.38122372
OS 56.33481748 -38.393243
OS 56.34221396 -38.4071114
OS 56.34313852 -38.40896052
OS 56.34498764 -38.41358332
OS 56.34868588 -38.42190436
OS 56.35238412 -38.43299908
OS 56.3551578 -38.44594292
OS 56.35885604 -38.46073588
OS 56.36070516 -38.47737796
OS 56.36162972 -38.4949446
OS 56.36162972 -38.49586916
OS 56.36162972 -38.49864284
OS 56.36162972 -38.50234108
OS 56.36070516 -38.508813
OS 56.3597806 -38.51528492
OS 56.35885604 -38.52360596
OS 56.35700692 -38.53285156
OS 56.3551578 -38.54302172
OS 56.34868588 -38.5642866
OS 56.34498764 -38.57538132
OS 56.33944028 -38.5874006
OS 56.33296836 -38.59941988
OS 56.32649644 -38.6105146
OS 56.3181754 -38.62160932
OS 56.3089298 -38.63270404
OS 56.30800524 -38.6336286
OS 56.30615612 -38.63547772
OS 56.30338244 -38.6382514
OS 56.29875964 -38.64102508
OS 56.29321228 -38.64564788
OS 56.2858158 -38.65027068
OS 56.2765702 -38.65581804
OS 56.26640004 -38.66044084
OS 56.25438076 -38.6659882
OS 56.24051236 -38.67153556
OS 56.2257194 -38.67615836
OS 56.20815276 -38.6798566
OS 56.18966156 -38.68355484
OS 56.16932124 -38.68632852
OS 56.14620724 -38.68817764
OS 56.12216868 -38.6891022
OS 55.95852156 -38.6891022
OS 55.95852156 -38.94890356
OS 55.87346204 -38.94890356
OS 55.87346204 -38.30910804
OS 56.13603708 -38.30910804
OS 56.14990548 -38.3100326
OE
OB 57.07723916 -38.94890356 I
OS 56.99587788 -38.94890356
OS 56.99587788 -38.41358332
OS 56.80911676 -38.94890356
OS 56.73330284 -38.94890356
OS 56.54839084 -38.40433772
OS 56.54839084 -38.94890356
OS 56.46702956 -38.94890356
OS 56.46702956 -38.30910804
OS 56.59369428 -38.30910804
OS 56.74532212 -38.763067
OS 56.74532212 -38.76399156
OS 56.74624668 -38.76584068
OS 56.74717124 -38.76861436
OS 56.74902036 -38.77323716
OS 56.7527186 -38.78433188
OS 56.7573414 -38.79820028
OS 56.7619642 -38.8139178
OS 56.76751156 -38.82963532
OS 56.77213436 -38.84442828
OS 56.7758326 -38.85737212
OS 56.77675716 -38.855523
OS 56.77768172 -38.8509002
OS 56.7804554 -38.84257916
OS 56.78415364 -38.83148444
OS 56.78877644 -38.81669148
OS 56.79524836 -38.79912484
OS 56.80172028 -38.77878452
OS 56.81004132 -38.75474596
OS 56.96351828 -38.30910804
OS 57.07723916 -38.30910804
OS 57.07723916 -38.94890356
OE
OB 55.39084172 -38.94890356 I
OS 55.31225412 -38.94890356
OS 55.31225412 -38.4487166
OS 55.31132956 -38.44964116
OS 55.30670676 -38.4533394
OS 55.3011594 -38.45888676
OS 55.2919138 -38.46535868
OS 55.28174364 -38.47367972
OS 55.2687998 -38.48292532
OS 55.25400684 -38.49309548
OS 55.23736476 -38.50326564
OS 55.2364402 -38.50326564
OS 55.23551564 -38.5041902
OS 55.22996828 -38.50788844
OS 55.22072268 -38.51251124
OS 55.20962796 -38.5180586
OS 55.19668412 -38.52453052
OS 55.18281572 -38.53100244
OS 55.16894732 -38.53747436
OS 55.15507892 -38.54302172
OS 55.15507892 -38.4672078
OS 55.15600348 -38.4672078
OS 55.1578526 -38.46535868
OS 55.16155084 -38.46443412
OS 55.16617364 -38.46166044
OS 55.171721 -38.45888676
OS 55.17819292 -38.45518852
OS 55.19391044 -38.44594292
OS 55.21240164 -38.43577276
OS 55.23089284 -38.42282892
OS 55.2503086 -38.40803596
OS 55.26972436 -38.39231844
OS 55.27064892 -38.39139388
OS 55.27157348 -38.39046932
OS 55.27434716 -38.38769564
OS 55.2780454 -38.38492196
OS 55.28636644 -38.37567636
OS 55.29746116 -38.36458164
OS 55.30855588 -38.3516378
OS 55.32057516 -38.33684484
OS 55.33074532 -38.32205188
OS 55.33999092 -38.30633436
OS 55.39084172 -38.30633436
OS 55.39084172 -38.94890356
OE
OB 54.48199924 -38.94890356 I
OS 54.39231692 -38.94890356
OS 54.39231692 -38.85922124
OS 54.48199924 -38.85922124
OS 54.48199924 -38.94890356
OE
OB 54.825011 -38.30725892 I
OS 54.83703028 -38.30910804
OS 54.85089868 -38.31188172
OS 54.86569164 -38.31557996
OS 54.88140916 -38.32020276
OS 54.89620212 -38.32759924
OS 54.89712668 -38.32759924
OS 54.89805124 -38.3285238
OS 54.90267404 -38.33129748
OS 54.91007052 -38.33592028
OS 54.91931612 -38.3423922
OS 54.92948628 -38.3516378
OS 54.940581 -38.36180796
OS 54.95075116 -38.37382724
OS 54.96092132 -38.38769564
OS 54.96184588 -38.38954476
OS 54.96554412 -38.39416756
OS 54.96924236 -38.4024886
OS 54.97571428 -38.41450788
OS 54.98126164 -38.42837628
OS 54.98865812 -38.4440938
OS 54.99513004 -38.462585
OS 55.0006774 -38.48292532
OS 55.0006774 -38.48384988
OS 55.00160196 -38.485699
OS 55.00252652 -38.48847268
OS 55.00345108 -38.49309548
OS 55.00437564 -38.49864284
OS 55.0053002 -38.50511476
OS 55.00714932 -38.5134358
OS 55.00807388 -38.5226814
OS 55.009923 -38.53285156
OS 55.01084756 -38.54394628
OS 55.01177212 -38.55689012
OS 55.01362124 -38.56983396
OS 55.0145458 -38.58462692
OS 55.0145458 -38.59941988
OS 55.01547036 -38.61606196
OS 55.01547036 -38.6336286
OS 55.01547036 -38.63455316
OS 55.01547036 -38.6382514
OS 55.01547036 -38.64472332
OS 55.01547036 -38.6521198
OS 55.0145458 -38.66228996
OS 55.0145458 -38.67338468
OS 55.01362124 -38.68540396
OS 55.01269668 -38.6983478
OS 55.009923 -38.72793372
OS 55.0053002 -38.7584442
OS 54.99975284 -38.78803012
OS 54.9960546 -38.80189852
OS 54.9914318 -38.81576692
OS 54.9914318 -38.81669148
OS 54.99050724 -38.8185406
OS 54.98865812 -38.82223884
OS 54.986809 -38.82686164
OS 54.98495988 -38.83333356
OS 54.98126164 -38.83980548
OS 54.97386516 -38.855523
OS 54.96461956 -38.87216508
OS 54.95260028 -38.89065628
OS 54.93873188 -38.90729836
OS 54.9220898 -38.92301588
OS 54.92116524 -38.92301588
OS 54.92024068 -38.924865
OS 54.917467 -38.92671412
OS 54.91376876 -38.92856324
OS 54.90914596 -38.93133692
OS 54.90452316 -38.93503516
OS 54.89065476 -38.94150708
OS 54.87401268 -38.947979
OS 54.85459692 -38.95445092
OS 54.83148292 -38.95814916
OS 54.8065198 -38.95999828
OS 54.7972742 -38.95999828
OS 54.79080228 -38.95907372
OS 54.7834058 -38.95814916
OS 54.7741602 -38.95630004
OS 54.76399004 -38.95445092
OS 54.75289532 -38.95167724
OS 54.7418006 -38.947979
OS 54.72978132 -38.94428076
OS 54.71776204 -38.9387334
OS 54.70574276 -38.93226148
OS 54.69372348 -38.924865
OS 54.6817042 -38.9156194
OS 54.67060948 -38.90544924
OS 54.66043932 -38.89435452
OS 54.65951476 -38.89342996
OS 54.65766564 -38.89065628
OS 54.65489196 -38.88603348
OS 54.65026916 -38.878637
OS 54.64564636 -38.87031596
OS 54.64102356 -38.85922124
OS 54.63455164 -38.8462774
OS 54.62900428 -38.83148444
OS 54.62345692 -38.81484236
OS 54.61790956 -38.7954266
OS 54.6123622 -38.77416172
OS 54.6077394 -38.75012316
OS 54.6031166 -38.72423548
OS 54.60034292 -38.69649868
OS 54.5984938 -38.6659882
OS 54.59756924 -38.6336286
OS 54.59756924 -38.63270404
OS 54.59756924 -38.6290058
OS 54.59756924 -38.62253388
OS 54.59756924 -38.6151374
OS 54.5984938 -38.60496724
OS 54.5984938 -38.59387252
OS 54.59941836 -38.58185324
OS 54.60034292 -38.56798484
OS 54.6031166 -38.53932348
OS 54.6077394 -38.508813
OS 54.61328676 -38.47830252
OS 54.616985 -38.46443412
OS 54.62068324 -38.45056572
OS 54.62068324 -38.44964116
OS 54.6216078 -38.44779204
OS 54.62345692 -38.4440938
OS 54.62530604 -38.439471
OS 54.62715516 -38.43299908
OS 54.6308534 -38.42652716
OS 54.63824988 -38.41080964
OS 54.64749548 -38.39416756
OS 54.65951476 -38.37660092
OS 54.67338316 -38.35903428
OS 54.69002524 -38.34424132
OS 54.6909498 -38.34424132
OS 54.69187436 -38.3423922
OS 54.69464804 -38.34054308
OS 54.69834628 -38.33869396
OS 54.70296908 -38.33499572
OS 54.70851644 -38.33222204
OS 54.72238484 -38.32482556
OS 54.73902692 -38.31835364
OS 54.75844268 -38.31188172
OS 54.78155668 -38.30818348
OS 54.8065198 -38.30633436
OS 54.81484084 -38.30633436
OS 54.825011 -38.30725892
OE
OB 49.95350436 -38.72331092 I
OS 50.040413 -38.72331092
OS 50.040413 -38.7954266
OS 49.95350436 -38.7954266
OS 49.95350436 -38.94890356
OS 49.87491676 -38.94890356
OS 49.87491676 -38.7954266
OS 49.5966242 -38.7954266
OS 49.5966242 -38.72331092
OS 49.88970972 -38.30910804
OS 49.95350436 -38.30910804
OS 49.95350436 -38.72331092
OE
OB 50.1467374 -38.95999828 I
OS 50.08386732 -38.95999828
OS 50.26970388 -38.29801332
OS 50.33257396 -38.29801332
OS 50.1467374 -38.95999828
OE
OB 50.59699812 -38.30725892 I
OS 50.6043946 -38.30818348
OS 50.6136402 -38.30910804
OS 50.62381036 -38.31095716
OS 50.63398052 -38.31280628
OS 50.65801908 -38.3192782
OS 50.68205764 -38.3285238
OS 50.69407692 -38.33407116
OS 50.7060962 -38.34054308
OS 50.71719092 -38.34886412
OS 50.72736108 -38.35810972
OS 50.72828564 -38.35903428
OS 50.73013476 -38.35995884
OS 50.73198388 -38.36365708
OS 50.73568212 -38.36735532
OS 50.74030492 -38.37197812
OS 50.74492772 -38.37845004
OS 50.74955052 -38.38492196
OS 50.75509788 -38.393243
OS 50.76434348 -38.41080964
OS 50.77358908 -38.43299908
OS 50.77728732 -38.4440938
OS 50.77913644 -38.45703764
OS 50.78098556 -38.46998148
OS 50.78191012 -38.48384988
OS 50.78191012 -38.485699
OS 50.78191012 -38.4903218
OS 50.78098556 -38.49771828
OS 50.780061 -38.50788844
OS 50.77821188 -38.51898316
OS 50.77451364 -38.531927
OS 50.7708154 -38.5457954
OS 50.76526804 -38.5596638
OS 50.76434348 -38.56151292
OS 50.76249436 -38.56613572
OS 50.75879612 -38.5735322
OS 50.75324876 -38.58370236
OS 50.74585228 -38.59479708
OS 50.73660668 -38.60866548
OS 50.72551196 -38.62253388
OS 50.71256812 -38.6382514
OS 50.710719 -38.64010052
OS 50.7060962 -38.64564788
OS 50.7014734 -38.65027068
OS 50.6968506 -38.65489348
OS 50.69130324 -38.66044084
OS 50.68390676 -38.66783732
OS 50.67651028 -38.6752338
OS 50.66726468 -38.68355484
OS 50.65801908 -38.69280044
OS 50.64692436 -38.7029706
OS 50.63490508 -38.71314076
OS 50.62196124 -38.72516004
OS 50.60716828 -38.73717932
OS 50.59237532 -38.75012316
OS 50.59145076 -38.75104772
OS 50.58960164 -38.75289684
OS 50.5859034 -38.75567052
OS 50.5812806 -38.75936876
OS 50.57573324 -38.76491612
OS 50.56926132 -38.77046348
OS 50.55446836 -38.78248276
OS 50.53875084 -38.79635116
OS 50.52395788 -38.81021956
OS 50.51101404 -38.82223884
OS 50.50546668 -38.82686164
OS 50.50084388 -38.83148444
OS 50.49991932 -38.832409
OS 50.49714564 -38.83518268
OS 50.4934474 -38.83888092
OS 50.4888246 -38.84442828
OS 50.4842018 -38.8509002
OS 50.47865444 -38.85737212
OS 50.46755972 -38.87308964
OS 50.78283468 -38.87308964
OS 50.78283468 -38.94890356
OS 50.35846164 -38.94890356
OS 50.35846164 -38.947979
OS 50.35846164 -38.94428076
OS 50.35846164 -38.9387334
OS 50.3593862 -38.93133692
OS 50.36031076 -38.92301588
OS 50.36215988 -38.91377028
OS 50.364009 -38.90452468
OS 50.36770724 -38.89435452
OS 50.36770724 -38.89342996
OS 50.3686318 -38.8925054
OS 50.37048092 -38.88695804
OS 50.37417916 -38.878637
OS 50.37972652 -38.86754228
OS 50.387123 -38.85459844
OS 50.3963686 -38.83980548
OS 50.40653876 -38.82501252
OS 50.4194826 -38.809295
OS 50.4194826 -38.80837044
OS 50.42133172 -38.80744588
OS 50.42595452 -38.80189852
OS 50.43427556 -38.79357748
OS 50.44629484 -38.7815582
OS 50.46016324 -38.7676898
OS 50.47772988 -38.75104772
OS 50.49899476 -38.73255652
OS 50.52210876 -38.71314076
OS 50.52303332 -38.7122162
OS 50.52673156 -38.70944252
OS 50.53227892 -38.70481972
OS 50.53875084 -38.69927236
OS 50.54707188 -38.69187588
OS 50.55724204 -38.68355484
OS 50.5674122 -38.67430924
OS 50.57943148 -38.66413908
OS 50.60254548 -38.64194964
OS 50.62565948 -38.6197602
OS 50.6367542 -38.60866548
OS 50.64692436 -38.59757076
OS 50.65616996 -38.5874006
OS 50.66356644 -38.57723044
OS 50.66356644 -38.57630588
OS 50.66541556 -38.57538132
OS 50.66726468 -38.57260764
OS 50.6691138 -38.5689094
OS 50.67558572 -38.55873924
OS 50.6829822 -38.54671996
OS 50.68945412 -38.531927
OS 50.69592604 -38.51620948
OS 50.69962428 -38.49864284
OS 50.7014734 -38.48200076
OS 50.7014734 -38.4810762
OS 50.7014734 -38.48015164
OS 50.70054884 -38.47460428
OS 50.69962428 -38.46535868
OS 50.6968506 -38.45518852
OS 50.69315236 -38.44224468
OS 50.68668044 -38.42930084
OS 50.6783594 -38.416357
OS 50.66726468 -38.40341316
OS 50.66541556 -38.40156404
OS 50.66079276 -38.3978658
OS 50.65432084 -38.393243
OS 50.64415068 -38.38677108
OS 50.63120684 -38.38122372
OS 50.61641388 -38.37567636
OS 50.59884724 -38.37197812
OS 50.57943148 -38.37105356
OS 50.57388412 -38.37105356
OS 50.57018588 -38.37197812
OS 50.55909116 -38.37290268
OS 50.54614732 -38.37567636
OS 50.53227892 -38.3793746
OS 50.5165614 -38.38584652
OS 50.50176844 -38.39416756
OS 50.48790004 -38.40526228
OS 50.48605092 -38.4071114
OS 50.48235268 -38.4117342
OS 50.47680532 -38.41913068
OS 50.47125796 -38.4302254
OS 50.46478604 -38.44316924
OS 50.45923868 -38.45981132
OS 50.45554044 -38.47830252
OS 50.45369132 -38.4995674
OS 50.3732546 -38.49124636
OS 50.3732546 -38.4903218
OS 50.37417916 -38.48754812
OS 50.37417916 -38.48292532
OS 50.37510372 -38.4764534
OS 50.37695284 -38.46905692
OS 50.37880196 -38.46073588
OS 50.38157564 -38.45056572
OS 50.38434932 -38.44039556
OS 50.3917458 -38.41820612
OS 50.40284052 -38.39601668
OS 50.40931244 -38.38492196
OS 50.41763348 -38.37382724
OS 50.42595452 -38.36365708
OS 50.43520012 -38.35441148
OS 50.43612468 -38.35348692
OS 50.4379738 -38.35256236
OS 50.44074748 -38.34978868
OS 50.44537028 -38.347015
OS 50.45091764 -38.34331676
OS 50.45738956 -38.33961852
OS 50.46478604 -38.33499572
OS 50.47403164 -38.33037292
OS 50.4842018 -38.32575012
OS 50.49529652 -38.32112732
OS 50.5073158 -38.31742908
OS 50.52025964 -38.31373084
OS 50.53412804 -38.31095716
OS 50.548921 -38.30818348
OS 50.56463852 -38.30725892
OS 50.5812806 -38.30633436
OS 50.5905262 -38.30633436
OS 50.59699812 -38.30725892
OE
OB 48.67576244 -38.94890356 I
OS 48.59717484 -38.94890356
OS 48.59717484 -38.4487166
OS 48.59625028 -38.44964116
OS 48.59162748 -38.4533394
OS 48.58608012 -38.45888676
OS 48.57683452 -38.46535868
OS 48.56666436 -38.47367972
OS 48.55372052 -38.48292532
OS 48.53892756 -38.49309548
OS 48.52228548 -38.50326564
OS 48.52136092 -38.50326564
OS 48.52043636 -38.5041902
OS 48.514889 -38.50788844
OS 48.5056434 -38.51251124
OS 48.49454868 -38.5180586
OS 48.48160484 -38.52453052
OS 48.46773644 -38.53100244
OS 48.45386804 -38.53747436
OS 48.43999964 -38.54302172
OS 48.43999964 -38.4672078
OS 48.4409242 -38.4672078
OS 48.44277332 -38.46535868
OS 48.44647156 -38.46443412
OS 48.45109436 -38.46166044
OS 48.45664172 -38.45888676
OS 48.46311364 -38.45518852
OS 48.47883116 -38.44594292
OS 48.49732236 -38.43577276
OS 48.51581356 -38.42282892
OS 48.53522932 -38.40803596
OS 48.55464508 -38.39231844
OS 48.55556964 -38.39139388
OS 48.5564942 -38.39046932
OS 48.55926788 -38.38769564
OS 48.56296612 -38.38492196
OS 48.57128716 -38.37567636
OS 48.58238188 -38.36458164
OS 48.5934766 -38.3516378
OS 48.60549588 -38.33684484
OS 48.61566604 -38.32205188
OS 48.62491164 -38.30633436
OS 48.67576244 -38.30633436
OS 48.67576244 -38.94890356
OE
OB 48.9032042 -38.95999828 I
OS 48.84033412 -38.95999828
OS 49.02617068 -38.29801332
OS 49.08904076 -38.29801332
OS 48.9032042 -38.95999828
OE
OB 49.35346492 -38.30725892 I
OS 49.3608614 -38.30818348
OS 49.370107 -38.30910804
OS 49.38027716 -38.31095716
OS 49.39044732 -38.31280628
OS 49.41448588 -38.3192782
OS 49.43852444 -38.3285238
OS 49.45054372 -38.33407116
OS 49.462563 -38.34054308
OS 49.47365772 -38.34886412
OS 49.48382788 -38.35810972
OS 49.48475244 -38.35903428
OS 49.48660156 -38.35995884
OS 49.48845068 -38.36365708
OS 49.49214892 -38.36735532
OS 49.49677172 -38.37197812
OS 49.50139452 -38.37845004
OS 49.50601732 -38.38492196
OS 49.51156468 -38.393243
OS 49.52081028 -38.41080964
OS 49.53005588 -38.43299908
OS 49.53375412 -38.4440938
OS 49.53560324 -38.45703764
OS 49.53745236 -38.46998148
OS 49.53837692 -38.48384988
OS 49.53837692 -38.485699
OS 49.53837692 -38.4903218
OS 49.53745236 -38.49771828
OS 49.5365278 -38.50788844
OS 49.53467868 -38.51898316
OS 49.53098044 -38.531927
OS 49.5272822 -38.5457954
OS 49.52173484 -38.5596638
OS 49.52081028 -38.56151292
OS 49.51896116 -38.56613572
OS 49.51526292 -38.5735322
OS 49.50971556 -38.58370236
OS 49.50231908 -38.59479708
OS 49.49307348 -38.60866548
OS 49.48197876 -38.62253388
OS 49.46903492 -38.6382514
OS 49.4671858 -38.64010052
OS 49.462563 -38.64564788
OS 49.4579402 -38.65027068
OS 49.4533174 -38.65489348
OS 49.44777004 -38.66044084
OS 49.44037356 -38.66783732
OS 49.43297708 -38.6752338
OS 49.42373148 -38.68355484
OS 49.41448588 -38.69280044
OS 49.40339116 -38.7029706
OS 49.39137188 -38.71314076
OS 49.37842804 -38.72516004
OS 49.36363508 -38.73717932
OS 49.34884212 -38.75012316
OS 49.34791756 -38.75104772
OS 49.34606844 -38.75289684
OS 49.3423702 -38.75567052
OS 49.3377474 -38.75936876
OS 49.33220004 -38.76491612
OS 49.32572812 -38.77046348
OS 49.31093516 -38.78248276
OS 49.29521764 -38.79635116
OS 49.28042468 -38.81021956
OS 49.26748084 -38.82223884
OS 49.26193348 -38.82686164
OS 49.25731068 -38.83148444
OS 49.25638612 -38.832409
OS 49.25361244 -38.83518268
OS 49.2499142 -38.83888092
OS 49.2452914 -38.84442828
OS 49.2406686 -38.8509002
OS 49.23512124 -38.85737212
OS 49.22402652 -38.87308964
OS 49.53930148 -38.87308964
OS 49.53930148 -38.94890356
OS 49.11492844 -38.94890356
OS 49.11492844 -38.947979
OS 49.11492844 -38.94428076
OS 49.11492844 -38.9387334
OS 49.115853 -38.93133692
OS 49.11677756 -38.92301588
OS 49.11862668 -38.91377028
OS 49.1204758 -38.90452468
OS 49.12417404 -38.89435452
OS 49.12417404 -38.89342996
OS 49.1250986 -38.8925054
OS 49.12694772 -38.88695804
OS 49.13064596 -38.878637
OS 49.13619332 -38.86754228
OS 49.1435898 -38.85459844
OS 49.1528354 -38.83980548
OS 49.16300556 -38.82501252
OS 49.1759494 -38.809295
OS 49.1759494 -38.80837044
OS 49.17779852 -38.80744588
OS 49.18242132 -38.80189852
OS 49.19074236 -38.79357748
OS 49.20276164 -38.7815582
OS 49.21663004 -38.7676898
OS 49.23419668 -38.75104772
OS 49.25546156 -38.73255652
OS 49.27857556 -38.71314076
OS 49.27950012 -38.7122162
OS 49.28319836 -38.70944252
OS 49.28874572 -38.70481972
OS 49.29521764 -38.69927236
OS 49.30353868 -38.69187588
OS 49.31370884 -38.68355484
OS 49.323879 -38.67430924
OS 49.33589828 -38.66413908
OS 49.35901228 -38.64194964
OS 49.38212628 -38.6197602
OS 49.393221 -38.60866548
OS 49.40339116 -38.59757076
OS 49.41263676 -38.5874006
OS 49.42003324 -38.57723044
OS 49.42003324 -38.57630588
OS 49.42188236 -38.57538132
OS 49.42373148 -38.57260764
OS 49.4255806 -38.5689094
OS 49.43205252 -38.55873924
OS 49.439449 -38.54671996
OS 49.44592092 -38.531927
OS 49.45239284 -38.51620948
OS 49.45609108 -38.49864284
OS 49.4579402 -38.48200076
OS 49.4579402 -38.4810762
OS 49.4579402 -38.48015164
OS 49.45701564 -38.47460428
OS 49.45609108 -38.46535868
OS 49.4533174 -38.45518852
OS 49.44961916 -38.44224468
OS 49.44314724 -38.42930084
OS 49.4348262 -38.416357
OS 49.42373148 -38.40341316
OS 49.42188236 -38.40156404
OS 49.41725956 -38.3978658
OS 49.41078764 -38.393243
OS 49.40061748 -38.38677108
OS 49.38767364 -38.38122372
OS 49.37288068 -38.37567636
OS 49.35531404 -38.37197812
OS 49.33589828 -38.37105356
OS 49.33035092 -38.37105356
OS 49.32665268 -38.37197812
OS 49.31555796 -38.37290268
OS 49.30261412 -38.37567636
OS 49.28874572 -38.3793746
OS 49.2730282 -38.38584652
OS 49.25823524 -38.39416756
OS 49.24436684 -38.40526228
OS 49.24251772 -38.4071114
OS 49.23881948 -38.4117342
OS 49.23327212 -38.41913068
OS 49.22772476 -38.4302254
OS 49.22125284 -38.44316924
OS 49.21570548 -38.45981132
OS 49.21200724 -38.47830252
OS 49.21015812 -38.4995674
OS 49.1297214 -38.49124636
OS 49.1297214 -38.4903218
OS 49.13064596 -38.48754812
OS 49.13064596 -38.48292532
OS 49.13157052 -38.4764534
OS 49.13341964 -38.46905692
OS 49.13526876 -38.46073588
OS 49.13804244 -38.45056572
OS 49.14081612 -38.44039556
OS 49.1482126 -38.41820612
OS 49.15930732 -38.39601668
OS 49.16577924 -38.38492196
OS 49.17410028 -38.37382724
OS 49.18242132 -38.36365708
OS 49.19166692 -38.35441148
OS 49.19259148 -38.35348692
OS 49.1944406 -38.35256236
OS 49.19721428 -38.34978868
OS 49.20183708 -38.347015
OS 49.20738444 -38.34331676
OS 49.21385636 -38.33961852
OS 49.22125284 -38.33499572
OS 49.23049844 -38.33037292
OS 49.2406686 -38.32575012
OS 49.25176332 -38.32112732
OS 49.2637826 -38.31742908
OS 49.27672644 -38.31373084
OS 49.29059484 -38.31095716
OS 49.3053878 -38.30818348
OS 49.32110532 -38.30725892
OS 49.3377474 -38.30633436
OS 49.346993 -38.30633436
OS 49.35346492 -38.30725892
OE
OB 51.0944114 -38.30725892 I
OS 51.10643068 -38.30910804
OS 51.12029908 -38.31188172
OS 51.13509204 -38.31557996
OS 51.15080956 -38.32020276
OS 51.16560252 -38.32759924
OS 51.16652708 -38.32759924
OS 51.16745164 -38.3285238
OS 51.17207444 -38.33129748
OS 51.17947092 -38.33592028
OS 51.18871652 -38.3423922
OS 51.19888668 -38.3516378
OS 51.2099814 -38.36180796
OS 51.22015156 -38.37382724
OS 51.23032172 -38.38769564
OS 51.23124628 -38.38954476
OS 51.23494452 -38.39416756
OS 51.23864276 -38.4024886
OS 51.24511468 -38.41450788
OS 51.25066204 -38.42837628
OS 51.25805852 -38.4440938
OS 51.26453044 -38.462585
OS 51.2700778 -38.48292532
OS 51.2700778 -38.48384988
OS 51.27100236 -38.485699
OS 51.27192692 -38.48847268
OS 51.27285148 -38.49309548
OS 51.27377604 -38.49864284
OS 51.2747006 -38.50511476
OS 51.27654972 -38.5134358
OS 51.27747428 -38.5226814
OS 51.2793234 -38.53285156
OS 51.28024796 -38.54394628
OS 51.28117252 -38.55689012
OS 51.28302164 -38.56983396
OS 51.2839462 -38.58462692
OS 51.2839462 -38.59941988
OS 51.28487076 -38.61606196
OS 51.28487076 -38.6336286
OS 51.28487076 -38.63455316
OS 51.28487076 -38.6382514
OS 51.28487076 -38.64472332
OS 51.28487076 -38.6521198
OS 51.2839462 -38.66228996
OS 51.2839462 -38.67338468
OS 51.28302164 -38.68540396
OS 51.28209708 -38.6983478
OS 51.2793234 -38.72793372
OS 51.2747006 -38.7584442
OS 51.26915324 -38.78803012
OS 51.265455 -38.80189852
OS 51.2608322 -38.81576692
OS 51.2608322 -38.81669148
OS 51.25990764 -38.8185406
OS 51.25805852 -38.82223884
OS 51.2562094 -38.82686164
OS 51.25436028 -38.83333356
OS 51.25066204 -38.83980548
OS 51.24326556 -38.855523
OS 51.23401996 -38.87216508
OS 51.22200068 -38.89065628
OS 51.20813228 -38.90729836
OS 51.1914902 -38.92301588
OS 51.19056564 -38.92301588
OS 51.18964108 -38.924865
OS 51.1868674 -38.92671412
OS 51.18316916 -38.92856324
OS 51.17854636 -38.93133692
OS 51.17392356 -38.93503516
OS 51.16005516 -38.94150708
OS 51.14341308 -38.947979
OS 51.12399732 -38.95445092
OS 51.10088332 -38.95814916
OS 51.0759202 -38.95999828
OS 51.0666746 -38.95999828
OS 51.06020268 -38.95907372
OS 51.0528062 -38.95814916
OS 51.0435606 -38.95630004
OS 51.03339044 -38.95445092
OS 51.02229572 -38.95167724
OS 51.011201 -38.947979
OS 50.99918172 -38.94428076
OS 50.98716244 -38.9387334
OS 50.97514316 -38.93226148
OS 50.96312388 -38.924865
OS 50.9511046 -38.9156194
OS 50.94000988 -38.90544924
OS 50.92983972 -38.89435452
OS 50.92891516 -38.89342996
OS 50.92706604 -38.89065628
OS 50.92429236 -38.88603348
OS 50.91966956 -38.878637
OS 50.91504676 -38.87031596
OS 50.91042396 -38.85922124
OS 50.90395204 -38.8462774
OS 50.89840468 -38.83148444
OS 50.89285732 -38.81484236
OS 50.88730996 -38.7954266
OS 50.8817626 -38.77416172
OS 50.8771398 -38.75012316
OS 50.872517 -38.72423548
OS 50.86974332 -38.69649868
OS 50.8678942 -38.6659882
OS 50.86696964 -38.6336286
OS 50.86696964 -38.63270404
OS 50.86696964 -38.6290058
OS 50.86696964 -38.62253388
OS 50.86696964 -38.6151374
OS 50.8678942 -38.60496724
OS 50.8678942 -38.59387252
OS 50.86881876 -38.58185324
OS 50.86974332 -38.56798484
OS 50.872517 -38.53932348
OS 50.8771398 -38.508813
OS 50.88268716 -38.47830252
OS 50.8863854 -38.46443412
OS 50.89008364 -38.45056572
OS 50.89008364 -38.44964116
OS 50.8910082 -38.44779204
OS 50.89285732 -38.4440938
OS 50.89470644 -38.439471
OS 50.89655556 -38.43299908
OS 50.9002538 -38.42652716
OS 50.90765028 -38.41080964
OS 50.91689588 -38.39416756
OS 50.92891516 -38.37660092
OS 50.94278356 -38.35903428
OS 50.95942564 -38.34424132
OS 50.9603502 -38.34424132
OS 50.96127476 -38.3423922
OS 50.96404844 -38.34054308
OS 50.96774668 -38.33869396
OS 50.97236948 -38.33499572
OS 50.97791684 -38.33222204
OS 50.99178524 -38.32482556
OS 51.00842732 -38.31835364
OS 51.02784308 -38.31188172
OS 51.05095708 -38.30818348
OS 51.0759202 -38.30633436
OS 51.08424124 -38.30633436
OS 51.0944114 -38.30725892
OE
OB 51.59182468 -38.30725892 I
OS 51.59922116 -38.30818348
OS 51.60846676 -38.30910804
OS 51.61863692 -38.31095716
OS 51.62880708 -38.31280628
OS 51.65284564 -38.3192782
OS 51.6768842 -38.3285238
OS 51.68890348 -38.33407116
OS 51.70092276 -38.34054308
OS 51.71201748 -38.34886412
OS 51.72218764 -38.35810972
OS 51.7231122 -38.35903428
OS 51.72496132 -38.35995884
OS 51.72681044 -38.36365708
OS 51.73050868 -38.36735532
OS 51.73513148 -38.37197812
OS 51.73975428 -38.37845004
OS 51.74437708 -38.38492196
OS 51.74992444 -38.393243
OS 51.75917004 -38.41080964
OS 51.76841564 -38.43299908
OS 51.77211388 -38.4440938
OS 51.773963 -38.45703764
OS 51.77581212 -38.46998148
OS 51.77673668 -38.48384988
OS 51.77673668 -38.485699
OS 51.77673668 -38.4903218
OS 51.77581212 -38.49771828
OS 51.77488756 -38.50788844
OS 51.77303844 -38.51898316
OS 51.7693402 -38.531927
OS 51.76564196 -38.5457954
OS 51.7600946 -38.5596638
OS 51.75917004 -38.56151292
OS 51.75732092 -38.56613572
OS 51.75362268 -38.5735322
OS 51.74807532 -38.58370236
OS 51.74067884 -38.59479708
OS 51.73143324 -38.60866548
OS 51.72033852 -38.62253388
OS 51.70739468 -38.6382514
OS 51.70554556 -38.64010052
OS 51.70092276 -38.64564788
OS 51.69629996 -38.65027068
OS 51.69167716 -38.65489348
OS 51.6861298 -38.66044084
OS 51.67873332 -38.66783732
OS 51.67133684 -38.6752338
OS 51.66209124 -38.68355484
OS 51.65284564 -38.69280044
OS 51.64175092 -38.7029706
OS 51.62973164 -38.71314076
OS 51.6167878 -38.72516004
OS 51.60199484 -38.73717932
OS 51.58720188 -38.75012316
OS 51.58627732 -38.75104772
OS 51.5844282 -38.75289684
OS 51.58072996 -38.75567052
OS 51.57610716 -38.75936876
OS 51.5705598 -38.76491612
OS 51.56408788 -38.77046348
OS 51.54929492 -38.78248276
OS 51.5335774 -38.79635116
OS 51.51878444 -38.81021956
OS 51.5058406 -38.82223884
OS 51.50029324 -38.82686164
OS 51.49567044 -38.83148444
OS 51.49474588 -38.832409
OS 51.4919722 -38.83518268
OS 51.48827396 -38.83888092
OS 51.48365116 -38.84442828
OS 51.47902836 -38.8509002
OS 51.473481 -38.85737212
OS 51.46238628 -38.87308964
OS 51.77766124 -38.87308964
OS 51.77766124 -38.94890356
OS 51.3532882 -38.94890356
OS 51.3532882 -38.947979
OS 51.3532882 -38.94428076
OS 51.3532882 -38.9387334
OS 51.35421276 -38.93133692
OS 51.35513732 -38.92301588
OS 51.35698644 -38.91377028
OS 51.35883556 -38.90452468
OS 51.3625338 -38.89435452
OS 51.3625338 -38.89342996
OS 51.36345836 -38.8925054
OS 51.36530748 -38.88695804
OS 51.36900572 -38.878637
OS 51.37455308 -38.86754228
OS 51.38194956 -38.85459844
OS 51.39119516 -38.83980548
OS 51.40136532 -38.82501252
OS 51.41430916 -38.809295
OS 51.41430916 -38.80837044
OS 51.41615828 -38.80744588
OS 51.42078108 -38.80189852
OS 51.42910212 -38.79357748
OS 51.4411214 -38.7815582
OS 51.4549898 -38.7676898
OS 51.47255644 -38.75104772
OS 51.49382132 -38.73255652
OS 51.51693532 -38.71314076
OS 51.51785988 -38.7122162
OS 51.52155812 -38.70944252
OS 51.52710548 -38.70481972
OS 51.5335774 -38.69927236
OS 51.54189844 -38.69187588
OS 51.5520686 -38.68355484
OS 51.56223876 -38.67430924
OS 51.57425804 -38.66413908
OS 51.59737204 -38.64194964
OS 51.62048604 -38.6197602
OS 51.63158076 -38.60866548
OS 51.64175092 -38.59757076
OS 51.65099652 -38.5874006
OS 51.658393 -38.57723044
OS 51.658393 -38.57630588
OS 51.66024212 -38.57538132
OS 51.66209124 -38.57260764
OS 51.66394036 -38.5689094
OS 51.67041228 -38.55873924
OS 51.67780876 -38.54671996
OS 51.68428068 -38.531927
OS 51.6907526 -38.51620948
OS 51.69445084 -38.49864284
OS 51.69629996 -38.48200076
OS 51.69629996 -38.4810762
OS 51.69629996 -38.48015164
OS 51.6953754 -38.47460428
OS 51.69445084 -38.46535868
OS 51.69167716 -38.45518852
OS 51.68797892 -38.44224468
OS 51.681507 -38.42930084
OS 51.67318596 -38.416357
OS 51.66209124 -38.40341316
OS 51.66024212 -38.40156404
OS 51.65561932 -38.3978658
OS 51.6491474 -38.393243
OS 51.63897724 -38.38677108
OS 51.6260334 -38.38122372
OS 51.61124044 -38.37567636
OS 51.5936738 -38.37197812
OS 51.57425804 -38.37105356
OS 51.56871068 -38.37105356
OS 51.56501244 -38.37197812
OS 51.55391772 -38.37290268
OS 51.54097388 -38.37567636
OS 51.52710548 -38.3793746
OS 51.51138796 -38.38584652
OS 51.496595 -38.39416756
OS 51.4827266 -38.40526228
OS 51.48087748 -38.4071114
OS 51.47717924 -38.4117342
OS 51.47163188 -38.41913068
OS 51.46608452 -38.4302254
OS 51.4596126 -38.44316924
OS 51.45406524 -38.45981132
OS 51.450367 -38.47830252
OS 51.44851788 -38.4995674
OS 51.36808116 -38.49124636
OS 51.36808116 -38.4903218
OS 51.36900572 -38.48754812
OS 51.36900572 -38.48292532
OS 51.36993028 -38.4764534
OS 51.3717794 -38.46905692
OS 51.37362852 -38.46073588
OS 51.3764022 -38.45056572
OS 51.37917588 -38.44039556
OS 51.38657236 -38.41820612
OS 51.39766708 -38.39601668
OS 51.404139 -38.38492196
OS 51.41246004 -38.37382724
OS 51.42078108 -38.36365708
OS 51.43002668 -38.35441148
OS 51.43095124 -38.35348692
OS 51.43280036 -38.35256236
OS 51.43557404 -38.34978868
OS 51.44019684 -38.347015
OS 51.4457442 -38.34331676
OS 51.45221612 -38.33961852
OS 51.4596126 -38.33499572
OS 51.4688582 -38.33037292
OS 51.47902836 -38.32575012
OS 51.49012308 -38.32112732
OS 51.50214236 -38.31742908
OS 51.5150862 -38.31373084
OS 51.5289546 -38.31095716
OS 51.54374756 -38.30818348
OS 51.55946508 -38.30725892
OS 51.57610716 -38.30633436
OS 51.58535276 -38.30633436
OS 51.59182468 -38.30725892
OE
OB 52.08184148 -38.30725892 I
OS 52.09386076 -38.30910804
OS 52.10865372 -38.31188172
OS 52.1252958 -38.31650452
OS 52.14193788 -38.32205188
OS 52.15857996 -38.32944836
OS 52.15950452 -38.32944836
OS 52.16042908 -38.33037292
OS 52.16597644 -38.3331466
OS 52.17429748 -38.33869396
OS 52.18354308 -38.34516588
OS 52.1946378 -38.35441148
OS 52.20573252 -38.36458164
OS 52.21682724 -38.37660092
OS 52.22607284 -38.39046932
OS 52.2269974 -38.39231844
OS 52.22977108 -38.39694124
OS 52.23346932 -38.40526228
OS 52.23809212 -38.41543244
OS 52.24271492 -38.42745172
OS 52.24641316 -38.44132012
OS 52.24918684 -38.45703764
OS 52.2501114 -38.47275516
OS 52.2501114 -38.47460428
OS 52.2501114 -38.48015164
OS 52.24918684 -38.48754812
OS 52.24733772 -38.49771828
OS 52.24456404 -38.50973756
OS 52.23994124 -38.5226814
OS 52.23439388 -38.53562524
OS 52.2269974 -38.54856908
OS 52.22607284 -38.5504182
OS 52.22329916 -38.55411644
OS 52.2177518 -38.56058836
OS 52.21035532 -38.56798484
OS 52.20110972 -38.57630588
OS 52.190015 -38.58555148
OS 52.17707116 -38.59387252
OS 52.16135364 -38.60219356
OS 52.1622782 -38.60219356
OS 52.16412732 -38.60311812
OS 52.166901 -38.60404268
OS 52.17059924 -38.60496724
OS 52.1807694 -38.60866548
OS 52.19371324 -38.61421284
OS 52.2085062 -38.62160932
OS 52.22329916 -38.63085492
OS 52.23716756 -38.6428742
OS 52.2501114 -38.6567426
OS 52.25103596 -38.65859172
OS 52.2547342 -38.66413908
OS 52.26028156 -38.67338468
OS 52.26582892 -38.68540396
OS 52.27137628 -38.70019692
OS 52.27692364 -38.71776356
OS 52.28062188 -38.73810388
OS 52.28154644 -38.76029332
OS 52.28154644 -38.76121788
OS 52.28154644 -38.76399156
OS 52.28154644 -38.76861436
OS 52.28062188 -38.77416172
OS 52.27969732 -38.7815582
OS 52.2778482 -38.78987924
OS 52.27599908 -38.79912484
OS 52.27414996 -38.809295
OS 52.26675348 -38.83148444
OS 52.26120612 -38.84350372
OS 52.25565876 -38.85459844
OS 52.24826228 -38.86661772
OS 52.23994124 -38.878637
OS 52.23069564 -38.89065628
OS 52.21960092 -38.901751
OS 52.21867636 -38.90267556
OS 52.21682724 -38.90452468
OS 52.213129 -38.90729836
OS 52.2085062 -38.9109966
OS 52.20295884 -38.9156194
OS 52.19556236 -38.9202422
OS 52.18724132 -38.92578956
OS 52.17707116 -38.93041236
OS 52.166901 -38.93595972
OS 52.15488172 -38.94150708
OS 52.14286244 -38.94612988
OS 52.12899404 -38.95075268
OS 52.11420108 -38.95445092
OS 52.09848356 -38.9572246
OS 52.08276604 -38.95907372
OS 52.0651994 -38.95999828
OS 52.05687836 -38.95999828
OS 52.051331 -38.95907372
OS 52.04393452 -38.95814916
OS 52.03561348 -38.9572246
OS 52.02636788 -38.95537548
OS 52.01619772 -38.95352636
OS 51.99400828 -38.947979
OS 51.97089428 -38.9387334
OS 51.958875 -38.93318604
OS 51.94778028 -38.92671412
OS 51.93668556 -38.91839308
OS 51.92559084 -38.91007204
OS 51.92466628 -38.90914748
OS 51.92281716 -38.90729836
OS 51.92004348 -38.90452468
OS 51.9172698 -38.90082644
OS 51.912647 -38.89620364
OS 51.9080242 -38.88973172
OS 51.90247684 -38.8832598
OS 51.89692948 -38.87493876
OS 51.89138212 -38.86569316
OS 51.88583476 -38.85644756
OS 51.8756646 -38.83425812
OS 51.86734356 -38.80837044
OS 51.86456988 -38.79450204
OS 51.86272076 -38.77970908
OS 51.94130836 -38.76953892
OS 51.94130836 -38.77046348
OS 51.94223292 -38.7723126
OS 51.94315748 -38.77601084
OS 51.94408204 -38.78063364
OS 51.9450066 -38.786181
OS 51.94685572 -38.79265292
OS 51.95147852 -38.80652132
OS 51.95795044 -38.8231634
OS 51.96627148 -38.83888092
OS 51.97551708 -38.85367388
OS 51.9866118 -38.86661772
OS 51.98846092 -38.86754228
OS 51.99215916 -38.87124052
OS 51.99955564 -38.87586332
OS 52.00880124 -38.88048612
OS 52.01989596 -38.88603348
OS 52.03376436 -38.89065628
OS 52.04948188 -38.89435452
OS 52.06612396 -38.89527908
OS 52.07167132 -38.89527908
OS 52.07536956 -38.89435452
OS 52.08553972 -38.89342996
OS 52.09848356 -38.89065628
OS 52.11327652 -38.88603348
OS 52.12899404 -38.87956156
OS 52.14471156 -38.87031596
OS 52.15950452 -38.85737212
OS 52.16135364 -38.855523
OS 52.16597644 -38.84997564
OS 52.1715238 -38.8416546
OS 52.17892028 -38.83055988
OS 52.18631676 -38.81669148
OS 52.19186412 -38.80097396
OS 52.19648692 -38.78248276
OS 52.19833604 -38.76214244
OS 52.19833604 -38.76121788
OS 52.19833604 -38.75936876
OS 52.19833604 -38.75659508
OS 52.19741148 -38.75289684
OS 52.19648692 -38.74272668
OS 52.19371324 -38.7307074
OS 52.190015 -38.71591444
OS 52.18354308 -38.70112148
OS 52.17429748 -38.68632852
OS 52.1622782 -38.67246012
OS 52.16042908 -38.670611
OS 52.15580628 -38.66691276
OS 52.1484098 -38.6613654
OS 52.13823964 -38.65489348
OS 52.1252958 -38.64842156
OS 52.10957828 -38.6428742
OS 52.09201164 -38.63917596
OS 52.07259588 -38.63732684
OS 52.06427484 -38.63732684
OS 52.05780292 -38.6382514
OS 52.04948188 -38.63917596
OS 52.04023628 -38.64102508
OS 52.02914156 -38.6428742
OS 52.01712228 -38.64564788
OS 52.02636788 -38.57630588
OS 52.03099068 -38.57630588
OS 52.03468892 -38.57723044
OS 52.0467082 -38.57723044
OS 52.05687836 -38.57538132
OS 52.06889764 -38.5735322
OS 52.08276604 -38.57075852
OS 52.09848356 -38.56613572
OS 52.11327652 -38.5596638
OS 52.12899404 -38.55134276
OS 52.1299186 -38.55134276
OS 52.13084316 -38.5504182
OS 52.13546596 -38.54671996
OS 52.14193788 -38.54024804
OS 52.14933436 -38.531927
OS 52.15673084 -38.51990772
OS 52.16320276 -38.50603932
OS 52.16782556 -38.4903218
OS 52.16967468 -38.4810762
OS 52.16967468 -38.47090604
OS 52.16967468 -38.46998148
OS 52.16967468 -38.46905692
OS 52.16967468 -38.46350956
OS 52.16782556 -38.45611308
OS 52.16597644 -38.44594292
OS 52.1622782 -38.4348482
OS 52.1576554 -38.42282892
OS 52.15025892 -38.41080964
OS 52.14008876 -38.39971492
OS 52.1391642 -38.39879036
OS 52.1345414 -38.39509212
OS 52.12806948 -38.39046932
OS 52.11974844 -38.38492196
OS 52.10865372 -38.38029916
OS 52.09570988 -38.37567636
OS 52.08091692 -38.37197812
OS 52.06427484 -38.37105356
OS 52.05687836 -38.37105356
OS 52.04855732 -38.37290268
OS 52.0374626 -38.3747518
OS 52.02544332 -38.37845004
OS 52.01342404 -38.38307284
OS 52.0004802 -38.39046932
OS 51.98846092 -38.39971492
OS 51.98753636 -38.40063948
OS 51.98383812 -38.40526228
OS 51.97829076 -38.4117342
OS 51.97181884 -38.4209798
OS 51.96534692 -38.43299908
OS 51.958875 -38.44779204
OS 51.95332764 -38.46535868
OS 51.9496294 -38.485699
OS 51.8710418 -38.4718306
OS 51.8710418 -38.47090604
OS 51.87196636 -38.46813236
OS 51.87289092 -38.46443412
OS 51.87381548 -38.45888676
OS 51.8756646 -38.45241484
OS 51.87843828 -38.44501836
OS 51.88398564 -38.42745172
OS 51.89323124 -38.4071114
OS 51.90432596 -38.38677108
OS 51.91819436 -38.36735532
OS 51.935761 -38.34978868
OS 51.93668556 -38.34886412
OS 51.93853468 -38.34793956
OS 51.94130836 -38.34609044
OS 51.9450066 -38.34331676
OS 51.9496294 -38.33961852
OS 51.95610132 -38.33592028
OS 51.96257324 -38.33222204
OS 51.97089428 -38.32759924
OS 51.98938548 -38.32020276
OS 52.01065036 -38.31280628
OS 52.03561348 -38.30818348
OS 52.04855732 -38.30633436
OS 52.07167132 -38.30633436
OS 52.08184148 -38.30725892
OE
OB 56.14158444 -38.38492196 H
OS 55.95852156 -38.38492196
OS 55.95852156 -38.61328828
OS 56.13048972 -38.61328828
OS 56.13696164 -38.61236372
OS 56.14343356 -38.61236372
OS 56.15083004 -38.61143916
OS 56.16839668 -38.60959004
OS 56.18781244 -38.6058918
OS 56.2072282 -38.60034444
OS 56.22479484 -38.59294796
OS 56.23311588 -38.58832516
OS 56.2395878 -38.5827778
OS 56.24143692 -38.58092868
OS 56.24513516 -38.57723044
OS 56.25068252 -38.56983396
OS 56.25715444 -38.56058836
OS 56.26362636 -38.54856908
OS 56.26917372 -38.53377612
OS 56.27287196 -38.51713404
OS 56.27472108 -38.49771828
OS 56.27472108 -38.49679372
OS 56.27472108 -38.49586916
OS 56.27472108 -38.49124636
OS 56.27379652 -38.48292532
OS 56.2719474 -38.47367972
OS 56.27009828 -38.46350956
OS 56.26640004 -38.45149028
OS 56.26085268 -38.44039556
OS 56.25438076 -38.42930084
OS 56.2534562 -38.42837628
OS 56.25068252 -38.42467804
OS 56.24605972 -38.42005524
OS 56.24051236 -38.41358332
OS 56.23219132 -38.4071114
OS 56.22294572 -38.40156404
OS 56.21277556 -38.39601668
OS 56.20075628 -38.39139388
OS 56.19983172 -38.39139388
OS 56.19613348 -38.39046932
OS 56.19058612 -38.38954476
OS 56.18318964 -38.38769564
OS 56.17209492 -38.38677108
OS 56.15822652 -38.38584652
OS 56.14158444 -38.38492196
OE
OB 49.87491676 -38.43669732 H
OS 49.67336268 -38.72331092
OS 49.87491676 -38.72331092
OS 49.87491676 -38.43669732
OE
OB 54.06132444 -38.37105356 H
OS 54.05392796 -38.37105356
OS 54.04560692 -38.37290268
OS 54.0345122 -38.3747518
OS 54.02249292 -38.37845004
OS 54.00954908 -38.38307284
OS 53.9975298 -38.39046932
OS 53.98551052 -38.40063948
OS 53.98458596 -38.40156404
OS 53.98088772 -38.40526228
OS 53.97626492 -38.4117342
OS 53.97164212 -38.42005524
OS 53.96609476 -38.4302254
OS 53.96147196 -38.44224468
OS 53.95777372 -38.45518852
OS 53.95684916 -38.46998148
OS 53.95684916 -38.47090604
OS 53.95684916 -38.4718306
OS 53.95777372 -38.47737796
OS 53.95869828 -38.485699
OS 53.9605474 -38.49586916
OS 53.96424564 -38.50788844
OS 53.96886844 -38.51990772
OS 53.97626492 -38.53285156
OS 53.98551052 -38.54394628
OS 53.98643508 -38.54487084
OS 53.99105788 -38.54856908
OS 53.9975298 -38.55319188
OS 54.00585084 -38.55781468
OS 54.01694556 -38.56336204
OS 54.0298894 -38.56798484
OS 54.04468236 -38.57168308
OS 54.06132444 -38.57260764
OS 54.06317356 -38.57260764
OS 54.06872092 -38.57168308
OS 54.07704196 -38.57075852
OS 54.08813668 -38.5689094
OS 54.10015596 -38.56521116
OS 54.11217524 -38.56058836
OS 54.12511908 -38.55319188
OS 54.1362138 -38.54394628
OS 54.13713836 -38.54302172
OS 54.1408366 -38.53839892
OS 54.1454594 -38.53285156
OS 54.15100676 -38.52453052
OS 54.15655412 -38.51436036
OS 54.16117692 -38.50234108
OS 54.16487516 -38.48847268
OS 54.16579972 -38.47367972
OS 54.16579972 -38.47275516
OS 54.16579972 -38.4718306
OS 54.16579972 -38.46628324
OS 54.1639506 -38.4579622
OS 54.16210148 -38.44779204
OS 54.15840324 -38.43669732
OS 54.15285588 -38.42467804
OS 54.1454594 -38.41265876
OS 54.13528924 -38.40063948
OS 54.13436468 -38.39971492
OS 54.12974188 -38.39601668
OS 54.12326996 -38.39139388
OS 54.11494892 -38.38584652
OS 54.1038542 -38.38029916
OS 54.09183492 -38.37567636
OS 54.07704196 -38.37197812
OS 54.06132444 -38.37105356
OE
OB 54.05855076 -38.63640228 H
OS 54.0530034 -38.63640228
OS 54.04930516 -38.63732684
OS 54.039135 -38.6382514
OS 54.02619116 -38.64102508
OS 54.0113982 -38.64564788
OS 53.99660524 -38.6521198
OS 53.98088772 -38.6613654
OS 53.96701932 -38.67338468
OS 53.9651702 -38.6752338
OS 53.96147196 -38.6798566
OS 53.9559246 -38.68817764
OS 53.94945268 -38.6983478
OS 53.9420562 -38.7122162
OS 53.93650884 -38.72793372
OS 53.9328106 -38.74550036
OS 53.93096148 -38.76491612
OS 53.93096148 -38.76676524
OS 53.93096148 -38.77046348
OS 53.93188604 -38.7769354
OS 53.9328106 -38.78525644
OS 53.93465972 -38.7954266
OS 53.9374334 -38.80652132
OS 53.94113164 -38.81761604
OS 53.94575444 -38.82963532
OS 53.946679 -38.83055988
OS 53.94852812 -38.83518268
OS 53.95222636 -38.84073004
OS 53.95777372 -38.84720196
OS 53.96424564 -38.855523
OS 53.97256668 -38.86384404
OS 53.98181228 -38.87124052
OS 53.992907 -38.878637
OS 53.99475612 -38.87956156
OS 53.99845436 -38.88141068
OS 54.00492628 -38.88418436
OS 54.01324732 -38.88695804
OS 54.02341748 -38.88973172
OS 54.03543676 -38.8925054
OS 54.0483806 -38.89435452
OS 54.06132444 -38.89527908
OS 54.0668718 -38.89527908
OS 54.07057004 -38.89435452
OS 54.08166476 -38.89342996
OS 54.0946086 -38.89065628
OS 54.10940156 -38.88603348
OS 54.12511908 -38.88048612
OS 54.13991204 -38.87124052
OS 54.154705 -38.85922124
OS 54.15655412 -38.85737212
OS 54.16025236 -38.85274932
OS 54.16672428 -38.84442828
OS 54.1731962 -38.83425812
OS 54.17966812 -38.82131428
OS 54.18614004 -38.80559676
OS 54.18983828 -38.78710556
OS 54.1916874 -38.7676898
OS 54.1916874 -38.76676524
OS 54.1916874 -38.76491612
OS 54.1916874 -38.76214244
OS 54.19076284 -38.7584442
OS 54.18983828 -38.74827404
OS 54.1870646 -38.73440564
OS 54.1824418 -38.72053724
OS 54.17596988 -38.70481972
OS 54.16672428 -38.6891022
OS 54.15378044 -38.67430924
OS 54.15193132 -38.67246012
OS 54.14730852 -38.66876188
OS 54.13898748 -38.66228996
OS 54.12789276 -38.65489348
OS 54.11402436 -38.64842156
OS 54.09738228 -38.64194964
OS 54.07889108 -38.6382514
OS 54.05855076 -38.63640228
OE
OB 54.80559524 -38.37105356 H
OS 54.80004788 -38.37105356
OS 54.79634964 -38.37197812
OS 54.78617948 -38.37382724
OS 54.7741602 -38.37660092
OS 54.7602918 -38.38214828
OS 54.74549884 -38.39046932
OS 54.73810236 -38.39601668
OS 54.73070588 -38.40156404
OS 54.72423396 -38.40896052
OS 54.71776204 -38.41728156
OS 54.71776204 -38.41820612
OS 54.71591292 -38.42005524
OS 54.7140638 -38.42375348
OS 54.71129012 -38.42837628
OS 54.70851644 -38.43577276
OS 54.7048182 -38.4440938
OS 54.70204452 -38.45426396
OS 54.69834628 -38.46628324
OS 54.69464804 -38.48015164
OS 54.6909498 -38.49586916
OS 54.68725156 -38.5134358
OS 54.68447788 -38.53285156
OS 54.6817042 -38.555041
OS 54.67985508 -38.57907956
OS 54.67893052 -38.60496724
OS 54.67800596 -38.6336286
OS 54.67800596 -38.63547772
OS 54.67800596 -38.64010052
OS 54.67800596 -38.64842156
OS 54.67893052 -38.65951628
OS 54.67893052 -38.67153556
OS 54.67985508 -38.68632852
OS 54.68077964 -38.70204604
OS 54.68262876 -38.71868812
OS 54.68725156 -38.75474596
OS 54.69002524 -38.7723126
OS 54.69372348 -38.78895468
OS 54.69742172 -38.8046722
OS 54.70296908 -38.81946516
OS 54.70851644 -38.832409
OS 54.71498836 -38.84350372
OS 54.71498836 -38.84442828
OS 54.71683748 -38.84535284
OS 54.72146028 -38.85182476
OS 54.72978132 -38.8601458
OS 54.73995148 -38.8693914
OS 54.75381988 -38.878637
OS 54.7695374 -38.88695804
OS 54.78710404 -38.89342996
OS 54.79634964 -38.89435452
OS 54.8065198 -38.89527908
OS 54.81206716 -38.89527908
OS 54.8157654 -38.89435452
OS 54.825011 -38.8925054
OS 54.83795484 -38.88880716
OS 54.85182324 -38.88233524
OS 54.86754076 -38.87308964
OS 54.87493724 -38.86754228
OS 54.88233372 -38.8601458
OS 54.8897302 -38.85274932
OS 54.89712668 -38.84350372
OS 54.89712668 -38.84257916
OS 54.8989758 -38.84073004
OS 54.90082492 -38.83795636
OS 54.90267404 -38.83333356
OS 54.90637228 -38.82686164
OS 54.90914596 -38.8185406
OS 54.9128442 -38.809295
OS 54.91654244 -38.79820028
OS 54.91931612 -38.78433188
OS 54.92301436 -38.76953892
OS 54.9267126 -38.75197228
OS 54.92948628 -38.73348108
OS 54.9313354 -38.71129164
OS 54.93318452 -38.68817764
OS 54.93503364 -38.66228996
OS 54.93503364 -38.6336286
OS 54.93503364 -38.63270404
OS 54.93503364 -38.63177948
OS 54.93503364 -38.62715668
OS 54.93503364 -38.61883564
OS 54.93410908 -38.60774092
OS 54.93410908 -38.59572164
OS 54.93318452 -38.58092868
OS 54.93225996 -38.56521116
OS 54.93041084 -38.54764452
OS 54.92578804 -38.51251124
OS 54.92301436 -38.4949446
OS 54.91931612 -38.47830252
OS 54.91561788 -38.462585
OS 54.91007052 -38.44779204
OS 54.90452316 -38.4348482
OS 54.89805124 -38.42375348
OS 54.89805124 -38.42282892
OS 54.89620212 -38.42190436
OS 54.894353 -38.41913068
OS 54.89157932 -38.41543244
OS 54.88325828 -38.4071114
OS 54.87308812 -38.39694124
OS 54.85921972 -38.38769564
OS 54.8435022 -38.3793746
OS 54.83518116 -38.37567636
OS 54.82593556 -38.37290268
OS 54.8157654 -38.37197812
OS 54.80559524 -38.37105356
OE
OB 51.07499564 -38.37105356 H
OS 51.06944828 -38.37105356
OS 51.06575004 -38.37197812
OS 51.05557988 -38.37382724
OS 51.0435606 -38.37660092
OS 51.0296922 -38.38214828
OS 51.01489924 -38.39046932
OS 51.00750276 -38.39601668
OS 51.00010628 -38.40156404
OS 50.99363436 -38.40896052
OS 50.98716244 -38.41728156
OS 50.98716244 -38.41820612
OS 50.98531332 -38.42005524
OS 50.9834642 -38.42375348
OS 50.98069052 -38.42837628
OS 50.97791684 -38.43577276
OS 50.9742186 -38.4440938
OS 50.97144492 -38.45426396
OS 50.96774668 -38.46628324
OS 50.96404844 -38.48015164
OS 50.9603502 -38.49586916
OS 50.95665196 -38.5134358
OS 50.95387828 -38.53285156
OS 50.9511046 -38.555041
OS 50.94925548 -38.57907956
OS 50.94833092 -38.60496724
OS 50.94740636 -38.6336286
OS 50.94740636 -38.63547772
OS 50.94740636 -38.64010052
OS 50.94740636 -38.64842156
OS 50.94833092 -38.65951628
OS 50.94833092 -38.67153556
OS 50.94925548 -38.68632852
OS 50.95018004 -38.70204604
OS 50.95202916 -38.71868812
OS 50.95665196 -38.75474596
OS 50.95942564 -38.7723126
OS 50.96312388 -38.78895468
OS 50.96682212 -38.8046722
OS 50.97236948 -38.81946516
OS 50.97791684 -38.832409
OS 50.98438876 -38.84350372
OS 50.98438876 -38.84442828
OS 50.98623788 -38.84535284
OS 50.99086068 -38.85182476
OS 50.99918172 -38.8601458
OS 51.00935188 -38.8693914
OS 51.02322028 -38.878637
OS 51.0389378 -38.88695804
OS 51.05650444 -38.89342996
OS 51.06575004 -38.89435452
OS 51.0759202 -38.89527908
OS 51.08146756 -38.89527908
OS 51.0851658 -38.89435452
OS 51.0944114 -38.8925054
OS 51.10735524 -38.88880716
OS 51.12122364 -38.88233524
OS 51.13694116 -38.87308964
OS 51.14433764 -38.86754228
OS 51.15173412 -38.8601458
OS 51.1591306 -38.85274932
OS 51.16652708 -38.84350372
OS 51.16652708 -38.84257916
OS 51.1683762 -38.84073004
OS 51.17022532 -38.83795636
OS 51.17207444 -38.83333356
OS 51.17577268 -38.82686164
OS 51.17854636 -38.8185406
OS 51.1822446 -38.809295
OS 51.18594284 -38.79820028
OS 51.18871652 -38.78433188
OS 51.19241476 -38.76953892
OS 51.196113 -38.75197228
OS 51.19888668 -38.73348108
OS 51.2007358 -38.71129164
OS 51.20258492 -38.68817764
OS 51.20443404 -38.66228996
OS 51.20443404 -38.6336286
OS 51.20443404 -38.63270404
OS 51.20443404 -38.63177948
OS 51.20443404 -38.62715668
OS 51.20443404 -38.61883564
OS 51.20350948 -38.60774092
OS 51.20350948 -38.59572164
OS 51.20258492 -38.58092868
OS 51.20166036 -38.56521116
OS 51.19981124 -38.54764452
OS 51.19518844 -38.51251124
OS 51.19241476 -38.4949446
OS 51.18871652 -38.47830252
OS 51.18501828 -38.462585
OS 51.17947092 -38.44779204
OS 51.17392356 -38.4348482
OS 51.16745164 -38.42375348
OS 51.16745164 -38.42282892
OS 51.16560252 -38.42190436
OS 51.1637534 -38.41913068
OS 51.16097972 -38.41543244
OS 51.15265868 -38.4071114
OS 51.14248852 -38.39694124
OS 51.12862012 -38.38769564
OS 51.1129026 -38.3793746
OS 51.10458156 -38.37567636
OS 51.09533596 -38.37290268
OS 51.0851658 -38.37197812
OS 51.07499564 -38.37105356
OE
SE
P -2.99999908 16.00000102 7 P 0 0 ;0=6,1=1
P -2.99999908 17.99999956 7 P 0 0 ;0=6,1=1
P -2.99999908 20.00000064 7 P 0 0 ;0=6,1=1
P -2.99999908 21.99999918 7 P 0 0 ;0=6,1=1
P -2.99999908 24.00000026 7 P 0 0 ;0=6,1=1
P -2.99999908 25.9999988 7 P 0 0 ;0=6,1=1
P -2.99999908 27.99999988 7 P 0 0 ;0=6,1=1
P -2.99999908 30.00000096 7 P 0 0 ;0=6,1=1
P -2.99999908 31.9999995 7 P 0 0 ;0=6,1=1
P -2.99999908 34.00000058 7 P 0 0 ;0=6,1=1
P -2.99999908 35.99999912 7 P 0 0 ;0=6,1=1
P -2.99999908 38.0000002 7 P 0 0 ;0=6,1=1
P -2.99999908 39.99999874 7 P 0 0 ;0=6,1=1
P 0.50000154 -3.99999962 7 P 0 0 ;0=6,1=1
P 2.50000008 -3.99999962 7 P 0 0 ;0=6,1=1
P 4.50000116 -3.99999962 7 P 0 0 ;0=6,1=1
P 6.4999997 -3.99999962 7 P 0 0 ;0=6,1=1
P 8.50000078 -3.99999962 7 P 0 0 ;0=6,1=1
P 10.49999932 -3.99999962 7 P 0 0 ;0=6,1=1
P 12.5000004 -3.99999962 7 P 0 0 ;0=6,1=1
P 12.74500118 40.26499948 7 P 0 0 ;0=6,1=1
P 12.74500118 41.21500012 7 P 0 0 ;0=6,1=1
P 12.74500118 44.63999962 7 P 0 0 ;0=6,1=1
P 12.75500116 42.16500076 7 P 0 0 ;0=6,1=1
P 12.98999942 18.0150008 7 P 0 0 ;0=6,1=1
P 14.50000148 -3.99999962 7 P 0 0 ;0=6,1=1
P 15.88470534 21.56499878 7 P 0 0 ;0=6,1=1
P 16.30970576 23.03999964 7 P 0 0 ;0=6,1=1
P 16.50000002 -3.99999962 7 P 0 0 ;0=6,1=1
P 17.57500168 13.89000016 7 P 0 0 ;0=6,1=1
P 17.915001 15.69625258 7 P 0 0 ;0=6,1=1
P 18.8149992 15.10000028 7 P 0 0 ;0=6,1=1
P 18.8149992 15.98270108 7 P 0 0 ;0=6,1=1
P 18.8149992 16.85250122 7 P 0 0 ;0=6,1=1
P 19.01500134 7.39000046 7 P 0 0 ;0=6,1=1
P 19.01500134 8.5900006 7 P 0 0 ;0=6,1=1
P 19.01500134 9.7899982 7 P 0 0 ;0=6,1=1
P 19.01500134 11.09000068 7 P 0 0 ;0=6,1=1
P 19.01500134 12.39000062 7 P 0 0 ;0=6,1=1
P 21.11499968 6.76500044 7 P 0 0 ;0=6,1=1
P 21.11499968 7.78999966 7 P 0 0 ;0=6,1=1
P 21.11499968 8.9899998 7 P 0 0 ;0=6,1=1
P 21.11499968 10.28999974 7 P 0 0 ;0=6,1=1
P 21.11499968 11.38590052 7 P 0 0 ;0=6,1=1
P 22.05919388 12.29000082 7 P 0 0 ;0=6,1=1
P 22.45970616 20.01499934 7 P 0 0 ;0=6,1=1
P 23.29999912 38.90000094 7 P 0 0 ;0=6,1=1
P 23.33999904 44.0138312 7 P 0 0 ;0=6,1=1
P 23.4097068 20.04000056 7 P 0 0 ;0=6,1=1
P 24.35970744 20.04000056 7 P 0 0 ;0=6,1=1
P 24.49999926 -3.50000062 7 P 0 0 ;0=6,1=1
P 25.7999992 38.90000094 7 P 0 0 ;0=6,1=1
P 26.50000034 -3.50000062 7 P 0 0 ;0=6,1=1
P 28.50000142 -3.50000062 7 P 0 0 ;0=6,1=1
P 30.49999996 -3.50000062 7 P 0 0 ;0=6,1=1
P 32.50000104 -3.50000062 7 P 0 0 ;0=6,1=1
P 32.80000044 38.90000094 7 P 0 0 ;0=6,1=1
P 35.30000052 44.0000009 7 P 0 0 ;0=6,1=1
P 38.4999992 -3.50000062 7 P 0 0 ;0=6,1=1
P 39.60000208 38.91499964 7 P 0 0 ;0=6,1=1
P 40.50000028 -3.50000062 7 P 0 0 ;0=6,1=1
P 40.67999992 42.76499956 7 P 0 0 ;0=6,1=1
P 42.2249981 38.91499964 7 P 0 0 ;0=6,1=1
P 44.4999999 0.499999 7 P 0 0 ;0=6,1=1
P 44.4999999 2.50000008 7 P 0 0 ;0=6,1=1
P 44.4999999 4.49999862 7 P 0 0 ;0=6,1=1
P 44.4999999 6.4999997 7 P 0 0 ;0=6,1=1
P 44.4999999 8.49999824 7 P 0 0 ;0=6,1=1
P 44.4999999 10.49999932 7 P 0 0 ;0=6,1=1
P 44.4999999 12.49999786 7 P 0 0 ;0=6,1=1
P 44.4999999 14.49999894 7 P 0 0 ;0=6,1=1
P 44.4999999 16.50000002 7 P 0 0 ;0=6,1=1
P 44.4999999 18.49999856 7 P 0 0 ;0=6,1=1
P 44.4999999 20.49999964 7 P 0 0 ;0=6,1=1
P 44.4999999 22.49999818 7 P 0 0 ;0=6,1=1
P 44.4999999 24.49999926 7 P 0 0 ;0=6,1=1
P 44.4999999 26.4999978 7 P 0 0 ;0=6,1=1
P 44.4999999 28.49999888 7 P 0 0 ;0=6,1=1
P 44.4999999 30.49999996 7 P 0 0 ;0=6,1=1
P 44.4999999 32.4999985 7 P 0 0 ;0=6,1=1
P 44.4999999 34.49999958 7 P 0 0 ;0=6,1=1
P 44.4999999 36.49999812 7 P 0 0 ;0=6,1=1
P 44.4999999 38.4999992 7 P 0 0 ;0=6,1=1
P 44.4999999 40.49999774 7 P 0 0 ;0=6,1=1

### steps/pcb/layers/l02-inner_layer/features
UNITS=MM
#Layer_Physical_Order=2
#Layer_Color=36540
#
#Feature symbol names
#
$0 r199.9996
$1 r99.9998
$2 r2090.0009
$3 r1524
$4 r1562.00094
$5 r1799.99894
$6 r599.9988

#
#Feature attribute names
#
@0 .geometry
@1 .pad_usage
@2 .nomenclature
@3 .string
@4 .string_angle

#
#Feature attribute text strings
#
&0 Pad_Simple_X2090.0009Y2090.0009H1090.0004C2106.0004
&1 Pad_Simple_X1524.0000Y1524.0000H762.0000C1778.0000
&2 Pad_Simple_X1562.0009Y1562.0009H961.9996C1977.9996
&3 Pad_Simple_X1799.9989Y1799.9989H1200.0001C2216.0001
&4 VIA_RoundD599.9988H299.9994C1315.9994

#
#Layer features
#
A 7.10000104 39.85210216 7.84394926 38.05605038 9.64000104 39.85210216 0 P 0 N
A 7.10000104 40.79999968 6.70684968 41.74914688 5.75770248 40.79999968 0 P 0 N
A 8.1739994 40.28310206 8.91794762 38.48705028 10.7139994 40.28310206 0 P 0 N
A 8.65605076 16.54605022 9.39999898 18.342102 6.85999898 18.342102 0 P 0 N
A 9.39999898 35.59999992 8.76360198 37.13639766 7.22720424 35.59999992 0 P 0 N
A 9.72105244 12.5310519 10.46500066 14.32710368 7.92500066 14.32710368 0 P 0 N
A 10.46500066 35.77336254 9.64044554 37.76454728 7.6507848 35.77430742 0 P 0 N
A 11.2219994 38.96010496 11.96594762 37.16405318 13.7619994 38.96010496 0 P 0 N
A 14.26999686 39.24563398 14.80955382 37.94543084 16.1063051 39.24560858 0 P 0 N
A 19.31499312 29.81499244 22.27014088 28.58999616 22.27240148 32.77240588 0 P 0 N
A 20.75207178 32.00292812 22.23112902 31.3899931 22.23183514 33.48269656 0 P 0 N
A 27.82772438 27.82227608 25.97569354 28.5899987 25.975691 25.97224422 0 P 0 N
A 30.38394736 30.34604802 27.86362728 31.39000072 27.86362474 27.82573048 0 P 0 N
L -9.5600012 -24.45999934 40.4400004 -24.45999934 1 P 0
L -9.5600012 -35.9599992 -9.5600012 -24.45999934 1 P 0
L -9.5600012 -35.9599992 28.439999 -35.9599992 1 P 0
L -9.5600012 -39.45999982 -9.5600012 -35.9599992 1 P 0
L -9.5600012 -39.45999982 28.439999 -39.45999982 1 P 0
L -9.5600012 -42.96000044 -9.5600012 -39.45999982 1 P 0
L -9.5600012 -42.96000044 28.439999 -42.96000044 1 P 0
L -10.0600002 -23.96000034 62.93999858 -23.96000034 1 P 0
L -10.0600002 -43.45999944 -10.0600002 -23.96000034 1 P 0
L -10.0600002 -43.45999944 62.93999858 -43.45999944 1 P 0
L 4.8300005 7.63999996 9.72105244 12.5310519 0 P 0
L 4.8300005 12.71999996 8.65605076 16.54605022 0 P 0
L 5.1259994 43.3299997 6.70684968 41.74914942 0 P 0
L 7.10000104 39.85210216 7.10000104 40.79999968 0 P 0
L 7.84394926 38.05605038 8.76360198 37.13639766 0 P 0
L 8.1739994 40.28310206 8.1739994 43.34999966 0 P 0
L 8.91794508 38.48705028 9.63984864 37.76514672 0 P 0
L 9.39999898 18.342102 9.39999898 35.59999992 0 P 0
L 9.63984864 37.76514672 9.64044554 37.76454728 0 P 0
L 10.46499812 35.77336254 10.46500066 35.77330158 0 P 0
L 10.46500066 14.32710368 10.46500066 35.77330158 0 P 0
L 11.2219994 38.96010496 11.2219994 43.34999966 0 P 0
L 11.96594762 37.16405318 19.31500074 29.81500006 0 P 0
L 14.26999686 39.24563398 14.2699994 39.24663982 0 P 0
L 14.2699994 39.24663982 14.2699994 43.34999966 0 P 0
L 14.80955128 37.9454283 14.80955382 37.94543084 0 P 0
L 14.80955382 37.94543084 20.75207432 32.00293066 0 P 0
L 22.2311341 31.38999818 27.86362982 31.39000072 0 P 0
L 22.27014088 28.58999616 25.97569608 28.5899987 0 P 0
L 27.82772438 27.82227608 37.8500005 17.79999996 0 P 0
L 28.439999 -35.96000174 45.44000056 -35.9599992 1 P 0
L 28.439999 -39.45999982 28.439999 -35.9599992 1 P 0
L 28.439999 -39.46000236 45.44000056 -39.45999982 1 P 0
L 28.439999 -42.96000044 28.439999 -39.45999982 1 P 0
L 28.439999 -42.96000298 45.44000056 -42.96000044 1 P 0
L 30.3839499 30.34605056 37.8500005 22.87999996 0 P 0
L 40.4400004 -24.45999934 62.43999958 -24.45999934 1 P 0
L 40.4400004 -35.9599992 40.4400004 -24.45999934 1 P 0
L 45.44000056 -35.9599992 62.43999958 -35.9599992 1 P 0
L 45.44000056 -39.45999982 62.43999958 -39.45999982 1 P 0
L 45.44000056 -42.96000044 45.44000056 -35.9599992 1 P 0
L 45.44000056 -42.96000044 62.43999958 -42.96000044 1 P 0
L 62.43999958 -35.9599992 62.43999958 -24.45999934 1 P 0
L 62.43999958 -42.96000044 62.43999958 -35.9599992 1 P 0
L 62.93999858 -43.45999944 62.93999858 -23.96000034 1 P 0
P 0 40.64 2 P 0 0 ;0=0,1=0
P 4.8300005 7.63999996 5 P 0 0 ;0=3,1=0
P 4.8300005 7.63999996 3 P 0 0 ;0=1,1=0
P 4.8300005 12.71999996 5 P 0 0 ;0=3,1=0
P 4.8300005 12.71999996 3 P 0 0 ;0=1,1=0
P 5.1259994 43.3299997 2 P 0 0 ;0=0,1=0
P 8.1739994 43.3299997 2 P 0 0 ;0=0,1=0
P 11.2219994 43.3299997 2 P 0 0 ;0=0,1=0
P 14.2699994 43.3299997 2 P 0 0 ;0=0,1=0
P 37.8500005 12.71999996 5 P 0 0 ;0=3,1=0
P 37.8500005 12.71999996 4 P 0 0 ;0=2,1=0
P 37.8500005 17.79999996 5 P 0 0 ;0=3,1=0
P 37.8500005 17.79999996 4 P 0 0 ;0=2,1=0
P 37.8500005 22.87999996 4 P 0 0 ;0=2,1=0
P 37.8500005 22.87999996 5 P 0 0 ;0=3,1=0
P 40.67999992 20.33999996 2 P 0 0 ;0=0,1=0
S P 0
OB 43.2467766 45.28782662 I
OS 43.5750081 45.19987658
OS 43.8889648 45.06983112
OS 44.18321872 44.89994068
OS 44.45280162 44.69308308
OS 44.693078 44.45280924
OS 44.89994068 44.18322126
OS 45.06983112 43.8889648
OS 45.19986896 43.57502842
OS 45.28782408 43.24677914
OS 45.33217502 42.90990402
OS 45.33217756 42.7399958
OS 45.33217502 -2.06000096
OS 45.33217502 -2.22990918
OS 45.28782662 -2.56677922
OS 45.19987658 -2.89501072
OS 45.06983112 -3.20896742
OS 44.89994068 -3.50322134
OS 44.69308308 -3.77280424
OS 44.45280924 -4.01308062
OS 44.18322126 -4.2199433
OS 43.8889648 -4.38983374
OS 43.57502842 -4.51987158
OS 43.24677914 -4.6078267
OS 42.90989132 -4.6521751
OS 42.7399958 -4.65217764
OS -2.06000096 -4.65218272
OS -2.22990918 -4.65218272
OS -2.56678938 -4.60783178
OS -2.89502088 -4.51988428
OS -3.20895472 -4.38984644
OS -3.50322388 -4.21994838
OS -3.77279916 -4.0130984
OS -4.0130984 -3.77279916
OS -4.21994584 -3.50322642
OS -4.38984136 -3.2089598
OS -4.51988174 -2.89502088
OS -4.60782924 -2.56679192
OS -4.65218018 -2.22991172
OS -4.65217764 -2.06000604
OS -4.65218526 42.73999834
OS -4.65218526 42.90990656
OS -4.60783432 43.24678422
OS -4.51988682 43.57501318
OS -4.38984644 43.88895464
OS -4.21995092 44.18321872
OS -4.01310094 44.452794
OS -3.77280932 44.69308562
OS -3.50323404 44.89993814
OS -3.20894964 45.06984128
OS -2.89502342 45.19987658
OS -2.56679192 45.28782408
OS -2.22992188 45.33217248
OS -2.07798416 45.33216486
OS -2.07795622 45.33216994
OS 42.74000088 45.33217502
OS 42.90990656 45.33217502
OS 43.2467766 45.28782662
OE
OB 14.42216826 44.87499788 H
OS 14.11783054 44.87499788
OS 13.8193399 44.81562538
OS 13.53816952 44.69915876
OS 13.28511948 44.53007858
OS 13.06992052 44.31487962
OS 12.90084034 44.06182958
OS 12.8147318 43.85394836
OS 12.677267 43.85394836
OS 12.59115846 44.06182958
OS 12.42207828 44.31487962
OS 12.20687932 44.53007858
OS 11.95382928 44.69915876
OS 11.6726589 44.81562538
OS 11.37416826 44.87499788
OS 11.06983054 44.87499788
OS 10.7713399 44.81562538
OS 10.49016952 44.69915876
OS 10.23711948 44.53007858
OS 10.02192052 44.31487962
OS 9.85284034 44.06182958
OS 9.73637372 43.7806592
OS 9.67700122 43.48216856
OS 9.67700122 43.17783084
OS 9.73637372 42.8793402
OS 9.85284034 42.59816982
OS 10.02192052 42.34511978
OS 10.23711948 42.12992082
OS 10.49016952 41.96084064
OS 10.61024548 41.91110236
OS 10.61024548 38.96010496
OS 10.61362876 38.94309458
OS 10.65106836 38.46738306
OS 10.76644786 37.9867922
OS 10.95558896 37.53016624
OS 11.21383076 37.1087523
OS 11.52374124 36.74589298
OS 11.53337292 36.73147848
OS 18.88238794 29.38246346
OS 18.88241842 29.38241774
OS 18.88242604 29.38242536
OS 18.89185706 29.37612362
OS 19.35480762 28.97012494
OS 19.87606642 28.62183252
OS 20.4383259 28.34455596
OS 21.03196708 28.14304252
OS 21.6468325 28.02073898
OS 22.25782696 27.9806908
OS 22.27014088 27.97824224
OS 25.97569608 27.97824478
OS 26.00513722 27.98409948
OS 26.36875092 27.94829056
OS 26.74670546 27.8336375
OS 27.0950309 27.6474555
OS 27.30369698 27.4762087
OS 27.39495918 27.38998078
OS 27.39514714 27.38969884
OS 27.48471516 27.3001359
OS 36.52407986 18.2607712
OS 36.4500033 17.98431252
OS 36.4500033 17.6156874
OS 36.54541078 17.25962258
OS 36.72972334 16.94038268
OS 36.99038322 16.6797228
OS 37.30962312 16.49541024
OS 37.66568794 16.40000276
OS 38.03431306 16.40000276
OS 38.39037788 16.49541024
OS 38.70961778 16.6797228
OS 38.97027766 16.94038268
OS 39.15459022 17.25962258
OS 39.2499977 17.6156874
OS 39.2499977 17.98431252
OS 39.15459022 18.34037734
OS 38.97027766 18.65961724
OS 38.70961778 18.92027712
OS 38.39037788 19.10458968
OS 38.03431306 19.19999716
OS 37.66568794 19.19999716
OS 37.38922926 19.1259206
OS 28.26029908 28.25485078
OS 28.24834076 28.26284162
OS 27.87288812 28.58351154
OS 27.44103732 28.84814906
OS 26.97310582 29.04197138
OS 26.48061506 29.16020838
OS 25.99072272 29.19876304
OS 25.97569608 29.20175262
OS 22.27014088 29.20175008
OS 22.23442086 29.1946457
OS 21.71224766 29.23574036
OS 21.16588858 29.36691104
OS 20.64677608 29.58193474
OS 20.1676889 29.8755181
OS 19.76819008 30.21672392
OS 19.74757544 30.24757476
OS 12.39852232 37.59662788
OS 12.37464378 37.61258416
OS 12.1517537 37.88417366
OS 11.97279038 38.21899138
OS 11.86258486 38.58228758
OS 11.82815008 38.93192874
OS 11.83375332 38.96010496
OS 11.83375332 41.91110236
OS 11.95382928 41.96084064
OS 12.20687932 42.12992082
OS 12.42207828 42.34511978
OS 12.59115846 42.59816982
OS 12.677267 42.80605104
OS 12.8147318 42.80605104
OS 12.90084034 42.59816982
OS 13.06992052 42.34511978
OS 13.28511948 42.12992082
OS 13.53816952 41.96084064
OS 13.65824548 41.91110236
OS 13.65824548 39.24664236
OS 13.65820992 39.24564414
OS 13.65820738 39.24560858
OS 13.67022666 39.12360222
OS 13.70524818 38.76800984
OS 13.84455956 38.3087626
OS 14.0707872 37.88551986
OS 14.37523922 37.5145427
OS 14.37658542 37.51344034
OS 14.37697658 37.5128536
OS 14.3769842 37.51284852
OS 20.31948946 31.57036358
OS 20.31949454 31.57034834
OS 20.31950216 31.57035342
OS 20.34366772 31.55420664
OS 20.64421068 31.29751932
OS 21.00559426 31.0760618
OS 21.39717082 30.91386502
OS 21.80930106 30.81492186
OS 22.20219588 30.7839999
OS 22.2309182 30.77828744
OS 22.2309182 30.77827474
OS 22.23112902 30.77823156
OS 22.23115442 30.77824172
OS 22.35791058 30.77824426
OS 27.86362982 30.7782468
OS 27.8930989 30.78410912
OS 28.32678104 30.7499766
OS 28.7785302 30.64152114
OS 29.2077521 30.4637313
OS 29.60388034 30.22098604
OS 29.86084198 30.00151988
OS 29.95137012 29.91347078
OS 30.04053174 29.82431932
OS 36.52407986 23.3407712
OS 36.4500033 23.06431252
OS 36.4500033 22.6956874
OS 36.54541078 22.33962258
OS 36.72972334 22.02038268
OS 36.99038322 21.7597228
OS 37.30962312 21.57541024
OS 37.66568794 21.48000276
OS 38.03431306 21.48000276
OS 38.39037788 21.57541024
OS 38.70961778 21.7597228
OS 38.97027766 22.02038268
OS 39.15459022 22.33962258
OS 39.2499977 22.6956874
OS 39.2499977 23.06431252
OS 39.15459022 23.42037734
OS 38.97027766 23.73961724
OS 38.70961778 24.00027712
OS 38.39037788 24.18458968
OS 38.03431306 24.27999716
OS 37.66568794 24.27999716
OS 37.38922926 24.2059206
OS 30.8165246 30.77862526
OS 30.79857696 30.7906166
OS 30.40410988 31.13655698
OS 29.95022712 31.43983298
OS 29.46064212 31.68127014
OS 28.94372926 31.85673588
OS 28.4083379 31.963233
OS 27.88477278 31.9975484
OS 27.86362982 32.00175464
OS 22.2311341 32.0017521
OS 22.2104458 31.9976373
OS 21.94170364 32.02410664
OS 21.66272274 32.10873436
OS 21.40561124 32.2461636
OS 21.19649304 32.41778378
OS 21.18464902 32.4355079
OS 15.24212852 38.37800808
OS 15.21664978 38.39503116
OS 15.03748326 38.6285232
OS 14.91418912 38.92618326
OS 14.88848686 39.12141528
OS 14.88175078 39.24562636
OS 14.88175332 39.24563398
OS 14.88165172 39.24613182
OS 14.88175332 39.24663982
OS 14.88175332 41.91110236
OS 15.00182928 41.96084064
OS 15.25487932 42.12992082
OS 15.47007828 42.34511978
OS 15.63915846 42.59816982
OS 15.75562508 42.8793402
OS 15.81499758 43.17783084
OS 15.81499758 43.48216856
OS 15.75562508 43.7806592
OS 15.63915846 44.06182958
OS 15.47007828 44.31487962
OS 15.25487932 44.53007858
OS 15.00182928 44.69915876
OS 14.7206589 44.81562538
OS 14.42216826 44.87499788
OE
OB 2.2419056 44.57499848 H
OS 1.9140932 44.57499848
OS 1.59744664 44.49015486
OS 1.31355084 44.32624866
OS 1.08175044 44.09444826
OS 0.91784424 43.81055246
OS 0.83300062 43.4939059
OS 0.83300062 43.1660935
OS 0.91784424 42.84944694
OS 1.08175044 42.56555114
OS 1.31355084 42.33375074
OS 1.59744664 42.16984454
OS 1.9140932 42.08500092
OS 2.2419056 42.08500092
OS 2.55855216 42.16984454
OS 2.84244796 42.33375074
OS 3.07424836 42.56555114
OS 3.23815456 42.84944694
OS 3.32299818 43.1660935
OS 3.32299818 43.4939059
OS 3.23815456 43.81055246
OS 3.07424836 44.09444826
OS 2.84244796 44.32624866
OS 2.55855216 44.49015486
OS 2.2419056 44.57499848
OE
OB 0.17101566 41.93899918 H
OS 0.12699492 41.93899918
OS 0.12699492 40.76701016
OS 1.29899918 40.76701016
OS 1.29899918 40.81101566
OS 1.2104751 41.141396
OS 1.0394569 41.43760318
OS 0.79760318 41.6794569
OS 0.501396 41.8504751
OS 0.17101566 41.93899918
OE
OB -0.12700508 41.93899918 H
OS -0.17101566 41.93899918
OS -0.501396 41.8504751
OS -0.79760318 41.6794569
OS -1.0394569 41.43760318
OS -1.2104751 41.141396
OS -1.29899918 40.81101566
OS -1.29899918 40.76701016
OS -0.12700508 40.76701016
OS -0.12700508 41.93899918
OE
OB 1.29899918 40.51301016 H
OS 0.12699492 40.51301016
OS 0.12699492 39.34100082
OS 0.17101566 39.34100082
OS 0.501396 39.4295249
OS 0.79760318 39.6005431
OS 1.0394569 39.84239682
OS 1.2104751 40.138604
OS 1.29899918 40.46898434
OS 1.29899918 40.51301016
OE
OB -0.12700508 40.51301016 H
OS -1.29899918 40.51301016
OS -1.29899918 40.46898434
OS -1.2104751 40.138604
OS -1.0394569 39.84239682
OS -0.79760318 39.6005431
OS -0.501396 39.4295249
OS -0.17101566 39.34100082
OS -0.12700508 39.34100082
OS -0.12700508 40.51301016
OE
OB 20.46429994 44.98999892 H
OS 20.01570038 44.98999892
OS 19.57262278 44.9198238
OS 19.14597898 44.78119822
OS 18.74627442 44.57753848
OS 18.38334906 44.31385854
OS 18.06614116 43.99665064
OS 17.80246122 43.63372528
OS 17.59880148 43.23402072
OS 17.4601759 42.80737692
OS 17.39000078 42.36429932
OS 17.39000078 41.91569976
OS 17.4601759 41.47262216
OS 17.59880148 41.04597836
OS 17.80246122 40.6462738
OS 18.06614116 40.28334844
OS 18.38334906 39.96614054
OS 18.74627442 39.7024606
OS 19.14597898 39.49880086
OS 19.57262278 39.36017528
OS 20.01570038 39.29000016
OS 20.46429994 39.29000016
OS 20.90737754 39.36017528
OS 21.33402134 39.49880086
OS 21.7337259 39.7024606
OS 22.09665126 39.96614054
OS 22.41385916 40.28334844
OS 22.6775391 40.6462738
OS 22.88119884 41.04597836
OS 23.01982442 41.47262216
OS 23.08999954 41.91569976
OS 23.08999954 42.36429932
OS 23.01982442 42.80737692
OS 22.88119884 43.23402072
OS 22.6775391 43.63372528
OS 22.41385916 43.99665064
OS 22.09665126 44.31385854
OS 21.7337259 44.57753848
OS 21.33402134 44.78119822
OS 20.90737754 44.9198238
OS 20.46429994 44.98999892
OE
OB 40.79216886 42.18499818 H
OS 40.48783114 42.18499818
OS 40.1893405 42.12562568
OS 39.90817012 42.00915906
OS 39.65512008 41.84007888
OS 39.43992112 41.62487992
OS 39.27084094 41.37182988
OS 39.15437432 41.0906595
OS 39.09500182 40.79216886
OS 39.09500182 40.48783114
OS 39.15437432 40.1893405
OS 39.27084094 39.90817012
OS 39.43992112 39.65512008
OS 39.65512008 39.43992112
OS 39.90817012 39.27084094
OS 40.1893405 39.15437432
OS 40.48783114 39.09500182
OS 40.79216886 39.09500182
OS 41.0906595 39.15437432
OS 41.37182988 39.27084094
OS 41.62487992 39.43992112
OS 41.84007888 39.65512008
OS 42.00915906 39.90817012
OS 42.12562568 40.1893405
OS 42.18499818 40.48783114
OS 42.18499818 40.79216886
OS 42.12562568 41.0906595
OS 42.00915906 41.37182988
OS 41.84007888 41.62487992
OS 41.62487992 41.84007888
OS 41.37182988 42.00915906
OS 41.0906595 42.12562568
OS 40.79216886 42.18499818
OE
OB 36.4019084 42.14999952 H
OS 35.99809412 42.14999952
OS 35.60203954 42.07121888
OS 35.2289618 41.91668528
OS 34.89320428 41.69233978
OS 34.60766256 41.40679806
OS 34.38331706 41.07104054
OS 34.22878346 40.6979628
OS 34.15000282 40.30190822
OS 34.15000282 39.89809394
OS 34.22878346 39.50203936
OS 34.38331706 39.12896162
OS 34.60766256 38.7932041
OS 34.89320428 38.50766238
OS 35.2289618 38.28331688
OS 35.60203954 38.12878328
OS 35.99809412 38.05000264
OS 36.4019084 38.05000264
OS 36.79796298 38.12878328
OS 37.17104072 38.28331688
OS 37.50679824 38.50766238
OS 37.79233996 38.7932041
OS 38.01668546 39.12896162
OS 38.17121906 39.50203936
OS 38.2499997 39.89809394
OS 38.2499997 40.30190822
OS 38.17121906 40.6979628
OS 38.01668546 41.07104054
OS 37.79233996 41.40679806
OS 37.50679824 41.69233978
OS 37.17104072 41.91668528
OS 36.79796298 42.07121888
OS 36.4019084 42.14999952
OE
OB 4.60190596 40.64999744 H
OS 4.19809168 40.64999744
OS 3.8020371 40.5712168
OS 3.42895936 40.4166832
OS 3.09320184 40.1923377
OS 2.80766012 39.90679598
OS 2.58331462 39.57103846
OS 2.42878102 39.19796072
OS 2.35000038 38.80190614
OS 2.35000038 38.39809186
OS 2.42878102 38.00203728
OS 2.58331462 37.62895954
OS 2.80766012 37.29320202
OS 3.09320184 37.0076603
OS 3.42895936 36.7833148
OS 3.8020371 36.6287812
OS 4.19809168 36.55000056
OS 4.60190596 36.55000056
OS 4.99796054 36.6287812
OS 5.37103828 36.7833148
OS 5.7067958 37.0076603
OS 5.99233752 37.29320202
OS 6.21668302 37.62895954
OS 6.37121662 38.00203728
OS 6.44999726 38.39809186
OS 6.44999726 38.80190614
OS 6.37121662 39.19796072
OS 6.21668302 39.57103846
OS 5.99233752 39.90679598
OS 5.7067958 40.1923377
OS 5.37103828 40.4166832
OS 4.99796054 40.5712168
OS 4.60190596 40.64999744
OE
OB 4.9748186 34.13999776 H
OS 4.6851824 34.13999776
OS 4.40541664 34.06503474
OS 4.15458656 33.92021664
OS 3.94978382 33.7154139
OS 3.80496572 33.46458382
OS 3.7300027 33.18481806
OS 3.7300027 32.89518186
OS 3.80496572 32.6154161
OS 3.94978382 32.36458602
OS 4.15458656 32.15978328
OS 4.40541664 32.01496518
OS 4.6851824 31.94000216
OS 4.9748186 31.94000216
OS 5.25458436 32.01496518
OS 5.50541444 32.15978328
OS 5.71021718 32.36458602
OS 5.85503528 32.6154161
OS 5.9299983 32.89518186
OS 5.9299983 33.18481806
OS 5.85503528 33.46458382
OS 5.71021718 33.7154139
OS 5.50541444 33.92021664
OS 5.25458436 34.06503474
OS 4.9748186 34.13999776
OE
OB 38.03431306 34.43999716 H
OS 37.66568794 34.43999716
OS 37.30962312 34.34458968
OS 36.99038322 34.16027712
OS 36.72972334 33.89961724
OS 36.54541078 33.58037734
OS 36.4500033 33.22431252
OS 36.4500033 32.8556874
OS 36.54541078 32.49962258
OS 36.72972334 32.18038268
OS 36.99038322 31.9197228
OS 37.30962312 31.73541024
OS 37.66568794 31.64000276
OS 38.03431306 31.64000276
OS 38.39037788 31.73541024
OS 38.70961778 31.9197228
OS 38.97027766 32.18038268
OS 39.15459022 32.49962258
OS 39.2499977 32.8556874
OS 39.2499977 33.22431252
OS 39.15459022 33.58037734
OS 38.97027766 33.89961724
OS 38.70961778 34.16027712
OS 38.39037788 34.34458968
OS 38.03431306 34.43999716
OE
OB 40.85101558 21.63899914 H
OS 40.80699484 21.63899914
OS 40.80699484 20.46699996
OS 41.9789991 20.46699996
OS 41.9789991 20.51101562
OS 41.89047502 20.84139596
OS 41.71945682 21.13760314
OS 41.4776031 21.37945686
OS 41.18139592 21.55047506
OS 40.85101558 21.63899914
OE
OB 40.55299484 21.63899914 H
OS 40.50898426 21.63899914
OS 40.17860392 21.55047506
OS 39.88239674 21.37945686
OS 39.64054302 21.13760314
OS 39.46952482 20.84139596
OS 39.38100074 20.51101562
OS 39.38100074 20.46699996
OS 40.55299484 20.46699996
OS 40.55299484 21.63899914
OE
OB 41.9789991 20.21299996 H
OS 40.80699484 20.21299996
OS 40.80699484 19.04100078
OS 40.85101558 19.04100078
OS 41.18139592 19.12952486
OS 41.4776031 19.30054306
OS 41.71945682 19.54239678
OS 41.89047502 19.83860396
OS 41.9789991 20.1689843
OS 41.9789991 20.21299996
OE
OB 40.55299484 20.21299996 H
OS 39.38100074 20.21299996
OS 39.38100074 20.1689843
OS 39.46952482 19.83860396
OS 39.64054302 19.54239678
OS 39.88239674 19.30054306
OS 40.17860392 19.12952486
OS 40.50898426 19.04100078
OS 40.55299484 19.04100078
OS 40.55299484 20.21299996
OE
OB 4.9748186 18.89999776 H
OS 4.6851824 18.89999776
OS 4.40541664 18.82503474
OS 4.15458656 18.68021664
OS 3.94978382 18.4754139
OS 3.80496572 18.22458382
OS 3.7300027 17.94481806
OS 3.7300027 17.65518186
OS 3.80496572 17.3754161
OS 3.94978382 17.12458602
OS 4.15458656 16.91978328
OS 4.40541664 16.77496518
OS 4.6851824 16.70000216
OS 4.9748186 16.70000216
OS 5.25458436 16.77496518
OS 5.50541444 16.91978328
OS 5.71021718 17.12458602
OS 5.85503528 17.3754161
OS 5.9299983 17.65518186
OS 5.9299983 17.94481806
OS 5.85503528 18.22458382
OS 5.71021718 18.4754139
OS 5.50541444 18.68021664
OS 5.25458436 18.82503474
OS 4.9748186 18.89999776
OE
OB 5.2899056 44.57499848 H
OS 4.9620932 44.57499848
OS 4.64544664 44.49015486
OS 4.36155084 44.32624866
OS 4.12975044 44.09444826
OS 3.96584424 43.81055246
OS 3.88100062 43.4939059
OS 3.88100062 43.1660935
OS 3.96584424 42.84944694
OS 4.12975044 42.56555114
OS 4.36155084 42.33375074
OS 4.64544664 42.16984454
OS 4.9620932 42.08500092
OS 5.2899056 42.08500092
OS 5.60655216 42.16984454
OS 5.76316094 42.26026092
OS 6.40075682 41.62266504
OS 6.49055344 41.53286334
OS 6.56646642 41.43729838
OS 6.65705552 41.31924172
OS 6.76080182 41.06877994
OS 6.79536614 40.80623792
OS 6.79412408 40.79999968
OS 6.79412408 39.85210216
OS 6.79122086 39.85210216
OS 6.82629318 39.40645408
OS 6.93064908 38.97178134
OS 7.10171808 38.55878242
OS 7.33528886 38.17763002
OS 7.62560832 37.83770944
OS 7.62766064 37.83976176
OS 8.45930998 37.00811496
OS 8.54731082 36.92010904
OS 8.62719128 36.82619508
OS 8.7813007 36.63841288
OS 8.95402324 36.31527154
OS 9.06038574 35.96464232
OS 9.09557744 35.6073202
OS 9.09412202 35.59999992
OS 9.09412202 18.342102
OS 9.09676616 18.3288051
OS 9.05507206 17.90547346
OS 8.92771392 17.4856267
OS 8.72089188 17.09869326
OS 8.52134694 16.85554668
OS 8.4397596 16.76233884
OS 8.43975452 16.76232868
OS 5.3610129 13.68358706
OS 5.25458436 13.74503474
OS 4.9748186 13.81999776
OS 4.6851824 13.81999776
OS 4.40541664 13.74503474
OS 4.15458656 13.60021664
OS 3.94978382 13.3954139
OS 3.80496572 13.14458382
OS 3.7300027 12.86481806
OS 3.7300027 12.57518186
OS 3.80496572 12.2954161
OS 3.94978382 12.04458602
OS 4.15458656 11.83978328
OS 4.40541664 11.69496518
OS 4.6851824 11.62000216
OS 4.9748186 11.62000216
OS 5.25458436 11.69496518
OS 5.50541444 11.83978328
OS 5.71021718 12.04458602
OS 5.85503528 12.2954161
OS 5.9299983 12.57518186
OS 5.9299983 12.86481806
OS 5.85503528 13.14458382
OS 5.7935876 13.25101236
OS 8.78253514 16.2399599
OS 8.87439424 16.32770928
OS 8.8743917 16.32771182
OS 9.16471116 16.66762986
OS 9.39828194 17.04878226
OS 9.56935094 17.46178118
OS 9.67370684 17.89645392
OS 9.70877916 18.342102
OS 9.70587594 18.342102
OS 9.70587594 35.59999992
OS 9.71196432 35.59999992
OS 9.66421994 36.0847513
OS 9.52282322 36.55087686
OS 9.29320722 36.98045944
OS 8.9841959 37.35698904
OS 8.98419844 37.35699158
OS 8.89008636 37.44248798
OS 8.06023788 38.272339
OS 8.04896536 38.2798701
OS 7.77910814 38.60869342
OS 7.5722861 38.99562686
OS 7.44492796 39.41547362
OS 7.40323386 39.83880526
OS 7.405878 39.85210216
OS 7.405878 40.79999968
OS 7.40794556 40.79999968
OS 7.3762362 41.12194722
OS 7.28232732 41.43151988
OS 7.12982826 41.71682538
OS 6.92460134 41.966896
OS 6.92460388 41.96689854
OS 6.8333366 42.05523974
OS 6.19573818 42.69283816
OS 6.28615456 42.84944694
OS 6.37099818 43.1660935
OS 6.37099818 43.4939059
OS 6.28615456 43.81055246
OS 6.12224836 44.09444826
OS 5.89044796 44.32624866
OS 5.60655216 44.49015486
OS 5.2899056 44.57499848
OE
OB 38.00192806 13.87399816 H
OS 37.97699034 13.87399816
OS 37.97699034 12.8469898
OS 39.0039987 12.8469898
OS 39.0039987 12.87192752
OS 38.92535522 13.16542706
OS 38.77342766 13.42857106
OS 38.5585716 13.64342712
OS 38.2954276 13.79535468
OS 38.00192806 13.87399816
OE
OB 37.72299034 13.87399816 H
OS 37.69807294 13.87399816
OS 37.4045734 13.79535468
OS 37.1414294 13.64342712
OS 36.92657334 13.42857106
OS 36.77464578 13.16542706
OS 36.6960023 12.87192752
OS 36.6960023 12.8469898
OS 37.72299034 12.8469898
OS 37.72299034 13.87399816
OE
OB 39.0039987 12.5929898 H
OS 37.97699034 12.5929898
OS 37.97699034 11.56600176
OS 38.00192806 11.56600176
OS 38.2954276 11.64464524
OS 38.5585716 11.7965728
OS 38.77342766 12.01142886
OS 38.92535522 12.27457286
OS 39.0039987 12.5680724
OS 39.0039987 12.5929898
OE
OB 37.72299034 12.5929898 H
OS 36.6960023 12.5929898
OS 36.6960023 12.5680724
OS 36.77464578 12.27457286
OS 36.92657334 12.01142886
OS 37.1414294 11.7965728
OS 37.4045734 11.64464524
OS 37.69807294 11.56600176
OS 37.72299034 11.56600176
OS 37.72299034 12.5929898
OE
OB 8.3379056 44.57499848 H
OS 8.0100932 44.57499848
OS 7.69344664 44.49015486
OS 7.40955084 44.32624866
OS 7.17775044 44.09444826
OS 7.01384424 43.81055246
OS 6.92900062 43.4939059
OS 6.92900062 43.1660935
OS 7.01384424 42.84944694
OS 7.17775044 42.56555114
OS 7.40955084 42.33375074
OS 7.69344664 42.16984454
OS 7.86812244 42.12303996
OS 7.86812244 40.28310206
OS 7.86521922 40.28310206
OS 7.90029154 39.83745398
OS 8.00464744 39.40278124
OS 8.17571644 38.98978232
OS 8.40928722 38.60862992
OS 8.69960668 38.26870934
OS 8.701659 38.27076166
OS 9.3343857 37.63803242
OS 9.42310028 37.5493153
OS 9.42325268 37.54916544
OS 9.42369718 37.54871586
OS 9.4241239 37.54830438
OS 9.42415438 37.54825612
OS 9.42419756 37.54823326
OS 9.50707268 37.4555766
OS 9.74078316 37.17079942
OS 9.97306616 36.73622828
OS 10.11610626 36.26468998
OS 10.15226062 35.89761426
OS 10.15914148 35.77346414
OS 10.15912116 35.77336254
OS 10.15912878 35.77332952
OS 10.1591237 35.77330158
OS 10.1591237 14.32710368
OS 10.16176784 14.31380678
OS 10.12007374 13.89047514
OS 9.9927156 13.47062838
OS 9.78589356 13.08369494
OS 9.58762878 12.84210792
OS 9.50475874 12.74734306
OS 9.50475874 12.74734052
OS 9.41667408 12.65924824
OS 5.3610129 8.60358706
OS 5.25458436 8.66503474
OS 4.9748186 8.73999776
OS 4.6851824 8.73999776
OS 4.40541664 8.66503474
OS 4.15458656 8.52021664
OS 3.94978382 8.3154139
OS 3.80496572 8.06458382
OS 3.7300027 7.78481806
OS 3.7300027 7.49518186
OS 3.80496572 7.2154161
OS 3.94978382 6.96458602
OS 4.15458656 6.75978328
OS 4.40541664 6.61496518
OS 4.6851824 6.54000216
OS 4.9748186 6.54000216
OS 5.25458436 6.61496518
OS 5.50541444 6.75978328
OS 5.71021718 6.96458602
OS 5.85503528 7.2154161
OS 5.9299983 7.49518186
OS 5.9299983 7.78481806
OS 5.85503528 8.06458382
OS 5.7935876 8.17101236
OS 9.84753682 12.22496158
OS 9.93939592 12.31271096
OS 9.93939338 12.3127135
OS 10.22971284 12.65263154
OS 10.46328362 13.03378394
OS 10.63435262 13.44678286
OS 10.73870852 13.8814556
OS 10.77378084 14.32710368
OS 10.77087762 14.32710368
OS 10.77087762 35.64774176
OS 10.774553 35.77325586
OS 10.77463428 35.77430742
OS 10.765028 35.89628584
OS 10.73616852 36.2629831
OS 10.62173644 36.73962934
OS 10.43414982 37.19250372
OS 10.17802892 37.61045818
OS 9.9404932 37.88857294
OS 9.85967802 37.98320064
OS 9.85933258 37.98349528
OS 9.76689944 38.07067062
OS 9.22403794 38.61353212
OS 9.13424386 38.70333382
OS 9.05265144 38.79654674
OS 8.8531065 39.03969332
OS 8.64628446 39.42662676
OS 8.51892632 39.84647352
OS 8.47723222 40.26980516
OS 8.47987636 40.28310206
OS 8.47987636 42.12303996
OS 8.65455216 42.16984454
OS 8.93844796 42.33375074
OS 9.17024836 42.56555114
OS 9.33415456 42.84944694
OS 9.41899818 43.1660935
OS 9.41899818 43.4939059
OS 9.33415456 43.81055246
OS 9.17024836 44.09444826
OS 8.93844796 44.32624866
OS 8.65455216 44.49015486
OS 8.3379056 44.57499848
OE
OB 37.9948186 8.73999776 H
OS 37.7051824 8.73999776
OS 37.42541664 8.66503474
OS 37.17458656 8.52021664
OS 36.96978382 8.3154139
OS 36.82496572 8.06458382
OS 36.7500027 7.78481806
OS 36.7500027 7.49518186
OS 36.82496572 7.2154161
OS 36.96978382 6.96458602
OS 37.17458656 6.75978328
OS 37.42541664 6.61496518
OS 37.7051824 6.54000216
OS 37.9948186 6.54000216
OS 38.27458436 6.61496518
OS 38.52541444 6.75978328
OS 38.73021718 6.96458602
OS 38.87503528 7.2154161
OS 38.9499983 7.49518186
OS 38.9499983 7.78481806
OS 38.87503528 8.06458382
OS 38.73021718 8.3154139
OS 38.52541444 8.52021664
OS 38.27458436 8.66503474
OS 37.9948186 8.73999776
OE
OB 4.60190596 4.04999952 H
OS 4.19809168 4.04999952
OS 3.8020371 3.97121888
OS 3.42895936 3.81668528
OS 3.09320184 3.59233978
OS 2.80766012 3.30679806
OS 2.58331462 2.97104054
OS 2.42878102 2.5979628
OS 2.35000038 2.20190822
OS 2.35000038 1.79809394
OS 2.42878102 1.40203936
OS 2.58331462 1.02896162
OS 2.80766012 0.6932041
OS 3.09320184 0.40766238
OS 3.42895936 0.18331688
OS 3.8020371 0.02878328
OS 4.19809168 -0.04999736
OS 4.60190596 -0.04999736
OS 4.99796054 0.02878328
OS 5.37103828 0.18331688
OS 5.7067958 0.40766238
OS 5.99233752 0.6932041
OS 6.21668302 1.02896162
OS 6.37121662 1.40203936
OS 6.44999726 1.79809394
OS 6.44999726 2.20190822
OS 6.37121662 2.5979628
OS 6.21668302 2.97104054
OS 5.99233752 3.30679806
OS 5.7067958 3.59233978
OS 5.37103828 3.81668528
OS 4.99796054 3.97121888
OS 4.60190596 4.04999952
OE
OB 40.8039062 1.24499878 H
OS 40.4760938 1.24499878
OS 40.15944724 1.16015516
OS 39.87555144 0.99624896
OS 39.64375104 0.76444856
OS 39.47984484 0.48055276
OS 39.39500122 0.1639062
OS 39.39500122 -0.1639062
OS 39.47984484 -0.48055276
OS 39.64375104 -0.76444856
OS 39.87555144 -0.99624896
OS 40.15944724 -1.16015516
OS 40.4760938 -1.24499878
OS 40.8039062 -1.24499878
OS 41.12055276 -1.16015516
OS 41.40444856 -0.99624896
OS 41.63624896 -0.76444856
OS 41.80015516 -0.48055276
OS 41.88499878 -0.1639062
OS 41.88499878 0.1639062
OS 41.80015516 0.48055276
OS 41.63624896 0.76444856
OS 41.40444856 0.99624896
OS 41.12055276 1.16015516
OS 40.8039062 1.24499878
OE
OB 0.1639062 1.24499878 H
OS -0.1639062 1.24499878
OS -0.48055276 1.16015516
OS -0.76444856 0.99624896
OS -0.99624896 0.76444856
OS -1.16015516 0.48055276
OS -1.24499878 0.1639062
OS -1.24499878 -0.1639062
OS -1.16015516 -0.48055276
OS -0.99624896 -0.76444856
OS -0.76444856 -0.99624896
OS -0.48055276 -1.16015516
OS -0.1639062 -1.24499878
OS 0.1639062 -1.24499878
OS 0.48055276 -1.16015516
OS 0.76444856 -0.99624896
OS 0.99624896 -0.76444856
OS 1.16015516 -0.48055276
OS 1.24499878 -0.1639062
OS 1.24499878 0.1639062
OS 1.16015516 0.48055276
OS 0.99624896 0.76444856
OS 0.76444856 0.99624896
OS 0.48055276 1.16015516
OS 0.1639062 1.24499878
OE
OB 35.70190726 1.0499979 H
OS 35.29809298 1.0499979
OS 34.9020384 0.97121726
OS 34.52896066 0.81668366
OS 34.19320314 0.59233816
OS 33.90766142 0.30679644
OS 33.68331592 -0.02896108
OS 33.52878232 -0.40203882
OS 33.45000168 -0.7980934
OS 33.45000168 -1.20190768
OS 33.52878232 -1.59796226
OS 33.68331592 -1.97104
OS 33.90766142 -2.30679752
OS 34.19320314 -2.59233924
OS 34.52896066 -2.81668474
OS 34.9020384 -2.97121834
OS 35.29809298 -3.04999898
OS 35.70190726 -3.04999898
OS 36.09796184 -2.97121834
OS 36.47103958 -2.81668474
OS 36.8067971 -2.59233924
OS 37.09233882 -2.30679752
OS 37.31668432 -1.97104
OS 37.47121792 -1.59796226
OS 37.54999856 -1.20190768
OS 37.54999856 -0.7980934
OS 37.47121792 -0.40203882
OS 37.31668432 -0.02896108
OS 37.09233882 0.30679644
OS 36.8067971 0.59233816
OS 36.47103958 0.81668366
OS 36.09796184 0.97121726
OS 35.70190726 1.0499979
OE
OB 20.66429954 1.58999936 H
OS 20.21569998 1.58999936
OS 19.77262238 1.51982424
OS 19.34597858 1.38119866
OS 18.94627402 1.17753892
OS 18.58334866 0.91385898
OS 18.26614076 0.59665108
OS 18.00246082 0.23372572
OS 17.79880108 -0.16597884
OS 17.6601755 -0.59262264
OS 17.59000038 -1.03570024
OS 17.59000038 -1.4842998
OS 17.6601755 -1.9273774
OS 17.79880108 -2.3540212
OS 18.00246082 -2.75372576
OS 18.26614076 -3.11665112
OS 18.58334866 -3.43385902
OS 18.94627402 -3.69753896
OS 19.34597858 -3.9011987
OS 19.77262238 -4.03982428
OS 20.21569998 -4.1099994
OS 20.66429954 -4.1099994
OS 21.10737714 -4.03982428
OS 21.53402094 -3.9011987
OS 21.9337255 -3.69753896
OS 22.29665086 -3.43385902
OS 22.61385876 -3.11665112
OS 22.8775387 -2.75372576
OS 23.08119844 -2.3540212
OS 23.21982402 -1.9273774
OS 23.28999914 -1.4842998
OS 23.28999914 -1.03570024
OS 23.21982402 -0.59262264
OS 23.08119844 -0.16597884
OS 22.8775387 0.23372572
OS 22.61385876 0.59665108
OS 22.29665086 0.91385898
OS 21.9337255 1.17753892
OS 21.53402094 1.38119866
OS 21.10737714 1.51982424
OS 20.66429954 1.58999936
OE
SE
S P 0
OB -2.97936666 -38.48662356 I
OS -2.97197018 -38.48754812
OS -2.96272458 -38.48939724
OS -2.95255442 -38.49124636
OS -2.94053514 -38.49402004
OS -2.92944042 -38.49679372
OS -2.91649658 -38.50141652
OS -2.9044773 -38.50603932
OS -2.89153346 -38.51251124
OS -2.87858962 -38.51990772
OS -2.86564578 -38.52822876
OS -2.8536265 -38.53839892
OS -2.84253178 -38.54949364
OS -2.84160722 -38.5504182
OS -2.8397581 -38.55226732
OS -2.83698442 -38.55596556
OS -2.83328618 -38.56151292
OS -2.82866338 -38.56798484
OS -2.82404058 -38.57538132
OS -2.81849322 -38.58462692
OS -2.81294586 -38.59572164
OS -2.8073985 -38.60774092
OS -2.80185114 -38.62068476
OS -2.79722834 -38.63547772
OS -2.79260554 -38.65119524
OS -2.7889073 -38.66876188
OS -2.78613362 -38.68725308
OS -2.7842845 -38.70666884
OS -2.78335994 -38.72793372
OS -2.78335994 -38.72885828
OS -2.78335994 -38.73255652
OS -2.78335994 -38.73902844
OS -2.7842845 -38.74827404
OS -3.1309945 -38.74827404
OS -3.1309945 -38.7491986
OS -3.1309945 -38.75197228
OS -3.13006994 -38.75567052
OS -3.13006994 -38.76121788
OS -3.12914538 -38.7676898
OS -3.12729626 -38.77508628
OS -3.12452258 -38.79172836
OS -3.11897522 -38.81021956
OS -3.11157874 -38.83055988
OS -3.10140858 -38.84905108
OS -3.08846474 -38.86569316
OS -3.08754018 -38.86569316
OS -3.08661562 -38.86754228
OS -3.08106826 -38.87216508
OS -3.07274722 -38.878637
OS -3.0616525 -38.88510892
OS -3.04685954 -38.8925054
OS -3.03021746 -38.89897732
OS -3.01172626 -38.90360012
OS -3.0015561 -38.90452468
OS -2.99046138 -38.90544924
OS -2.9830649 -38.90544924
OS -2.97474386 -38.90452468
OS -2.9645737 -38.90267556
OS -2.95347898 -38.89990188
OS -2.94053514 -38.89620364
OS -2.92851586 -38.89065628
OS -2.91649658 -38.8832598
OS -2.91557202 -38.88233524
OS -2.91094922 -38.878637
OS -2.90540186 -38.87308964
OS -2.89892994 -38.86569316
OS -2.89153346 -38.855523
OS -2.88321242 -38.84257916
OS -2.87489138 -38.8277862
OS -2.8674949 -38.81021956
OS -2.78613362 -38.82038972
OS -2.78613362 -38.82131428
OS -2.78705818 -38.8231634
OS -2.78798274 -38.82686164
OS -2.78983186 -38.832409
OS -2.79260554 -38.83795636
OS -2.79537922 -38.84535284
OS -2.8027757 -38.86107036
OS -2.8120213 -38.878637
OS -2.82496514 -38.8971282
OS -2.8397581 -38.91469484
OS -2.8582493 -38.93133692
OS -2.85917386 -38.93133692
OS -2.86102298 -38.93318604
OS -2.86379666 -38.93503516
OS -2.8674949 -38.93780884
OS -2.87304226 -38.94058252
OS -2.87858962 -38.9433562
OS -2.8859861 -38.94705444
OS -2.89430714 -38.95075268
OS -2.90355274 -38.95445092
OS -2.91279834 -38.95814916
OS -2.93591234 -38.96369652
OS -2.96180002 -38.96831932
OS -2.99046138 -38.97016844
OS -3.00063154 -38.97016844
OS -3.00710346 -38.96924388
OS -3.0154245 -38.96831932
OS -3.02559466 -38.9664702
OS -3.03668938 -38.96462108
OS -3.04870866 -38.96277196
OS -3.07459634 -38.95537548
OS -3.08846474 -38.94982812
OS -3.10140858 -38.94428076
OS -3.11527698 -38.93688428
OS -3.12822082 -38.92856324
OS -3.1402401 -38.91931764
OS -3.15225938 -38.90822292
OS -3.15318394 -38.90729836
OS -3.15503306 -38.90544924
OS -3.15780674 -38.901751
OS -3.16150498 -38.89620364
OS -3.16612778 -38.88973172
OS -3.17075058 -38.88233524
OS -3.17629794 -38.87308964
OS -3.1818453 -38.86291948
OS -3.18739266 -38.8509002
OS -3.19294002 -38.83795636
OS -3.19756282 -38.8231634
OS -3.20218562 -38.80744588
OS -3.20588386 -38.7908038
OS -3.20865754 -38.7723126
OS -3.21050666 -38.75289684
OS -3.21143122 -38.73255652
OS -3.21143122 -38.73163196
OS -3.21143122 -38.72700916
OS -3.21143122 -38.7214618
OS -3.21050666 -38.71314076
OS -3.2095821 -38.7029706
OS -3.20865754 -38.69187588
OS -3.20680842 -38.67893204
OS -3.20403474 -38.6659882
OS -3.19663826 -38.63640228
OS -3.19201546 -38.62160932
OS -3.1864681 -38.6058918
OS -3.17907162 -38.59109884
OS -3.17075058 -38.57723044
OS -3.16150498 -38.56336204
OS -3.15133482 -38.5504182
OS -3.15041026 -38.54949364
OS -3.14856114 -38.54764452
OS -3.1448629 -38.54487084
OS -3.1402401 -38.54024804
OS -3.13469274 -38.53562524
OS -3.12729626 -38.53007788
OS -3.11897522 -38.52360596
OS -3.10880506 -38.5180586
OS -3.0986349 -38.51158668
OS -3.08661562 -38.50603932
OS -3.07367178 -38.50049196
OS -3.05980338 -38.49586916
OS -3.04501042 -38.49124636
OS -3.0292929 -38.48847268
OS -3.01265082 -38.48662356
OS -2.99508418 -38.485699
OS -2.98583858 -38.485699
OS -2.97936666 -38.48662356
OE
OB -2.5022937 -38.48662356 I
OS -2.49212354 -38.48847268
OS -2.48010426 -38.49217092
OS -2.46716042 -38.49679372
OS -2.45236746 -38.50326564
OS -2.43664994 -38.51158668
OS -2.4653113 -38.58370236
OS -2.46623586 -38.5827778
OS -2.4699341 -38.58092868
OS -2.47548146 -38.578155
OS -2.48287794 -38.57538132
OS -2.49119898 -38.57260764
OS -2.50136914 -38.56983396
OS -2.5115393 -38.56798484
OS -2.52170946 -38.56706028
OS -2.52633226 -38.56706028
OS -2.53095506 -38.56798484
OS -2.53742698 -38.5689094
OS -2.5438989 -38.57075852
OS -2.55221994 -38.5735322
OS -2.56054098 -38.57723044
OS -2.56793746 -38.5827778
OS -2.56886202 -38.58370236
OS -2.5716357 -38.58555148
OS -2.57440938 -38.58924972
OS -2.57903218 -38.59387252
OS -2.58365498 -38.60034444
OS -2.58827778 -38.60774092
OS -2.59290058 -38.61606196
OS -2.59659882 -38.62623212
OS -2.59752338 -38.62808124
OS -2.59844794 -38.6336286
OS -2.60029706 -38.64194964
OS -2.60307074 -38.65304436
OS -2.60584442 -38.66691276
OS -2.60769354 -38.68263028
OS -2.6086181 -38.69927236
OS -2.60954266 -38.71776356
OS -2.60954266 -38.95999828
OS -2.68813026 -38.95999828
OS -2.68813026 -38.49586916
OS -2.61693914 -38.49586916
OS -2.61693914 -38.56613572
OS -2.61601458 -38.56521116
OS -2.61231634 -38.55873924
OS -2.60769354 -38.5504182
OS -2.60029706 -38.54024804
OS -2.59290058 -38.53007788
OS -2.58457954 -38.51898316
OS -2.5762585 -38.50973756
OS -2.56793746 -38.50234108
OS -2.5670129 -38.50141652
OS -2.56423922 -38.4995674
OS -2.55869186 -38.49679372
OS -2.5531445 -38.49402004
OS -2.54574802 -38.49124636
OS -2.53650242 -38.48847268
OS -2.52725682 -38.48662356
OS -2.51708666 -38.485699
OS -2.51061474 -38.485699
OS -2.5022937 -38.48662356
OE
OB -3.4499677 -38.48662356 I
OS -3.43979754 -38.48754812
OS -3.42777826 -38.48939724
OS -3.41483442 -38.49217092
OS -3.40096602 -38.49586916
OS -3.38802218 -38.50141652
OS -3.38617306 -38.50234108
OS -3.38247482 -38.5041902
OS -3.3760029 -38.50696388
OS -3.36860642 -38.51158668
OS -3.35936082 -38.51713404
OS -3.35103978 -38.52453052
OS -3.34271874 -38.531927
OS -3.33532226 -38.5411726
OS -3.3343977 -38.54209716
OS -3.33254858 -38.5457954
OS -3.3297749 -38.5504182
OS -3.3251521 -38.55689012
OS -3.32145386 -38.56613572
OS -3.31775562 -38.57538132
OS -3.31313282 -38.58647604
OS -3.31035914 -38.59849532
OS -3.31035914 -38.59941988
OS -3.30943458 -38.60311812
OS -3.30851002 -38.60866548
OS -3.30758546 -38.61606196
OS -3.30758546 -38.62715668
OS -3.3066609 -38.64010052
OS -3.30573634 -38.65581804
OS -3.30573634 -38.6752338
OS -3.30573634 -38.95999828
OS -3.38432394 -38.95999828
OS -3.38432394 -38.67893204
OS -3.38432394 -38.67800748
OS -3.38432394 -38.67708292
OS -3.38432394 -38.670611
OS -3.38432394 -38.66228996
OS -3.3852485 -38.6521198
OS -3.38617306 -38.64010052
OS -3.38802218 -38.62808124
OS -3.39079586 -38.61698652
OS -3.39356954 -38.60681636
OS -3.39356954 -38.6058918
OS -3.39541866 -38.60311812
OS -3.39819234 -38.59849532
OS -3.40096602 -38.59294796
OS -3.40558882 -38.5874006
OS -3.41113618 -38.58092868
OS -3.41853266 -38.57445676
OS -3.4268537 -38.5689094
OS -3.42777826 -38.56798484
OS -3.43055194 -38.56613572
OS -3.4360993 -38.5642866
OS -3.44257122 -38.56151292
OS -3.4499677 -38.55873924
OS -3.4592133 -38.55596556
OS -3.47030802 -38.555041
OS -3.48140274 -38.55411644
OS -3.48602554 -38.55411644
OS -3.48972378 -38.555041
OS -3.49896938 -38.55596556
OS -3.51098866 -38.55781468
OS -3.5239325 -38.56243748
OS -3.53872546 -38.56798484
OS -3.55351842 -38.57538132
OS -3.56738682 -38.58647604
OS -3.56923594 -38.58832516
OS -3.57293418 -38.59294796
OS -3.57570786 -38.5966462
OS -3.57848154 -38.601269
OS -3.58217978 -38.60681636
OS -3.58495346 -38.61328828
OS -3.5886517 -38.62068476
OS -3.59234994 -38.62993036
OS -3.59512362 -38.64010052
OS -3.5978973 -38.65119524
OS -3.59974642 -38.66321452
OS -3.60159554 -38.67615836
OS -3.60344466 -38.69187588
OS -3.60344466 -38.7075934
OS -3.60344466 -38.95999828
OS -3.68203226 -38.95999828
OS -3.68203226 -38.49586916
OS -3.6117657 -38.49586916
OS -3.6117657 -38.56243748
OS -3.61084114 -38.56151292
OS -3.60899202 -38.55873924
OS -3.60621834 -38.555041
OS -3.6025201 -38.5504182
OS -3.59697274 -38.54487084
OS -3.59050082 -38.53839892
OS -3.58310434 -38.53100244
OS -3.57385874 -38.52360596
OS -3.56461314 -38.51713404
OS -3.55351842 -38.50973756
OS -3.54149914 -38.50326564
OS -3.5285553 -38.49771828
OS -3.51376234 -38.49309548
OS -3.49896938 -38.48939724
OS -3.4823273 -38.48662356
OS -3.46476066 -38.485699
OS -3.45736418 -38.485699
OS -3.4499677 -38.48662356
OE
OB -0.0660781 -38.48662356 I
OS -0.05590794 -38.48847268
OS -0.04388866 -38.49217092
OS -0.03094482 -38.49679372
OS -0.01615186 -38.50326564
OS -0.00043434 -38.51158668
OS -0.0290957 -38.58370236
OS -0.03002026 -38.5827778
OS -0.0337185 -38.58092868
OS -0.03926586 -38.578155
OS -0.04666234 -38.57538132
OS -0.05498338 -38.57260764
OS -0.06515354 -38.56983396
OS -0.0753237 -38.56798484
OS -0.08549386 -38.56706028
OS -0.09011666 -38.56706028
OS -0.09473946 -38.56798484
OS -0.10121138 -38.5689094
OS -0.1076833 -38.57075852
OS -0.11600434 -38.5735322
OS -0.12432538 -38.57723044
OS -0.13172186 -38.5827778
OS -0.13264642 -38.58370236
OS -0.1354201 -38.58555148
OS -0.13819378 -38.58924972
OS -0.14281658 -38.59387252
OS -0.14743938 -38.60034444
OS -0.15206218 -38.60774092
OS -0.15668498 -38.61606196
OS -0.16038322 -38.62623212
OS -0.16130778 -38.62808124
OS -0.16223234 -38.6336286
OS -0.16408146 -38.64194964
OS -0.16685514 -38.65304436
OS -0.16962882 -38.66691276
OS -0.17147794 -38.68263028
OS -0.1724025 -38.69927236
OS -0.17332706 -38.71776356
OS -0.17332706 -38.95999828
OS -0.25191466 -38.95999828
OS -0.25191466 -38.49586916
OS -0.18072354 -38.49586916
OS -0.18072354 -38.56613572
OS -0.17979898 -38.56521116
OS -0.17610074 -38.55873924
OS -0.17147794 -38.5504182
OS -0.16408146 -38.54024804
OS -0.15668498 -38.53007788
OS -0.14836394 -38.51898316
OS -0.1400429 -38.50973756
OS -0.13172186 -38.50234108
OS -0.1307973 -38.50141652
OS -0.12802362 -38.4995674
OS -0.12247626 -38.49679372
OS -0.1169289 -38.49402004
OS -0.10953242 -38.49124636
OS -0.10028682 -38.48847268
OS -0.09104122 -38.48662356
OS -0.08087106 -38.485699
OS -0.07439914 -38.485699
OS -0.0660781 -38.48662356
OE
OB -1.94201034 -39.1375138 I
OS -2.46253762 -39.1375138
OS -2.46253762 -39.08111564
OS -1.94201034 -39.08111564
OS -1.94201034 -39.1375138
OE
OB -1.81534562 -38.95999828 I
OS -1.89393322 -38.95999828
OS -1.89393322 -38.32020276
OS -1.81534562 -38.32020276
OS -1.81534562 -38.95999828
OE
OB -0.99248722 -38.96739476 I
OS -0.99248722 -38.96831932
OS -0.99341178 -38.971093
OS -0.9952609 -38.97479124
OS -0.99711002 -38.97941404
OS -0.9998837 -38.98588596
OS -1.00265738 -38.99328244
OS -1.0091293 -39.00899996
OS -1.01560122 -39.0265666
OS -1.0229977 -39.04413324
OS -1.03039418 -39.05985076
OS -1.03409242 -39.06632268
OS -1.0368661 -39.0727946
OS -1.03779066 -39.07464372
OS -1.04056434 -39.07926652
OS -1.04518714 -39.08573844
OS -1.0507345 -39.09405948
OS -1.05813098 -39.10330508
OS -1.06645202 -39.11255068
OS -1.07477306 -39.12179628
OS -1.08494322 -39.12919276
OS -1.08586778 -39.13011732
OS -1.08956602 -39.13196644
OS -1.09511338 -39.13474012
OS -1.10343442 -39.13843836
OS -1.11268002 -39.1421366
OS -1.12377474 -39.14491028
OS -1.13579402 -39.1467594
OS -1.14966242 -39.14768396
OS -1.15336066 -39.14768396
OS -1.15798346 -39.1467594
OS -1.16445538 -39.1467594
OS -1.17185186 -39.14491028
OS -1.1801729 -39.14306116
OS -1.1894185 -39.14121204
OS -1.19958866 -39.1375138
OS -1.2079097 -39.06447356
OS -1.20698514 -39.06447356
OS -1.2032869 -39.06539812
OS -1.1986641 -39.06632268
OS -1.19311674 -39.0681718
OS -1.17832378 -39.07094548
OS -1.16353082 -39.07187004
OS -1.15890802 -39.07187004
OS -1.15428522 -39.07094548
OS -1.14873786 -39.07094548
OS -1.13486946 -39.0681718
OS -1.12839754 -39.06539812
OS -1.12192562 -39.06262444
OS -1.12100106 -39.06262444
OS -1.11915194 -39.06077532
OS -1.11637826 -39.0589262
OS -1.11268002 -39.05615252
OS -1.10435898 -39.04875604
OS -1.0969625 -39.03858588
OS -1.0969625 -39.03766132
OS -1.09511338 -39.0358122
OS -1.09326426 -39.03211396
OS -1.09141514 -39.0265666
OS -1.0877169 -39.01917012
OS -1.08401866 -39.0080754
OS -1.0784713 -38.99513156
OS -1.07292394 -38.97941404
OS -1.07292394 -38.97848948
OS -1.07107482 -38.97479124
OS -1.0692257 -38.96831932
OS -1.06552746 -38.95999828
OS -1.24119386 -38.49586916
OS -1.15798346 -38.49586916
OS -1.06090466 -38.76491612
OS -1.06090466 -38.76584068
OS -1.0599801 -38.76676524
OS -1.05905554 -38.76953892
OS -1.05813098 -38.77416172
OS -1.05628186 -38.77878452
OS -1.05443274 -38.78433188
OS -1.04980994 -38.79727572
OS -1.04426258 -38.81299324
OS -1.03871522 -38.83148444
OS -1.03316786 -38.8509002
OS -1.0276205 -38.87216508
OS -1.0276205 -38.87124052
OS -1.02669594 -38.8693914
OS -1.02577138 -38.86661772
OS -1.02484682 -38.86291948
OS -1.02392226 -38.85829668
OS -1.02207314 -38.85274932
OS -1.0183749 -38.83888092
OS -1.0137521 -38.8231634
OS -1.00728018 -38.8046722
OS -1.00173282 -38.786181
OS -0.99433634 -38.76676524
OS -0.89448386 -38.49586916
OS -0.81589626 -38.49586916
OS -0.99248722 -38.96739476
OE
OB -0.54315106 -38.48662356 I
OS -0.53575458 -38.48754812
OS -0.52650898 -38.48939724
OS -0.51633882 -38.49124636
OS -0.50431954 -38.49402004
OS -0.49322482 -38.49679372
OS -0.48028098 -38.50141652
OS -0.4682617 -38.50603932
OS -0.45531786 -38.51251124
OS -0.44237402 -38.51990772
OS -0.42943018 -38.52822876
OS -0.4174109 -38.53839892
OS -0.40631618 -38.54949364
OS -0.40539162 -38.5504182
OS -0.4035425 -38.55226732
OS -0.40076882 -38.55596556
OS -0.39707058 -38.56151292
OS -0.39244778 -38.56798484
OS -0.38782498 -38.57538132
OS -0.38227762 -38.58462692
OS -0.37673026 -38.59572164
OS -0.3711829 -38.60774092
OS -0.36563554 -38.62068476
OS -0.36101274 -38.63547772
OS -0.35638994 -38.65119524
OS -0.3526917 -38.66876188
OS -0.34991802 -38.68725308
OS -0.3480689 -38.70666884
OS -0.34714434 -38.72793372
OS -0.34714434 -38.72885828
OS -0.34714434 -38.73255652
OS -0.34714434 -38.73902844
OS -0.3480689 -38.74827404
OS -0.6947789 -38.74827404
OS -0.6947789 -38.7491986
OS -0.6947789 -38.75197228
OS -0.69385434 -38.75567052
OS -0.69385434 -38.76121788
OS -0.69292978 -38.7676898
OS -0.69108066 -38.77508628
OS -0.68830698 -38.79172836
OS -0.68275962 -38.81021956
OS -0.67536314 -38.83055988
OS -0.66519298 -38.84905108
OS -0.65224914 -38.86569316
OS -0.65132458 -38.86569316
OS -0.65040002 -38.86754228
OS -0.64485266 -38.87216508
OS -0.63653162 -38.878637
OS -0.6254369 -38.88510892
OS -0.61064394 -38.8925054
OS -0.59400186 -38.89897732
OS -0.57551066 -38.90360012
OS -0.5653405 -38.90452468
OS -0.55424578 -38.90544924
OS -0.5468493 -38.90544924
OS -0.53852826 -38.90452468
OS -0.5283581 -38.90267556
OS -0.51726338 -38.89990188
OS -0.50431954 -38.89620364
OS -0.49230026 -38.89065628
OS -0.48028098 -38.8832598
OS -0.47935642 -38.88233524
OS -0.47473362 -38.878637
OS -0.46918626 -38.87308964
OS -0.46271434 -38.86569316
OS -0.45531786 -38.855523
OS -0.44699682 -38.84257916
OS -0.43867578 -38.8277862
OS -0.4312793 -38.81021956
OS -0.34991802 -38.82038972
OS -0.34991802 -38.82131428
OS -0.35084258 -38.8231634
OS -0.35176714 -38.82686164
OS -0.35361626 -38.832409
OS -0.35638994 -38.83795636
OS -0.35916362 -38.84535284
OS -0.3665601 -38.86107036
OS -0.3758057 -38.878637
OS -0.38874954 -38.8971282
OS -0.4035425 -38.91469484
OS -0.4220337 -38.93133692
OS -0.42295826 -38.93133692
OS -0.42480738 -38.93318604
OS -0.42758106 -38.93503516
OS -0.4312793 -38.93780884
OS -0.43682666 -38.94058252
OS -0.44237402 -38.9433562
OS -0.4497705 -38.94705444
OS -0.45809154 -38.95075268
OS -0.46733714 -38.95445092
OS -0.47658274 -38.95814916
OS -0.49969674 -38.96369652
OS -0.52558442 -38.96831932
OS -0.55424578 -38.97016844
OS -0.56441594 -38.97016844
OS -0.57088786 -38.96924388
OS -0.5792089 -38.96831932
OS -0.58937906 -38.9664702
OS -0.60047378 -38.96462108
OS -0.61249306 -38.96277196
OS -0.63838074 -38.95537548
OS -0.65224914 -38.94982812
OS -0.66519298 -38.94428076
OS -0.67906138 -38.93688428
OS -0.69200522 -38.92856324
OS -0.7040245 -38.91931764
OS -0.71604378 -38.90822292
OS -0.71696834 -38.90729836
OS -0.71881746 -38.90544924
OS -0.72159114 -38.901751
OS -0.72528938 -38.89620364
OS -0.72991218 -38.88973172
OS -0.73453498 -38.88233524
OS -0.74008234 -38.87308964
OS -0.7456297 -38.86291948
OS -0.75117706 -38.8509002
OS -0.75672442 -38.83795636
OS -0.76134722 -38.8231634
OS -0.76597002 -38.80744588
OS -0.76966826 -38.7908038
OS -0.77244194 -38.7723126
OS -0.77429106 -38.75289684
OS -0.77521562 -38.73255652
OS -0.77521562 -38.73163196
OS -0.77521562 -38.72700916
OS -0.77521562 -38.7214618
OS -0.77429106 -38.71314076
OS -0.7733665 -38.7029706
OS -0.77244194 -38.69187588
OS -0.77059282 -38.67893204
OS -0.76781914 -38.6659882
OS -0.76042266 -38.63640228
OS -0.75579986 -38.62160932
OS -0.7502525 -38.6058918
OS -0.74285602 -38.59109884
OS -0.73453498 -38.57723044
OS -0.72528938 -38.56336204
OS -0.71511922 -38.5504182
OS -0.71419466 -38.54949364
OS -0.71234554 -38.54764452
OS -0.7086473 -38.54487084
OS -0.7040245 -38.54024804
OS -0.69847714 -38.53562524
OS -0.69108066 -38.53007788
OS -0.68275962 -38.52360596
OS -0.67258946 -38.5180586
OS -0.6624193 -38.51158668
OS -0.65040002 -38.50603932
OS -0.63745618 -38.50049196
OS -0.62358778 -38.49586916
OS -0.60879482 -38.49124636
OS -0.5930773 -38.48847268
OS -0.57643522 -38.48662356
OS -0.55886858 -38.485699
OS -0.54962298 -38.485699
OS -0.54315106 -38.48662356
OE
OB -1.47695666 -38.48662356 I
OS -1.46308826 -38.48754812
OS -1.44737074 -38.48939724
OS -1.43165322 -38.49217092
OS -1.4159357 -38.49586916
OS -1.40114274 -38.50049196
OS -1.39929362 -38.50141652
OS -1.39467082 -38.50326564
OS -1.3881989 -38.50603932
OS -1.37987786 -38.50973756
OS -1.37063226 -38.51528492
OS -1.36138666 -38.52083228
OS -1.35306562 -38.52822876
OS -1.34566914 -38.53562524
OS -1.34474458 -38.5365498
OS -1.34289546 -38.53932348
OS -1.34012178 -38.54394628
OS -1.33642354 -38.54949364
OS -1.33180074 -38.55781468
OS -1.3281025 -38.56613572
OS -1.32440426 -38.57630588
OS -1.32163058 -38.58832516
OS -1.32163058 -38.58924972
OS -1.32070602 -38.5920234
OS -1.31978146 -38.59757076
OS -1.3188569 -38.60496724
OS -1.3188569 -38.6151374
OS -1.31793234 -38.62715668
OS -1.31700778 -38.6428742
OS -1.31700778 -38.66044084
OS -1.31700778 -38.76584068
OS -1.31700778 -38.76676524
OS -1.31700778 -38.77046348
OS -1.31700778 -38.77601084
OS -1.31700778 -38.78340732
OS -1.31700778 -38.79172836
OS -1.31700778 -38.80189852
OS -1.31608322 -38.82408796
OS -1.31608322 -38.84720196
OS -1.31515866 -38.87031596
OS -1.3142341 -38.88048612
OS -1.3142341 -38.88973172
OS -1.31330954 -38.89805276
OS -1.31238498 -38.90452468
OS -1.31238498 -38.90544924
OS -1.31146042 -38.90914748
OS -1.31053586 -38.91469484
OS -1.30776218 -38.92209132
OS -1.30591306 -38.93041236
OS -1.30221482 -38.93965796
OS -1.29759202 -38.94982812
OS -1.29296922 -38.95999828
OS -1.37525506 -38.95999828
OS -1.37617962 -38.95907372
OS -1.37710418 -38.95537548
OS -1.3789533 -38.95075268
OS -1.38172698 -38.9433562
OS -1.38450066 -38.93503516
OS -1.38634978 -38.924865
OS -1.3881989 -38.91377028
OS -1.39004802 -38.901751
OS -1.39097258 -38.901751
OS -1.39189714 -38.90360012
OS -1.3974445 -38.90822292
OS -1.40576554 -38.91469484
OS -1.41686026 -38.92301588
OS -1.43072866 -38.93133692
OS -1.44459706 -38.94058252
OS -1.45939002 -38.94890356
OS -1.47510754 -38.95537548
OS -1.47695666 -38.95630004
OS -1.48250402 -38.9572246
OS -1.49082506 -38.95999828
OS -1.50099522 -38.96277196
OS -1.51393906 -38.96554564
OS -1.52873202 -38.96739476
OS -1.5453741 -38.96924388
OS -1.56201618 -38.97016844
OS -1.56941266 -38.97016844
OS -1.57496002 -38.96924388
OS -1.58143194 -38.96924388
OS -1.58882842 -38.96831932
OS -1.6054705 -38.96554564
OS -1.6239617 -38.96092284
OS -1.64430202 -38.95445092
OS -1.66279322 -38.94520532
OS -1.6794353 -38.93318604
OS -1.68128442 -38.93133692
OS -1.68590722 -38.92671412
OS -1.69237914 -38.91839308
OS -1.69977562 -38.90729836
OS -1.7071721 -38.89342996
OS -1.71364402 -38.87771244
OS -1.71826682 -38.85829668
OS -1.71919138 -38.84905108
OS -1.72011594 -38.83795636
OS -1.72011594 -38.83610724
OS -1.72011594 -38.832409
OS -1.71919138 -38.82593708
OS -1.71826682 -38.81761604
OS -1.7164177 -38.80744588
OS -1.71364402 -38.79727572
OS -1.70994578 -38.786181
OS -1.70532298 -38.77601084
OS -1.70439842 -38.77508628
OS -1.7025493 -38.77138804
OS -1.69885106 -38.76584068
OS -1.69422826 -38.75936876
OS -1.6886809 -38.75197228
OS -1.68128442 -38.7445758
OS -1.67388794 -38.73717932
OS -1.66464234 -38.7307074
OS -1.66371778 -38.72978284
OS -1.66001954 -38.72793372
OS -1.65539674 -38.72423548
OS -1.64800026 -38.72053724
OS -1.63967922 -38.716839
OS -1.62950906 -38.7122162
OS -1.6193389 -38.70851796
OS -1.60731962 -38.70481972
OS -1.60639506 -38.70481972
OS -1.60269682 -38.70389516
OS -1.59714946 -38.70204604
OS -1.58975298 -38.70112148
OS -1.58050738 -38.69927236
OS -1.5684881 -38.69742324
OS -1.5546197 -38.69464956
OS -1.53797762 -38.69280044
OS -1.53705306 -38.69280044
OS -1.53335482 -38.69187588
OS -1.52873202 -38.69187588
OS -1.5222601 -38.69095132
OS -1.51486362 -38.69002676
OS -1.50561802 -38.68817764
OS -1.49544786 -38.68725308
OS -1.48435314 -38.68540396
OS -1.4621637 -38.68078116
OS -1.43812514 -38.67615836
OS -1.41686026 -38.670611
OS -1.4066901 -38.66783732
OS -1.3974445 -38.66506364
OS -1.3974445 -38.66413908
OS -1.3974445 -38.66228996
OS -1.39651994 -38.6567426
OS -1.39651994 -38.65027068
OS -1.39651994 -38.64657244
OS -1.39651994 -38.64472332
OS -1.39651994 -38.64379876
OS -1.39651994 -38.6428742
OS -1.39651994 -38.63732684
OS -1.3974445 -38.62808124
OS -1.39929362 -38.61791108
OS -1.4020673 -38.60681636
OS -1.4066901 -38.59572164
OS -1.41223746 -38.58555148
OS -1.41963394 -38.57723044
OS -1.4205585 -38.57630588
OS -1.4251813 -38.57260764
OS -1.43257778 -38.5689094
OS -1.44182338 -38.56336204
OS -1.45476722 -38.55873924
OS -1.46956018 -38.55411644
OS -1.48805138 -38.55134276
OS -1.50931626 -38.5504182
OS -1.51856186 -38.5504182
OS -1.52780746 -38.55134276
OS -1.5407513 -38.55319188
OS -1.55369514 -38.555041
OS -1.56756354 -38.55873924
OS -1.58050738 -38.56336204
OS -1.5916021 -38.56983396
OS -1.59252666 -38.57075852
OS -1.5962249 -38.5735322
OS -1.6008477 -38.578155
OS -1.60639506 -38.58555148
OS -1.61194242 -38.59479708
OS -1.61841434 -38.60681636
OS -1.6239617 -38.62160932
OS -1.62950906 -38.6382514
OS -1.70624754 -38.62808124
OS -1.70624754 -38.62715668
OS -1.70532298 -38.62623212
OS -1.70532298 -38.62345844
OS -1.70439842 -38.6197602
OS -1.70162474 -38.61143916
OS -1.6979265 -38.59941988
OS -1.6933037 -38.5874006
OS -1.68775634 -38.57445676
OS -1.68035986 -38.56151292
OS -1.67203882 -38.54949364
OS -1.67111426 -38.54856908
OS -1.66741602 -38.54487084
OS -1.66186866 -38.53932348
OS -1.65447218 -38.531927
OS -1.64430202 -38.52453052
OS -1.63228274 -38.51713404
OS -1.61841434 -38.508813
OS -1.60269682 -38.50234108
OS -1.60177226 -38.50234108
OS -1.6008477 -38.50141652
OS -1.59807402 -38.50049196
OS -1.59437578 -38.4995674
OS -1.58513018 -38.49679372
OS -1.57218634 -38.49402004
OS -1.55739338 -38.49124636
OS -1.53890218 -38.48847268
OS -1.51948642 -38.48662356
OS -1.49729698 -38.485699
OS -1.48712682 -38.485699
OS -1.47695666 -38.48662356
OE
OB 0.11698478 -38.42745172 I
OS 0.0957199 -38.54671996
OS 0.04671822 -38.54671996
OS 0.02730246 -38.42745172
OS 0.02730246 -38.32020276
OS 0.11698478 -38.32020276
OS 0.11698478 -38.42745172
OE
OB -5.4655085 -38.31835364 I
OS -5.45348922 -38.32020276
OS -5.43962082 -38.32297644
OS -5.42482786 -38.32667468
OS -5.40911034 -38.33129748
OS -5.39431738 -38.33869396
OS -5.39339282 -38.33869396
OS -5.39246826 -38.33961852
OS -5.38784546 -38.3423922
OS -5.38044898 -38.347015
OS -5.37120338 -38.35348692
OS -5.36103322 -38.36273252
OS -5.3499385 -38.37290268
OS -5.33976834 -38.38492196
OS -5.32959818 -38.39879036
OS -5.32867362 -38.40063948
OS -5.32497538 -38.40526228
OS -5.32127714 -38.41358332
OS -5.31480522 -38.4256026
OS -5.30925786 -38.439471
OS -5.30186138 -38.45518852
OS -5.29538946 -38.47367972
OS -5.2898421 -38.49402004
OS -5.2898421 -38.4949446
OS -5.28891754 -38.49679372
OS -5.28799298 -38.4995674
OS -5.28706842 -38.5041902
OS -5.28614386 -38.50973756
OS -5.2852193 -38.51620948
OS -5.28337018 -38.52453052
OS -5.28244562 -38.53377612
OS -5.2805965 -38.54394628
OS -5.27967194 -38.555041
OS -5.27874738 -38.56798484
OS -5.27689826 -38.58092868
OS -5.2759737 -38.59572164
OS -5.2759737 -38.6105146
OS -5.27504914 -38.62715668
OS -5.27504914 -38.64472332
OS -5.27504914 -38.64564788
OS -5.27504914 -38.64934612
OS -5.27504914 -38.65581804
OS -5.27504914 -38.66321452
OS -5.2759737 -38.67338468
OS -5.2759737 -38.6844794
OS -5.27689826 -38.69649868
OS -5.27782282 -38.70944252
OS -5.2805965 -38.73902844
OS -5.2852193 -38.76953892
OS -5.29076666 -38.79912484
OS -5.2944649 -38.81299324
OS -5.2990877 -38.82686164
OS -5.2990877 -38.8277862
OS -5.30001226 -38.82963532
OS -5.30186138 -38.83333356
OS -5.3037105 -38.83795636
OS -5.30555962 -38.84442828
OS -5.30925786 -38.8509002
OS -5.31665434 -38.86661772
OS -5.32589994 -38.8832598
OS -5.33791922 -38.901751
OS -5.35178762 -38.91839308
OS -5.3684297 -38.9341106
OS -5.36935426 -38.9341106
OS -5.37027882 -38.93595972
OS -5.3730525 -38.93780884
OS -5.37675074 -38.93965796
OS -5.38137354 -38.94243164
OS -5.38599634 -38.94612988
OS -5.39986474 -38.9526018
OS -5.41650682 -38.95907372
OS -5.43592258 -38.96554564
OS -5.45903658 -38.96924388
OS -5.4839997 -38.971093
OS -5.4932453 -38.971093
OS -5.49971722 -38.97016844
OS -5.5071137 -38.96924388
OS -5.5163593 -38.96739476
OS -5.52652946 -38.96554564
OS -5.53762418 -38.96277196
OS -5.5487189 -38.95907372
OS -5.56073818 -38.95537548
OS -5.57275746 -38.94982812
OS -5.58477674 -38.9433562
OS -5.59679602 -38.93595972
OS -5.6088153 -38.92671412
OS -5.61991002 -38.91654396
OS -5.63008018 -38.90544924
OS -5.63100474 -38.90452468
OS -5.63285386 -38.901751
OS -5.63562754 -38.8971282
OS -5.64025034 -38.88973172
OS -5.64487314 -38.88141068
OS -5.64949594 -38.87031596
OS -5.65596786 -38.85737212
OS -5.66151522 -38.84257916
OS -5.66706258 -38.82593708
OS -5.67260994 -38.80652132
OS -5.6781573 -38.78525644
OS -5.6827801 -38.76121788
OS -5.6874029 -38.7353302
OS -5.69017658 -38.7075934
OS -5.6920257 -38.67708292
OS -5.69295026 -38.64472332
OS -5.69295026 -38.64379876
OS -5.69295026 -38.64010052
OS -5.69295026 -38.6336286
OS -5.69295026 -38.62623212
OS -5.6920257 -38.61606196
OS -5.6920257 -38.60496724
OS -5.69110114 -38.59294796
OS -5.69017658 -38.57907956
OS -5.6874029 -38.5504182
OS -5.6827801 -38.51990772
OS -5.67723274 -38.48939724
OS -5.6735345 -38.47552884
OS -5.66983626 -38.46166044
OS -5.66983626 -38.46073588
OS -5.6689117 -38.45888676
OS -5.66706258 -38.45518852
OS -5.66521346 -38.45056572
OS -5.66336434 -38.4440938
OS -5.6596661 -38.43762188
OS -5.65226962 -38.42190436
OS -5.64302402 -38.40526228
OS -5.63100474 -38.38769564
OS -5.61713634 -38.370129
OS -5.60049426 -38.35533604
OS -5.5995697 -38.35533604
OS -5.59864514 -38.35348692
OS -5.59587146 -38.3516378
OS -5.59217322 -38.34978868
OS -5.58755042 -38.34609044
OS -5.58200306 -38.34331676
OS -5.56813466 -38.33592028
OS -5.55149258 -38.32944836
OS -5.53207682 -38.32297644
OS -5.50896282 -38.3192782
OS -5.4839997 -38.31742908
OS -5.47567866 -38.31742908
OS -5.4655085 -38.31835364
OE
OB -5.79280274 -38.95999828 I
OS -5.87139034 -38.95999828
OS -5.87139034 -38.32020276
OS -5.79280274 -38.32020276
OS -5.79280274 -38.95999828
OE
OB -5.97031826 -38.42745172 I
OS -5.99158314 -38.54671996
OS -6.04058482 -38.54671996
OS -6.06000058 -38.42745172
OS -6.06000058 -38.32020276
OS -5.97031826 -38.32020276
OS -5.97031826 -38.42745172
OE
OB -4.96809522 -38.31835364 I
OS -4.96069874 -38.3192782
OS -4.95145314 -38.32020276
OS -4.94128298 -38.32205188
OS -4.93111282 -38.323901
OS -4.90707426 -38.33037292
OS -4.8830357 -38.33961852
OS -4.87101642 -38.34516588
OS -4.85899714 -38.3516378
OS -4.84790242 -38.35995884
OS -4.83773226 -38.36920444
OS -4.8368077 -38.370129
OS -4.83495858 -38.37105356
OS -4.83310946 -38.3747518
OS -4.82941122 -38.37845004
OS -4.82478842 -38.38307284
OS -4.82016562 -38.38954476
OS -4.81554282 -38.39601668
OS -4.80999546 -38.40433772
OS -4.80074986 -38.42190436
OS -4.79150426 -38.4440938
OS -4.78780602 -38.45518852
OS -4.7859569 -38.46813236
OS -4.78410778 -38.4810762
OS -4.78318322 -38.4949446
OS -4.78318322 -38.49679372
OS -4.78318322 -38.50141652
OS -4.78410778 -38.508813
OS -4.78503234 -38.51898316
OS -4.78688146 -38.53007788
OS -4.7905797 -38.54302172
OS -4.79427794 -38.55689012
OS -4.7998253 -38.57075852
OS -4.80074986 -38.57260764
OS -4.80259898 -38.57723044
OS -4.80629722 -38.58462692
OS -4.81184458 -38.59479708
OS -4.81924106 -38.6058918
OS -4.82848666 -38.6197602
OS -4.83958138 -38.6336286
OS -4.85252522 -38.64934612
OS -4.85437434 -38.65119524
OS -4.85899714 -38.6567426
OS -4.86361994 -38.6613654
OS -4.86824274 -38.6659882
OS -4.8737901 -38.67153556
OS -4.88118658 -38.67893204
OS -4.88858306 -38.68632852
OS -4.89782866 -38.69464956
OS -4.90707426 -38.70389516
OS -4.91816898 -38.71406532
OS -4.93018826 -38.72423548
OS -4.9431321 -38.73625476
OS -4.95792506 -38.74827404
OS -4.97271802 -38.76121788
OS -4.97364258 -38.76214244
OS -4.9754917 -38.76399156
OS -4.97918994 -38.76676524
OS -4.98381274 -38.77046348
OS -4.9893601 -38.77601084
OS -4.99583202 -38.7815582
OS -5.01062498 -38.79357748
OS -5.0263425 -38.80744588
OS -5.04113546 -38.82131428
OS -5.0540793 -38.83333356
OS -5.05962666 -38.83795636
OS -5.06424946 -38.84257916
OS -5.06517402 -38.84350372
OS -5.0679477 -38.8462774
OS -5.07164594 -38.84997564
OS -5.07626874 -38.855523
OS -5.08089154 -38.86199492
OS -5.0864389 -38.86846684
OS -5.09753362 -38.88418436
OS -4.78225866 -38.88418436
OS -4.78225866 -38.95999828
OS -5.2066317 -38.95999828
OS -5.2066317 -38.95907372
OS -5.2066317 -38.95537548
OS -5.2066317 -38.94982812
OS -5.20570714 -38.94243164
OS -5.20478258 -38.9341106
OS -5.20293346 -38.924865
OS -5.20108434 -38.9156194
OS -5.1973861 -38.90544924
OS -5.1973861 -38.90452468
OS -5.19646154 -38.90360012
OS -5.19461242 -38.89805276
OS -5.19091418 -38.88973172
OS -5.18536682 -38.878637
OS -5.17797034 -38.86569316
OS -5.16872474 -38.8509002
OS -5.15855458 -38.83610724
OS -5.14561074 -38.82038972
OS -5.14561074 -38.81946516
OS -5.14376162 -38.8185406
OS -5.13913882 -38.81299324
OS -5.13081778 -38.8046722
OS -5.1187985 -38.79265292
OS -5.1049301 -38.77878452
OS -5.08736346 -38.76214244
OS -5.06609858 -38.74365124
OS -5.04298458 -38.72423548
OS -5.04206002 -38.72331092
OS -5.03836178 -38.72053724
OS -5.03281442 -38.71591444
OS -5.0263425 -38.71036708
OS -5.01802146 -38.7029706
OS -5.0078513 -38.69464956
OS -4.99768114 -38.68540396
OS -4.98566186 -38.6752338
OS -4.96254786 -38.65304436
OS -4.93943386 -38.63085492
OS -4.92833914 -38.6197602
OS -4.91816898 -38.60866548
OS -4.90892338 -38.59849532
OS -4.9015269 -38.58832516
OS -4.9015269 -38.5874006
OS -4.89967778 -38.58647604
OS -4.89782866 -38.58370236
OS -4.89597954 -38.58000412
OS -4.88950762 -38.56983396
OS -4.88211114 -38.55781468
OS -4.87563922 -38.54302172
OS -4.8691673 -38.5273042
OS -4.86546906 -38.50973756
OS -4.86361994 -38.49309548
OS -4.86361994 -38.49217092
OS -4.86361994 -38.49124636
OS -4.8645445 -38.485699
OS -4.86546906 -38.4764534
OS -4.86824274 -38.46628324
OS -4.87194098 -38.4533394
OS -4.8784129 -38.44039556
OS -4.88673394 -38.42745172
OS -4.89782866 -38.41450788
OS -4.89967778 -38.41265876
OS -4.90430058 -38.40896052
OS -4.9107725 -38.40433772
OS -4.92094266 -38.3978658
OS -4.9338865 -38.39231844
OS -4.94867946 -38.38677108
OS -4.9662461 -38.38307284
OS -4.98566186 -38.38214828
OS -4.99120922 -38.38214828
OS -4.99490746 -38.38307284
OS -5.00600218 -38.3839974
OS -5.01894602 -38.38677108
OS -5.03281442 -38.39046932
OS -5.04853194 -38.39694124
OS -5.0633249 -38.40526228
OS -5.0771933 -38.416357
OS -5.07904242 -38.41820612
OS -5.08274066 -38.42282892
OS -5.08828802 -38.4302254
OS -5.09383538 -38.44132012
OS -5.1003073 -38.45426396
OS -5.10585466 -38.47090604
OS -5.1095529 -38.48939724
OS -5.11140202 -38.51066212
OS -5.19183874 -38.50234108
OS -5.19183874 -38.50141652
OS -5.19091418 -38.49864284
OS -5.19091418 -38.49402004
OS -5.18998962 -38.48754812
OS -5.1881405 -38.48015164
OS -5.18629138 -38.4718306
OS -5.1835177 -38.46166044
OS -5.18074402 -38.45149028
OS -5.17334754 -38.42930084
OS -5.16225282 -38.4071114
OS -5.1557809 -38.39601668
OS -5.14745986 -38.38492196
OS -5.13913882 -38.3747518
OS -5.12989322 -38.3655062
OS -5.12896866 -38.36458164
OS -5.12711954 -38.36365708
OS -5.12434586 -38.3608834
OS -5.11972306 -38.35810972
OS -5.1141757 -38.35441148
OS -5.10770378 -38.35071324
OS -5.1003073 -38.34609044
OS -5.0910617 -38.34146764
OS -5.08089154 -38.33684484
OS -5.06979682 -38.33222204
OS -5.05777754 -38.3285238
OS -5.0448337 -38.32482556
OS -5.0309653 -38.32205188
OS -5.01617234 -38.3192782
OS -5.00045482 -38.31835364
OS -4.98381274 -38.31742908
OS -4.97456714 -38.31742908
OS -4.96809522 -38.31835364
OE
OB -4.29963834 -38.40988508 I
OS -4.37822594 -38.40988508
OS -4.37822594 -38.32020276
OS -4.29963834 -38.32020276
OS -4.29963834 -38.40988508
OE
OB -4.29963834 -38.95999828 I
OS -4.37822594 -38.95999828
OS -4.37822594 -38.49586916
OS -4.29963834 -38.49586916
OS -4.29963834 -38.95999828
OE
OB -4.46421002 -38.7676898 I
OS -4.7073693 -38.7676898
OS -4.7073693 -38.6891022
OS -4.46421002 -38.6891022
OS -4.46421002 -38.7676898
OE
OB -3.94738098 -38.48662356 I
OS -3.93721082 -38.48754812
OS -3.92519154 -38.48939724
OS -3.9122477 -38.49217092
OS -3.8983793 -38.49586916
OS -3.88543546 -38.50141652
OS -3.88358634 -38.50234108
OS -3.8798881 -38.5041902
OS -3.87341618 -38.50696388
OS -3.8660197 -38.51158668
OS -3.8567741 -38.51713404
OS -3.84845306 -38.52453052
OS -3.84013202 -38.531927
OS -3.83273554 -38.5411726
OS -3.83181098 -38.54209716
OS -3.82996186 -38.5457954
OS -3.82718818 -38.5504182
OS -3.82256538 -38.55689012
OS -3.81886714 -38.56613572
OS -3.8151689 -38.57538132
OS -3.8105461 -38.58647604
OS -3.80777242 -38.59849532
OS -3.80777242 -38.59941988
OS -3.80684786 -38.60311812
OS -3.8059233 -38.60866548
OS -3.80499874 -38.61606196
OS -3.80499874 -38.62715668
OS -3.80407418 -38.64010052
OS -3.80314962 -38.65581804
OS -3.80314962 -38.6752338
OS -3.80314962 -38.95999828
OS -3.88173722 -38.95999828
OS -3.88173722 -38.67893204
OS -3.88173722 -38.67800748
OS -3.88173722 -38.67708292
OS -3.88173722 -38.670611
OS -3.88173722 -38.66228996
OS -3.88266178 -38.6521198
OS -3.88358634 -38.64010052
OS -3.88543546 -38.62808124
OS -3.88820914 -38.61698652
OS -3.89098282 -38.60681636
OS -3.89098282 -38.6058918
OS -3.89283194 -38.60311812
OS -3.89560562 -38.59849532
OS -3.8983793 -38.59294796
OS -3.9030021 -38.5874006
OS -3.90854946 -38.58092868
OS -3.91594594 -38.57445676
OS -3.92426698 -38.5689094
OS -3.92519154 -38.56798484
OS -3.92796522 -38.56613572
OS -3.93351258 -38.5642866
OS -3.9399845 -38.56151292
OS -3.94738098 -38.55873924
OS -3.95662658 -38.55596556
OS -3.9677213 -38.555041
OS -3.97881602 -38.55411644
OS -3.98343882 -38.55411644
OS -3.98713706 -38.555041
OS -3.99638266 -38.55596556
OS -4.00840194 -38.55781468
OS -4.02134578 -38.56243748
OS -4.03613874 -38.56798484
OS -4.0509317 -38.57538132
OS -4.0648001 -38.58647604
OS -4.06664922 -38.58832516
OS -4.07034746 -38.59294796
OS -4.07312114 -38.5966462
OS -4.07589482 -38.601269
OS -4.07959306 -38.60681636
OS -4.08236674 -38.61328828
OS -4.08606498 -38.62068476
OS -4.08976322 -38.62993036
OS -4.0925369 -38.64010052
OS -4.09531058 -38.65119524
OS -4.0971597 -38.66321452
OS -4.09900882 -38.67615836
OS -4.10085794 -38.69187588
OS -4.10085794 -38.7075934
OS -4.10085794 -38.95999828
OS -4.17944554 -38.95999828
OS -4.17944554 -38.49586916
OS -4.10917898 -38.49586916
OS -4.10917898 -38.56243748
OS -4.10825442 -38.56151292
OS -4.1064053 -38.55873924
OS -4.10363162 -38.555041
OS -4.09993338 -38.5504182
OS -4.09438602 -38.54487084
OS -4.0879141 -38.53839892
OS -4.08051762 -38.53100244
OS -4.07127202 -38.52360596
OS -4.06202642 -38.51713404
OS -4.0509317 -38.50973756
OS -4.03891242 -38.50326564
OS -4.02596858 -38.49771828
OS -4.01117562 -38.49309548
OS -3.99638266 -38.48939724
OS -3.97974058 -38.48662356
OS -3.96217394 -38.485699
OS -3.95477746 -38.485699
OS -3.94738098 -38.48662356
OE
OB -0.55794402 -38.5504182 H
OS -0.56349138 -38.5504182
OS -0.56718962 -38.55134276
OS -0.57735978 -38.55226732
OS -0.58937906 -38.555041
OS -0.60417202 -38.5596638
OS -0.61988954 -38.56613572
OS -0.6346825 -38.57538132
OS -0.64947546 -38.5874006
OS -0.65132458 -38.58924972
OS -0.65502282 -38.59387252
OS -0.66149474 -38.60219356
OS -0.66796666 -38.61328828
OS -0.67536314 -38.62623212
OS -0.68183506 -38.6428742
OS -0.68738242 -38.66228996
OS -0.6901561 -38.68355484
OS -0.43035474 -38.68355484
OS -0.43035474 -38.68263028
OS -0.43035474 -38.68078116
OS -0.4312793 -38.67800748
OS -0.4312793 -38.67430924
OS -0.43312842 -38.66321452
OS -0.4359021 -38.65119524
OS -0.4405249 -38.63640228
OS -0.4451477 -38.62253388
OS -0.45254418 -38.60866548
OS -0.46086522 -38.5966462
OS -0.46086522 -38.59572164
OS -0.46271434 -38.59479708
OS -0.46733714 -38.58924972
OS -0.47565818 -38.58185324
OS -0.4867529 -38.5735322
OS -0.5006213 -38.56521116
OS -0.51726338 -38.55781468
OS -0.53667914 -38.55226732
OS -0.5468493 -38.55134276
OS -0.55794402 -38.5504182
OE
OB -5.48492426 -38.38214828 H
OS -5.49047162 -38.38214828
OS -5.49416986 -38.38307284
OS -5.50434002 -38.38492196
OS -5.5163593 -38.38769564
OS -5.5302277 -38.393243
OS -5.54502066 -38.40156404
OS -5.55241714 -38.4071114
OS -5.55981362 -38.41265876
OS -5.56628554 -38.42005524
OS -5.57275746 -38.42837628
OS -5.57275746 -38.42930084
OS -5.57460658 -38.43114996
OS -5.5764557 -38.4348482
OS -5.57922938 -38.439471
OS -5.58200306 -38.44686748
OS -5.5857013 -38.45518852
OS -5.58847498 -38.46535868
OS -5.59217322 -38.47737796
OS -5.59587146 -38.49124636
OS -5.5995697 -38.50696388
OS -5.60326794 -38.52453052
OS -5.60604162 -38.54394628
OS -5.6088153 -38.56613572
OS -5.61066442 -38.59017428
OS -5.61158898 -38.61606196
OS -5.61251354 -38.64472332
OS -5.61251354 -38.64657244
OS -5.61251354 -38.65119524
OS -5.61251354 -38.65951628
OS -5.61158898 -38.670611
OS -5.61158898 -38.68263028
OS -5.61066442 -38.69742324
OS -5.60973986 -38.71314076
OS -5.60789074 -38.72978284
OS -5.60326794 -38.76584068
OS -5.60049426 -38.78340732
OS -5.59679602 -38.8000494
OS -5.59309778 -38.81576692
OS -5.58755042 -38.83055988
OS -5.58200306 -38.84350372
OS -5.57553114 -38.85459844
OS -5.57553114 -38.855523
OS -5.57368202 -38.85644756
OS -5.56905922 -38.86291948
OS -5.56073818 -38.87124052
OS -5.55056802 -38.88048612
OS -5.53669962 -38.88973172
OS -5.5209821 -38.89805276
OS -5.50341546 -38.90452468
OS -5.49416986 -38.90544924
OS -5.4839997 -38.9063738
OS -5.47845234 -38.9063738
OS -5.4747541 -38.90544924
OS -5.4655085 -38.90360012
OS -5.45256466 -38.89990188
OS -5.43869626 -38.89342996
OS -5.42297874 -38.88418436
OS -5.41558226 -38.878637
OS -5.40818578 -38.87124052
OS -5.4007893 -38.86384404
OS -5.39339282 -38.85459844
OS -5.39339282 -38.85367388
OS -5.3915437 -38.85182476
OS -5.38969458 -38.84905108
OS -5.38784546 -38.84442828
OS -5.38414722 -38.83795636
OS -5.38137354 -38.82963532
OS -5.3776753 -38.82038972
OS -5.37397706 -38.809295
OS -5.37120338 -38.7954266
OS -5.36750514 -38.78063364
OS -5.3638069 -38.763067
OS -5.36103322 -38.7445758
OS -5.3591841 -38.72238636
OS -5.35733498 -38.69927236
OS -5.35548586 -38.67338468
OS -5.35548586 -38.64472332
OS -5.35548586 -38.64379876
OS -5.35548586 -38.6428742
OS -5.35548586 -38.6382514
OS -5.35548586 -38.62993036
OS -5.35641042 -38.61883564
OS -5.35641042 -38.60681636
OS -5.35733498 -38.5920234
OS -5.35825954 -38.57630588
OS -5.36010866 -38.55873924
OS -5.36473146 -38.52360596
OS -5.36750514 -38.50603932
OS -5.37120338 -38.48939724
OS -5.37490162 -38.47367972
OS -5.38044898 -38.45888676
OS -5.38599634 -38.44594292
OS -5.39246826 -38.4348482
OS -5.39246826 -38.43392364
OS -5.39431738 -38.43299908
OS -5.3961665 -38.4302254
OS -5.39894018 -38.42652716
OS -5.40726122 -38.41820612
OS -5.41743138 -38.40803596
OS -5.43129978 -38.39879036
OS -5.4470173 -38.39046932
OS -5.45533834 -38.38677108
OS -5.46458394 -38.3839974
OS -5.4747541 -38.38307284
OS -5.48492426 -38.38214828
OE
OB -2.99415962 -38.5504182 H
OS -2.99970698 -38.5504182
OS -3.00340522 -38.55134276
OS -3.01357538 -38.55226732
OS -3.02559466 -38.555041
OS -3.04038762 -38.5596638
OS -3.05610514 -38.56613572
OS -3.0708981 -38.57538132
OS -3.08569106 -38.5874006
OS -3.08754018 -38.58924972
OS -3.09123842 -38.59387252
OS -3.09771034 -38.60219356
OS -3.10418226 -38.61328828
OS -3.11157874 -38.62623212
OS -3.11805066 -38.6428742
OS -3.12359802 -38.66228996
OS -3.1263717 -38.68355484
OS -2.86657034 -38.68355484
OS -2.86657034 -38.68263028
OS -2.86657034 -38.68078116
OS -2.8674949 -38.67800748
OS -2.8674949 -38.67430924
OS -2.86934402 -38.66321452
OS -2.8721177 -38.65119524
OS -2.8767405 -38.63640228
OS -2.8813633 -38.62253388
OS -2.88875978 -38.60866548
OS -2.89708082 -38.5966462
OS -2.89708082 -38.59572164
OS -2.89892994 -38.59479708
OS -2.90355274 -38.58924972
OS -2.91187378 -38.58185324
OS -2.9229685 -38.5735322
OS -2.9368369 -38.56521116
OS -2.95347898 -38.55781468
OS -2.97289474 -38.55226732
OS -2.9830649 -38.55134276
OS -2.99415962 -38.5504182
OE
OB -1.39651994 -38.72700916 H
OS -1.3974445 -38.72700916
OS -1.39836906 -38.72793372
OS -1.40114274 -38.72885828
OS -1.40484098 -38.72978284
OS -1.40946378 -38.73163196
OS -1.41501114 -38.73348108
OS -1.42148306 -38.7353302
OS -1.42887954 -38.73717932
OS -1.43720058 -38.739953
OS -1.44737074 -38.74180212
OS -1.4575409 -38.7445758
OS -1.46956018 -38.74734948
OS -1.48250402 -38.75012316
OS -1.49544786 -38.75289684
OS -1.51024082 -38.75474596
OS -1.52595834 -38.75751964
OS -1.52780746 -38.75751964
OS -1.53335482 -38.7584442
OS -1.54260042 -38.76029332
OS -1.55277058 -38.76214244
OS -1.5638653 -38.76399156
OS -1.57496002 -38.76676524
OS -1.58513018 -38.76953892
OS -1.59437578 -38.77323716
OS -1.59530034 -38.77323716
OS -1.59807402 -38.77508628
OS -1.60177226 -38.7769354
OS -1.6054705 -38.77970908
OS -1.61656522 -38.78710556
OS -1.62581082 -38.79820028
OS -1.62581082 -38.79912484
OS -1.62765994 -38.80097396
OS -1.6285845 -38.8046722
OS -1.63043362 -38.809295
OS -1.63228274 -38.81484236
OS -1.63413186 -38.82038972
OS -1.63505642 -38.8277862
OS -1.63598098 -38.83518268
OS -1.63598098 -38.83610724
OS -1.63598098 -38.84073004
OS -1.63505642 -38.8462774
OS -1.6332073 -38.85367388
OS -1.63043362 -38.86199492
OS -1.62581082 -38.87031596
OS -1.62026346 -38.87956156
OS -1.61286698 -38.8878826
OS -1.61194242 -38.88880716
OS -1.60824418 -38.89065628
OS -1.60269682 -38.89435452
OS -1.59530034 -38.89805276
OS -1.58513018 -38.901751
OS -1.5731109 -38.90544924
OS -1.5592425 -38.90729836
OS -1.54260042 -38.90822292
OS -1.53520394 -38.90822292
OS -1.52595834 -38.90729836
OS -1.51578818 -38.90544924
OS -1.50284434 -38.90360012
OS -1.4899005 -38.89990188
OS -1.4760321 -38.89527908
OS -1.4621637 -38.88880716
OS -1.46031458 -38.8878826
OS -1.45661634 -38.88510892
OS -1.45014442 -38.88048612
OS -1.44274794 -38.8740142
OS -1.4344269 -38.86661772
OS -1.4251813 -38.85737212
OS -1.41778482 -38.8462774
OS -1.41038834 -38.83425812
OS -1.40946378 -38.83333356
OS -1.40853922 -38.82963532
OS -1.4066901 -38.8231634
OS -1.40391642 -38.81484236
OS -1.40114274 -38.80374764
OS -1.39929362 -38.7908038
OS -1.39836906 -38.77508628
OS -1.3974445 -38.75659508
OS -1.39651994 -38.72700916
OE
SE
S P 0
OB -4.66714078 -36.5016923 I
OS -4.65465922 -36.5016923
OS -4.62553558 -36.50307914
OS -4.5950251 -36.50723966
OS -4.56174094 -36.51140018
OS -4.53123046 -36.51833438
OS -4.51597522 -36.5224949
OS -4.50349366 -36.52665542
OS -4.50210682 -36.52665542
OS -4.50071998 -36.52804226
OS -4.49239894 -36.53220278
OS -4.47991738 -36.53775014
OS -4.46466214 -36.54745802
OS -4.44802006 -36.55993958
OS -4.42999114 -36.57658166
OS -4.41334906 -36.59599742
OS -4.39670698 -36.61818686
OS -4.39670698 -36.6195737
OS -4.39532014 -36.62096054
OS -4.38977278 -36.62928158
OS -4.38422542 -36.64314998
OS -4.37590438 -36.6611789
OS -4.36897018 -36.6819815
OS -4.36203598 -36.70694462
OS -4.35787546 -36.73329458
OS -4.35648862 -36.76241822
OS -4.35648862 -36.76380506
OS -4.35648862 -36.76657874
OS -4.35648862 -36.7721261
OS -4.35787546 -36.7790603
OS -4.35787546 -36.78876818
OS -4.3592623 -36.79847606
OS -4.36480966 -36.82205234
OS -4.3731307 -36.84978914
OS -4.38422542 -36.87891278
OS -4.4008675 -36.90803642
OS -4.41196222 -36.92190482
OS -4.42305694 -36.93577322
OS -4.42444378 -36.93716006
OS -4.42583062 -36.9385469
OS -4.42999114 -36.94270742
OS -4.4355385 -36.94686794
OS -4.4424727 -36.9524153
OS -4.45079374 -36.95796266
OS -4.46188846 -36.96489686
OS -4.47298318 -36.9732179
OS -4.48685158 -36.9801521
OS -4.50210682 -36.9870863
OS -4.5187489 -36.99540734
OS -4.53677782 -37.00234154
OS -4.55758042 -37.0078889
OS -4.57838302 -37.0148231
OS -4.6019593 -37.01898362
OS -4.62692242 -37.02314414
OS -4.62414874 -37.02453098
OS -4.61860138 -37.02730466
OS -4.61028034 -37.03285202
OS -4.59918562 -37.03839938
OS -4.5742225 -37.05365462
OS -4.56174094 -37.0633625
OS -4.55064622 -37.07168354
OS -4.54787254 -37.07445722
OS -4.54093834 -37.08139142
OS -4.52984362 -37.09248614
OS -4.51597522 -37.10635454
OS -4.50071998 -37.1257703
OS -4.48269106 -37.1465729
OS -4.46466214 -37.17153602
OS -4.44524638 -37.19927282
OS -4.28021242 -37.45999874
OS -4.43831218 -37.45999874
OS -4.56451462 -37.26029378
OS -4.56451462 -37.25890694
OS -4.5672883 -37.25613326
OS -4.57006198 -37.25197274
OS -4.5742225 -37.24642538
OS -4.58393038 -37.23117014
OS -4.59641194 -37.21175438
OS -4.61166718 -37.19095178
OS -4.62692242 -37.16876234
OS -4.64217766 -37.14795974
OS -4.65604606 -37.12854398
OS -4.6574329 -37.12715714
OS -4.66159342 -37.12160978
OS -4.66852762 -37.11328874
OS -4.6782355 -37.10358086
OS -4.6990381 -37.08277826
OS -4.71013282 -37.07307038
OS -4.72122754 -37.06474934
OS -4.72261438 -37.0633625
OS -4.72538806 -37.06197566
OS -4.73093542 -37.05920198
OS -4.73925646 -37.05504146
OS -4.7475775 -37.05088094
OS -4.75728538 -37.04672042
OS -4.77947482 -37.03978622
OS -4.78086166 -37.03978622
OS -4.78363534 -37.03839938
OS -4.7891827 -37.03839938
OS -4.7961169 -37.03701254
OS -4.80582478 -37.0356257
OS -4.8169195 -37.0356257
OS -4.83217474 -37.03423886
OS -4.99582186 -37.03423886
OS -4.99582186 -37.45999874
OS -5.12341114 -37.45999874
OS -5.12341114 -36.50030546
OS -4.6782355 -36.50030546
OS -4.66714078 -36.5016923
OE
OB -1.0100437 -37.45999874 I
OS -1.13208562 -37.45999874
OS -1.13208562 -36.65701838
OS -1.4122273 -37.45999874
OS -1.52594818 -37.45999874
OS -1.80331618 -36.64314998
OS -1.80331618 -37.45999874
OS -1.9253581 -37.45999874
OS -1.9253581 -36.50030546
OS -1.73536102 -36.50030546
OS -1.50791926 -37.1812439
OS -1.50791926 -37.18263074
OS -1.50653242 -37.18540442
OS -1.50514558 -37.18956494
OS -1.5023719 -37.19649914
OS -1.49682454 -37.21314122
OS -1.48989034 -37.23394382
OS -1.48295614 -37.2575201
OS -1.4746351 -37.28109638
OS -1.4677009 -37.30328582
OS -1.46215354 -37.32270158
OS -1.4607667 -37.3199279
OS -1.45937986 -37.3129937
OS -1.45521934 -37.30051214
OS -1.44967198 -37.28387006
OS -1.44273778 -37.26168062
OS -1.4330299 -37.23533066
OS -1.42332202 -37.20482018
OS -1.41084046 -37.16876234
OS -1.18062502 -36.50030546
OS -1.0100437 -36.50030546
OS -1.0100437 -37.45999874
OE
OB -2.02382374 -37.45999874 I
OS -2.1680551 -37.45999874
OS -2.28038914 -37.16876234
OS -2.68257274 -37.16876234
OS -2.78658574 -37.45999874
OS -2.92110922 -37.45999874
OS -2.55498346 -36.50030546
OS -2.41629946 -36.50030546
OS -2.02382374 -37.45999874
OE
OB -3.02928274 -37.45999874 I
OS -3.16103254 -37.45999874
OS -3.66306862 -36.70694462
OS -3.66306862 -37.45999874
OS -3.78511054 -37.45999874
OS -3.78511054 -36.50030546
OS -3.65474758 -36.50030546
OS -3.15132466 -37.25474642
OS -3.15132466 -36.50030546
OS -3.02928274 -36.50030546
OS -3.02928274 -37.45999874
OE
OB -5.3231161 -36.61402634 I
OS -5.89033366 -36.61402634
OS -5.89033366 -36.90664958
OS -5.35917394 -36.90664958
OS -5.35917394 -37.02037046
OS -5.89033366 -37.02037046
OS -5.89033366 -37.34627786
OS -5.30092666 -37.34627786
OS -5.30092666 -37.45999874
OS -6.01792294 -37.45999874
OS -6.01792294 -36.50030546
OS -5.3231161 -36.50030546
OS -5.3231161 -36.61402634
OE
OB -0.10721086 -36.61402634 I
OS -0.67442842 -36.61402634
OS -0.67442842 -36.90664958
OS -0.1432687 -36.90664958
OS -0.1432687 -37.02037046
OS -0.67442842 -37.02037046
OS -0.67442842 -37.34627786
OS -0.08502142 -37.34627786
OS -0.08502142 -37.45999874
OS -0.8020177 -37.45999874
OS -0.8020177 -36.50030546
OS -0.10721086 -36.50030546
OS -0.10721086 -36.61402634
OE
OB -8.43241138 -37.34627786 I
OS -7.95949894 -37.34627786
OS -7.95949894 -37.45999874
OS -8.56000066 -37.45999874
OS -8.56000066 -36.50030546
OS -8.43241138 -36.50030546
OS -8.43241138 -37.34627786
OE
OB -6.51718534 -37.05365462 I
OS -6.51718534 -37.45999874
OS -6.64477462 -37.45999874
OS -6.64477462 -37.05365462
OS -7.0150609 -36.50030546
OS -6.86112166 -36.50030546
OS -6.67251142 -36.79154186
OS -6.67251142 -36.7929287
OS -6.66973774 -36.79570238
OS -6.66696406 -36.7998629
OS -6.66419038 -36.80541026
OS -6.65864302 -36.81234446
OS -6.65309566 -36.8206655
OS -6.6406141 -36.8414681
OS -6.62535886 -36.86643122
OS -6.60871678 -36.89416802
OS -6.59068786 -36.92329166
OS -6.57404578 -36.95380214
OS -6.57404578 -36.9524153
OS -6.57265894 -36.94964162
OS -6.56988526 -36.9454811
OS -6.56572474 -36.93993374
OS -6.56156422 -36.93299954
OS -6.55601686 -36.9246785
OS -6.5435353 -36.9038759
OS -6.52828006 -36.87891278
OS -6.51025114 -36.84978914
OS -6.48944854 -36.81789182
OS -6.4672591 -36.78322082
OS -6.28280938 -36.50030546
OS -6.1344175 -36.50030546
OS -6.51718534 -37.05365462
OE
OB -7.01644774 -37.45999874 I
OS -7.1606791 -37.45999874
OS -7.27301314 -37.16876234
OS -7.67519674 -37.16876234
OS -7.77920974 -37.45999874
OS -7.91373322 -37.45999874
OS -7.54760746 -36.50030546
OS -7.40892346 -36.50030546
OS -7.01644774 -37.45999874
OE
OB -7.48103914 -36.60015794 H
OS -7.48103914 -36.60154478
OS -7.48242598 -36.60431846
OS -7.48242598 -36.60986582
OS -7.48519966 -36.61541318
OS -7.4865865 -36.62512106
OS -7.48936018 -36.63482894
OS -7.49490754 -36.65840522
OS -7.50184174 -36.68614202
OS -7.51154962 -36.7166525
OS -7.5212575 -36.74993666
OS -7.53373906 -36.78460766
OS -7.63775206 -37.06474934
OS -7.3132315 -37.06474934
OS -7.41308398 -36.80124974
OS -7.41308398 -36.7998629
OS -7.41447082 -36.79570238
OS -7.4172445 -36.78876818
OS -7.42001818 -36.78044714
OS -7.4241787 -36.77073926
OS -7.42833922 -36.7582577
OS -7.43249974 -36.7443893
OS -7.4380471 -36.7305209
OS -7.44914182 -36.69862358
OS -7.46023654 -36.66533942
OS -7.47133126 -36.63205526
OS -7.48103914 -36.60015794
OE
OB -4.69349074 -36.60709214 H
OS -4.99582186 -36.60709214
OS -4.99582186 -36.9246785
OS -4.71013282 -36.9246785
OS -4.69349074 -36.92329166
OS -4.67407498 -36.92190482
OS -4.65188554 -36.92051798
OS -4.6296961 -36.9177443
OS -4.60750666 -36.91358378
OS -4.5880909 -36.90803642
OS -4.58531722 -36.90664958
OS -4.57976986 -36.9038759
OS -4.57144882 -36.89971538
OS -4.5603541 -36.89416802
OS -4.54787254 -36.88584698
OS -4.53539098 -36.8761391
OS -4.52290942 -36.86365754
OS -4.51320154 -36.84978914
OS -4.5118147 -36.8484023
OS -4.50904102 -36.84285494
OS -4.5048805 -36.8345339
OS -4.49933314 -36.82343918
OS -4.49517262 -36.81095762
OS -4.4910121 -36.79708922
OS -4.48823842 -36.78044714
OS -4.48685158 -36.76380506
OS -4.48685158 -36.76241822
OS -4.48685158 -36.76103138
OS -4.48823842 -36.75271034
OS -4.48962526 -36.74022878
OS -4.49239894 -36.7235867
OS -4.49933314 -36.70694462
OS -4.50765418 -36.68752886
OS -4.52013574 -36.66949994
OS -4.53677782 -36.65147102
OS -4.5395515 -36.65008418
OS -4.5464857 -36.64453682
OS -4.55758042 -36.63760262
OS -4.57560934 -36.62928158
OS -4.59641194 -36.62096054
OS -4.62414874 -36.61402634
OS -4.65604606 -36.60847898
OS -4.69349074 -36.60709214
OE
OB -2.48841514 -36.60015794 H
OS -2.48841514 -36.60154478
OS -2.48980198 -36.60431846
OS -2.48980198 -36.60986582
OS -2.49257566 -36.61541318
OS -2.4939625 -36.62512106
OS -2.49673618 -36.63482894
OS -2.50228354 -36.65840522
OS -2.50921774 -36.68614202
OS -2.51892562 -36.7166525
OS -2.5286335 -36.74993666
OS -2.54111506 -36.78460766
OS -2.64512806 -37.06474934
OS -2.3206075 -37.06474934
OS -2.42045998 -36.80124974
OS -2.42045998 -36.7998629
OS -2.42184682 -36.79570238
OS -2.4246205 -36.78876818
OS -2.42739418 -36.78044714
OS -2.4315547 -36.77073926
OS -2.43571522 -36.7582577
OS -2.43987574 -36.7443893
OS -2.4454231 -36.7305209
OS -2.45651782 -36.69862358
OS -2.46761254 -36.66533942
OS -2.47870726 -36.63205526
OS -2.48841514 -36.60015794
OE
SE
S P 0
OB 35.73690338 -37.45999874 I
OS 35.61486146 -37.45999874
OS 35.61486146 -36.65701838
OS 35.33471978 -37.45999874
OS 35.2209989 -37.45999874
OS 34.9436309 -36.64314998
OS 34.9436309 -37.45999874
OS 34.82158898 -37.45999874
OS 34.82158898 -36.50030546
OS 35.01158606 -36.50030546
OS 35.23902782 -37.1812439
OS 35.23902782 -37.18263074
OS 35.24041466 -37.18540442
OS 35.2418015 -37.18956494
OS 35.24457518 -37.19649914
OS 35.25012254 -37.21314122
OS 35.25705674 -37.23394382
OS 35.26399094 -37.2575201
OS 35.27231198 -37.28109638
OS 35.27924618 -37.30328582
OS 35.28479354 -37.32270158
OS 35.28618038 -37.3199279
OS 35.28756722 -37.3129937
OS 35.29172774 -37.30051214
OS 35.2972751 -37.28387006
OS 35.3042093 -37.26168062
OS 35.31391718 -37.23533066
OS 35.32362506 -37.20482018
OS 35.33610662 -37.16876234
OS 35.56632206 -36.50030546
OS 35.73690338 -36.50030546
OS 35.73690338 -37.45999874
OE
OB 34.61356298 -37.05504146 I
OS 34.61356298 -37.0564283
OS 34.61356298 -37.06197566
OS 34.61356298 -37.06890986
OS 34.61356298 -37.07861774
OS 34.61217614 -37.0910993
OS 34.61217614 -37.1049677
OS 34.6107893 -37.12160978
OS 34.60940246 -37.13825186
OS 34.60524194 -37.17569654
OS 34.59969458 -37.21452806
OS 34.59137354 -37.25197274
OS 34.58582618 -37.27000166
OS 34.58027882 -37.28664374
OS 34.58027882 -37.28803058
OS 34.57889198 -37.29080426
OS 34.5761183 -37.29496478
OS 34.57334462 -37.30051214
OS 34.56502358 -37.31576738
OS 34.55254202 -37.33518314
OS 34.53589994 -37.35737258
OS 34.51648418 -37.37956202
OS 34.49152106 -37.4031383
OS 34.46101058 -37.4239409
OS 34.45962374 -37.4239409
OS 34.45685006 -37.42671458
OS 34.45268954 -37.42810142
OS 34.44575534 -37.43226194
OS 34.4374343 -37.43642246
OS 34.42633958 -37.44058298
OS 34.41524486 -37.4447435
OS 34.40137646 -37.45029086
OS 34.38612122 -37.45583822
OS 34.36947914 -37.45999874
OS 34.35145022 -37.46415926
OS 34.33064762 -37.46831978
OS 34.30984502 -37.47109346
OS 34.28765558 -37.47386714
OS 34.23772934 -37.47664082
OS 34.22524778 -37.47664082
OS 34.2155399 -37.47525398
OS 34.20444518 -37.47525398
OS 34.19057678 -37.47386714
OS 34.17532154 -37.4724803
OS 34.1600663 -37.47109346
OS 34.1253953 -37.4655461
OS 34.08795062 -37.45722506
OS 34.05189278 -37.44613034
OS 34.01722178 -37.4308751
OS 34.01583494 -37.4308751
OS 34.01306126 -37.42810142
OS 34.00890074 -37.42532774
OS 34.00335338 -37.42255406
OS 33.98809814 -37.41145934
OS 33.97006922 -37.3962041
OS 33.94926662 -37.37678834
OS 33.92985086 -37.3545989
OS 33.9104351 -37.3268621
OS 33.89517986 -37.29635162
OS 33.89517986 -37.29496478
OS 33.89379302 -37.2921911
OS 33.89240618 -37.28664374
OS 33.8896325 -37.27970954
OS 33.88685882 -37.2713885
OS 33.88408514 -37.26029378
OS 33.87992462 -37.24781222
OS 33.87715094 -37.23255698
OS 33.87437726 -37.2159149
OS 33.87021674 -37.19788598
OS 33.86744306 -37.17847022
OS 33.86466938 -37.15766762
OS 33.8618957 -37.13409134
OS 33.86050886 -37.10912822
OS 33.85912202 -37.08277826
OS 33.85912202 -37.05504146
OS 33.85912202 -36.50030546
OS 33.9867113 -36.50030546
OS 33.9867113 -37.05504146
OS 33.9867113 -37.0564283
OS 33.9867113 -37.06058882
OS 33.9867113 -37.06752302
OS 33.9867113 -37.07584406
OS 33.98809814 -37.08555194
OS 33.98809814 -37.0980335
OS 33.98948498 -37.12438346
OS 33.99225866 -37.15489394
OS 33.99641918 -37.18540442
OS 34.00196654 -37.21452806
OS 34.00474022 -37.22700962
OS 34.00890074 -37.23949118
OS 34.01028758 -37.24226486
OS 34.01306126 -37.24919906
OS 34.01999546 -37.25890694
OS 34.0283165 -37.27277534
OS 34.03802438 -37.28664374
OS 34.05189278 -37.30189898
OS 34.06853486 -37.31715422
OS 34.08795062 -37.32963578
OS 34.0907243 -37.33102262
OS 34.0976585 -37.33518314
OS 34.11014006 -37.33934366
OS 34.12678214 -37.34489102
OS 34.1461979 -37.35182522
OS 34.17116102 -37.35598574
OS 34.19751098 -37.36014626
OS 34.22663462 -37.3615331
OS 34.24050302 -37.3615331
OS 34.24882406 -37.36014626
OS 34.26130562 -37.36014626
OS 34.27378718 -37.35875942
OS 34.30429766 -37.35321206
OS 34.33758182 -37.34627786
OS 34.36947914 -37.33518314
OS 34.39998962 -37.3199279
OS 34.41385802 -37.31022002
OS 34.42633958 -37.2991253
OS 34.42772642 -37.29773846
OS 34.42911326 -37.29635162
OS 34.43188694 -37.2921911
OS 34.43604746 -37.28664374
OS 34.44020798 -37.2783227
OS 34.44575534 -37.27000166
OS 34.4513027 -37.2575201
OS 34.45685006 -37.24503854
OS 34.46239742 -37.2297833
OS 34.46655794 -37.21175438
OS 34.4721053 -37.19095178
OS 34.47626582 -37.16876234
OS 34.48042634 -37.14379922
OS 34.48320002 -37.11744926
OS 34.4859737 -37.08693878
OS 34.4859737 -37.05504146
OS 34.4859737 -36.50030546
OS 34.61356298 -36.50030546
OS 34.61356298 -37.05504146
OE
OB 33.64416182 -37.45999874 I
OS 33.51241202 -37.45999874
OS 33.01037594 -36.70694462
OS 33.01037594 -37.45999874
OS 32.88833402 -37.45999874
OS 32.88833402 -36.50030546
OS 33.01869698 -36.50030546
OS 33.5221199 -37.25474642
OS 33.5221199 -36.50030546
OS 33.64416182 -36.50030546
OS 33.64416182 -37.45999874
OE
OB 38.19022334 -36.5016923 I
OS 38.2027049 -36.5016923
OS 38.23182854 -36.50307914
OS 38.26233902 -36.50723966
OS 38.29562318 -36.51140018
OS 38.32613366 -36.51833438
OS 38.3413889 -36.5224949
OS 38.35387046 -36.52665542
OS 38.3552573 -36.52665542
OS 38.35664414 -36.52804226
OS 38.36496518 -36.53220278
OS 38.37744674 -36.53775014
OS 38.39270198 -36.54745802
OS 38.40934406 -36.55993958
OS 38.42737298 -36.57658166
OS 38.44401506 -36.59599742
OS 38.46065714 -36.61818686
OS 38.46065714 -36.6195737
OS 38.46204398 -36.62096054
OS 38.46759134 -36.62928158
OS 38.4731387 -36.64314998
OS 38.48145974 -36.6611789
OS 38.48839394 -36.6819815
OS 38.49532814 -36.70694462
OS 38.49948866 -36.73329458
OS 38.5008755 -36.76241822
OS 38.5008755 -36.76380506
OS 38.5008755 -36.76657874
OS 38.5008755 -36.7721261
OS 38.49948866 -36.7790603
OS 38.49948866 -36.78876818
OS 38.49810182 -36.79847606
OS 38.49255446 -36.82205234
OS 38.48423342 -36.84978914
OS 38.4731387 -36.87891278
OS 38.45649662 -36.90803642
OS 38.4454019 -36.92190482
OS 38.43430718 -36.93577322
OS 38.43292034 -36.93716006
OS 38.4315335 -36.9385469
OS 38.42737298 -36.94270742
OS 38.42182562 -36.94686794
OS 38.41489142 -36.9524153
OS 38.40657038 -36.95796266
OS 38.39547566 -36.96489686
OS 38.38438094 -36.9732179
OS 38.37051254 -36.9801521
OS 38.3552573 -36.9870863
OS 38.33861522 -36.99540734
OS 38.3205863 -37.00234154
OS 38.2997837 -37.0078889
OS 38.2789811 -37.0148231
OS 38.25540482 -37.01898362
OS 38.2304417 -37.02314414
OS 38.23321538 -37.02453098
OS 38.23876274 -37.02730466
OS 38.24708378 -37.03285202
OS 38.2581785 -37.03839938
OS 38.28314162 -37.05365462
OS 38.29562318 -37.0633625
OS 38.3067179 -37.07168354
OS 38.30949158 -37.07445722
OS 38.31642578 -37.08139142
OS 38.3275205 -37.09248614
OS 38.3413889 -37.10635454
OS 38.35664414 -37.1257703
OS 38.37467306 -37.1465729
OS 38.39270198 -37.17153602
OS 38.41211774 -37.19927282
OS 38.5771517 -37.45999874
OS 38.41905194 -37.45999874
OS 38.2928495 -37.26029378
OS 38.2928495 -37.25890694
OS 38.29007582 -37.25613326
OS 38.28730214 -37.25197274
OS 38.28314162 -37.24642538
OS 38.27343374 -37.23117014
OS 38.26095218 -37.21175438
OS 38.24569694 -37.19095178
OS 38.2304417 -37.16876234
OS 38.21518646 -37.14795974
OS 38.20131806 -37.12854398
OS 38.19993122 -37.12715714
OS 38.1957707 -37.12160978
OS 38.1888365 -37.11328874
OS 38.17912862 -37.10358086
OS 38.15832602 -37.08277826
OS 38.1472313 -37.07307038
OS 38.13613658 -37.06474934
OS 38.13474974 -37.0633625
OS 38.13197606 -37.06197566
OS 38.1264287 -37.05920198
OS 38.11810766 -37.05504146
OS 38.10978662 -37.05088094
OS 38.10007874 -37.04672042
OS 38.0778893 -37.03978622
OS 38.07650246 -37.03978622
OS 38.07372878 -37.03839938
OS 38.06818142 -37.03839938
OS 38.06124722 -37.03701254
OS 38.05153934 -37.0356257
OS 38.04044462 -37.0356257
OS 38.02518938 -37.03423886
OS 37.86154226 -37.03423886
OS 37.86154226 -37.45999874
OS 37.73395298 -37.45999874
OS 37.73395298 -36.50030546
OS 38.17912862 -36.50030546
OS 38.19022334 -36.5016923
OE
OB 37.53424802 -36.61402634 I
OS 36.96703046 -36.61402634
OS 36.96703046 -36.90664958
OS 37.49819018 -36.90664958
OS 37.49819018 -37.02037046
OS 36.96703046 -37.02037046
OS 36.96703046 -37.34627786
OS 37.55643746 -37.34627786
OS 37.55643746 -37.45999874
OS 36.83944118 -37.45999874
OS 36.83944118 -36.50030546
OS 37.53424802 -36.50030546
OS 37.53424802 -36.61402634
OE
OB 36.32492354 -36.5016923 I
OS 36.33601826 -36.5016923
OS 36.36098138 -36.50446598
OS 36.38871818 -36.50723966
OS 36.41784182 -36.51278702
OS 36.44696546 -36.51972122
OS 36.47331542 -36.5294291
OS 36.47470226 -36.5294291
OS 36.4760891 -36.53081594
OS 36.48441014 -36.53497646
OS 36.4968917 -36.54191066
OS 36.5107601 -36.55161854
OS 36.52740218 -36.5641001
OS 36.5454311 -36.57935534
OS 36.56207318 -36.5987711
OS 36.57732842 -36.6195737
OS 36.57871526 -36.62234738
OS 36.58287578 -36.63066842
OS 36.58980998 -36.64176314
OS 36.59674418 -36.65840522
OS 36.60367838 -36.67782098
OS 36.61061258 -36.69862358
OS 36.6147731 -36.72219986
OS 36.61615994 -36.74577614
OS 36.61615994 -36.74854982
OS 36.61615994 -36.75548402
OS 36.6147731 -36.76796558
OS 36.61199942 -36.78322082
OS 36.6078389 -36.80124974
OS 36.6009047 -36.8206655
OS 36.59258366 -36.84008126
OS 36.58148894 -36.86088386
OS 36.5801021 -36.86365754
OS 36.57594158 -36.8692049
OS 36.56762054 -36.88029962
OS 36.55652582 -36.89139434
OS 36.54265742 -36.90526274
OS 36.52601534 -36.92051798
OS 36.50521274 -36.93438638
OS 36.48163646 -36.94825478
OS 36.4830233 -36.94825478
OS 36.48579698 -36.94964162
OS 36.4899575 -36.95102846
OS 36.49550486 -36.95380214
OS 36.51214694 -36.9593495
OS 36.5315627 -36.96905738
OS 36.5523653 -36.98153894
OS 36.57594158 -36.99679418
OS 36.59674418 -37.0148231
OS 36.61615994 -37.03701254
OS 36.61754678 -37.03978622
OS 36.62309414 -37.04810726
OS 36.63141518 -37.06058882
OS 36.63973622 -37.0772309
OS 36.64805726 -37.09942034
OS 36.6563783 -37.12299662
OS 36.66192566 -37.15073342
OS 36.6633125 -37.1812439
OS 36.6633125 -37.18263074
OS 36.6633125 -37.18401758
OS 36.6633125 -37.19233862
OS 36.66192566 -37.20620702
OS 36.65915198 -37.2228491
OS 36.6563783 -37.24226486
OS 36.65083094 -37.26306746
OS 36.64389674 -37.2852569
OS 36.63418886 -37.30744634
OS 36.63280202 -37.31022002
OS 36.6286415 -37.31715422
OS 36.62309414 -37.3268621
OS 36.6147731 -37.3407305
OS 36.60367838 -37.3545989
OS 36.59258366 -37.36985414
OS 36.57871526 -37.38510938
OS 36.56346002 -37.39759094
OS 36.56207318 -37.39897778
OS 36.55652582 -37.4031383
OS 36.54681794 -37.40868566
OS 36.53433638 -37.41423302
OS 36.51908114 -37.42255406
OS 36.50105222 -37.4308751
OS 36.48163646 -37.4378093
OS 36.45806018 -37.4447435
OS 36.4552865 -37.4447435
OS 36.44696546 -37.44751718
OS 36.43309706 -37.44890402
OS 36.41506814 -37.4516777
OS 36.3928787 -37.45445138
OS 36.36652874 -37.45722506
OS 36.3374051 -37.4586119
OS 36.30412094 -37.45999874
OS 35.93799518 -37.45999874
OS 35.93799518 -36.50030546
OS 36.31521566 -36.50030546
OS 36.32492354 -36.5016923
OE
OB 32.3849111 -36.61402634 I
OS 32.06871158 -36.61402634
OS 32.06871158 -37.45999874
OS 31.9411223 -37.45999874
OS 31.9411223 -36.61402634
OS 31.62492278 -36.61402634
OS 31.62492278 -36.50030546
OS 32.3849111 -36.50030546
OS 32.3849111 -36.61402634
OE
OB 30.62639798 -37.45999874 I
OS 30.48216662 -37.45999874
OS 30.36983258 -37.16876234
OS 29.96764898 -37.16876234
OS 29.86363598 -37.45999874
OS 29.7291125 -37.45999874
OS 30.09523826 -36.50030546
OS 30.23392226 -36.50030546
OS 30.62639798 -37.45999874
OE
OB 29.3546657 -36.5016923 I
OS 29.37824198 -36.50307914
OS 29.4032051 -36.50446598
OS 29.42678138 -36.50723966
OS 29.44758398 -36.51001334
OS 29.45035766 -36.51001334
OS 29.46006554 -36.51278702
OS 29.4725471 -36.5155607
OS 29.48918918 -36.51972122
OS 29.5072181 -36.52665542
OS 29.52663386 -36.53497646
OS 29.54743646 -36.54468434
OS 29.56546538 -36.55577906
OS 29.56823906 -36.5571659
OS 29.57378642 -36.56132642
OS 29.58210746 -36.56964746
OS 29.59320218 -36.57935534
OS 29.60568374 -36.5918369
OS 29.6181653 -36.60847898
OS 29.6320337 -36.6265079
OS 29.64312842 -36.6473105
OS 29.64451526 -36.65008418
OS 29.64728894 -36.65701838
OS 29.6528363 -36.66949994
OS 29.65838366 -36.68614202
OS 29.66254418 -36.70555778
OS 29.66809154 -36.72774722
OS 29.67086522 -36.75271034
OS 29.67225206 -36.7790603
OS 29.67225206 -36.78044714
OS 29.67225206 -36.78460766
OS 29.67225206 -36.79015502
OS 29.67086522 -36.7998629
OS 29.66947838 -36.80957078
OS 29.66809154 -36.82205234
OS 29.66531786 -36.83592074
OS 29.66254418 -36.85117598
OS 29.6528363 -36.8830733
OS 29.64728894 -36.89971538
OS 29.6389679 -36.9177443
OS 29.62926002 -36.93577322
OS 29.61955214 -36.9524153
OS 29.60707058 -36.96905738
OS 29.59320218 -36.98569946
OS 29.59181534 -36.9870863
OS 29.58904166 -36.98985998
OS 29.58488114 -36.9940205
OS 29.57794694 -36.99818102
OS 29.5696259 -37.00511522
OS 29.55853118 -37.01204942
OS 29.54466278 -37.02037046
OS 29.52940754 -37.02730466
OS 29.51137862 -37.0356257
OS 29.49057602 -37.04394674
OS 29.46838658 -37.05088094
OS 29.44203662 -37.0564283
OS 29.41429982 -37.06197566
OS 29.38378934 -37.06613618
OS 29.34911834 -37.06890986
OS 29.3130605 -37.0702967
OS 29.06758982 -37.0702967
OS 29.06758982 -37.45999874
OS 28.94000054 -37.45999874
OS 28.94000054 -36.50030546
OS 29.3338631 -36.50030546
OS 29.3546657 -36.5016923
OE
OB 31.18668134 -36.5016923 I
OS 31.1991629 -36.5016923
OS 31.22828654 -36.50307914
OS 31.25879702 -36.50723966
OS 31.29208118 -36.51140018
OS 31.32259166 -36.51833438
OS 31.3378469 -36.5224949
OS 31.35032846 -36.52665542
OS 31.3517153 -36.52665542
OS 31.35310214 -36.52804226
OS 31.36142318 -36.53220278
OS 31.37390474 -36.53775014
OS 31.38915998 -36.54745802
OS 31.40580206 -36.55993958
OS 31.42383098 -36.57658166
OS 31.44047306 -36.59599742
OS 31.45711514 -36.61818686
OS 31.45711514 -36.6195737
OS 31.45850198 -36.62096054
OS 31.46404934 -36.62928158
OS 31.4695967 -36.64314998
OS 31.47791774 -36.6611789
OS 31.48485194 -36.6819815
OS 31.49178614 -36.70694462
OS 31.49594666 -36.73329458
OS 31.4973335 -36.76241822
OS 31.4973335 -36.76380506
OS 31.4973335 -36.76657874
OS 31.4973335 -36.7721261
OS 31.49594666 -36.7790603
OS 31.49594666 -36.78876818
OS 31.49455982 -36.79847606
OS 31.48901246 -36.82205234
OS 31.48069142 -36.84978914
OS 31.4695967 -36.87891278
OS 31.45295462 -36.90803642
OS 31.4418599 -36.92190482
OS 31.43076518 -36.93577322
OS 31.42937834 -36.93716006
OS 31.4279915 -36.9385469
OS 31.42383098 -36.94270742
OS 31.41828362 -36.94686794
OS 31.41134942 -36.9524153
OS 31.40302838 -36.95796266
OS 31.39193366 -36.96489686
OS 31.38083894 -36.9732179
OS 31.36697054 -36.9801521
OS 31.3517153 -36.9870863
OS 31.33507322 -36.99540734
OS 31.3170443 -37.00234154
OS 31.2962417 -37.0078889
OS 31.2754391 -37.0148231
OS 31.25186282 -37.01898362
OS 31.2268997 -37.02314414
OS 31.22967338 -37.02453098
OS 31.23522074 -37.02730466
OS 31.24354178 -37.03285202
OS 31.2546365 -37.03839938
OS 31.27959962 -37.05365462
OS 31.29208118 -37.0633625
OS 31.3031759 -37.07168354
OS 31.30594958 -37.07445722
OS 31.31288378 -37.08139142
OS 31.3239785 -37.09248614
OS 31.3378469 -37.10635454
OS 31.35310214 -37.1257703
OS 31.37113106 -37.1465729
OS 31.38915998 -37.17153602
OS 31.40857574 -37.19927282
OS 31.5736097 -37.45999874
OS 31.41550994 -37.45999874
OS 31.2893075 -37.26029378
OS 31.2893075 -37.25890694
OS 31.28653382 -37.25613326
OS 31.28376014 -37.25197274
OS 31.27959962 -37.24642538
OS 31.26989174 -37.23117014
OS 31.25741018 -37.21175438
OS 31.24215494 -37.19095178
OS 31.2268997 -37.16876234
OS 31.21164446 -37.14795974
OS 31.19777606 -37.12854398
OS 31.19638922 -37.12715714
OS 31.1922287 -37.12160978
OS 31.1852945 -37.11328874
OS 31.17558662 -37.10358086
OS 31.15478402 -37.08277826
OS 31.1436893 -37.07307038
OS 31.13259458 -37.06474934
OS 31.13120774 -37.0633625
OS 31.12843406 -37.06197566
OS 31.1228867 -37.05920198
OS 31.11456566 -37.05504146
OS 31.10624462 -37.05088094
OS 31.09653674 -37.04672042
OS 31.0743473 -37.03978622
OS 31.07296046 -37.03978622
OS 31.07018678 -37.03839938
OS 31.06463942 -37.03839938
OS 31.05770522 -37.03701254
OS 31.04799734 -37.0356257
OS 31.03690262 -37.0356257
OS 31.02164738 -37.03423886
OS 30.85800026 -37.03423886
OS 30.85800026 -37.45999874
OS 30.73041098 -37.45999874
OS 30.73041098 -36.50030546
OS 31.17558662 -36.50030546
OS 31.18668134 -36.5016923
OE
OB 38.16387338 -36.60709214 H
OS 37.86154226 -36.60709214
OS 37.86154226 -36.9246785
OS 38.1472313 -36.9246785
OS 38.16387338 -36.92329166
OS 38.18328914 -36.92190482
OS 38.20547858 -36.92051798
OS 38.22766802 -36.9177443
OS 38.24985746 -36.91358378
OS 38.26927322 -36.90803642
OS 38.2720469 -36.90664958
OS 38.27759426 -36.9038759
OS 38.2859153 -36.89971538
OS 38.29701002 -36.89416802
OS 38.30949158 -36.88584698
OS 38.32197314 -36.8761391
OS 38.3344547 -36.86365754
OS 38.34416258 -36.84978914
OS 38.34554942 -36.8484023
OS 38.3483231 -36.84285494
OS 38.35248362 -36.8345339
OS 38.35803098 -36.82343918
OS 38.3621915 -36.81095762
OS 38.36635202 -36.79708922
OS 38.3691257 -36.78044714
OS 38.37051254 -36.76380506
OS 38.37051254 -36.76241822
OS 38.37051254 -36.76103138
OS 38.3691257 -36.75271034
OS 38.36773886 -36.74022878
OS 38.36496518 -36.7235867
OS 38.35803098 -36.70694462
OS 38.34970994 -36.68752886
OS 38.33722838 -36.66949994
OS 38.3205863 -36.65147102
OS 38.31781262 -36.65008418
OS 38.31087842 -36.64453682
OS 38.2997837 -36.63760262
OS 38.28175478 -36.62928158
OS 38.26095218 -36.62096054
OS 38.23321538 -36.61402634
OS 38.20131806 -36.60847898
OS 38.16387338 -36.60709214
OE
OB 29.34218414 -36.61402634 H
OS 29.06758982 -36.61402634
OS 29.06758982 -36.95657582
OS 29.32554206 -36.95657582
OS 29.33524994 -36.95518898
OS 29.34495782 -36.95518898
OS 29.35605254 -36.95380214
OS 29.3824025 -36.95102846
OS 29.41152614 -36.9454811
OS 29.44064978 -36.93716006
OS 29.46699974 -36.92606534
OS 29.4794813 -36.91913114
OS 29.48918918 -36.9108101
OS 29.49196286 -36.90803642
OS 29.49751022 -36.90248906
OS 29.50583126 -36.89139434
OS 29.51553914 -36.87752594
OS 29.52524702 -36.85949702
OS 29.53356806 -36.83730758
OS 29.53911542 -36.81234446
OS 29.5418891 -36.78322082
OS 29.5418891 -36.78183398
OS 29.5418891 -36.78044714
OS 29.5418891 -36.77351294
OS 29.54050226 -36.76103138
OS 29.53772858 -36.74716298
OS 29.5349549 -36.73190774
OS 29.52940754 -36.71387882
OS 29.5210865 -36.69723674
OS 29.51137862 -36.68059466
OS 29.50999178 -36.67920782
OS 29.50583126 -36.67366046
OS 29.49889706 -36.66672626
OS 29.49057602 -36.65701838
OS 29.47809446 -36.6473105
OS 29.46422606 -36.63898946
OS 29.44897082 -36.63066842
OS 29.4309419 -36.62373422
OS 29.42955506 -36.62373422
OS 29.4240077 -36.62234738
OS 29.41568666 -36.62096054
OS 29.40459194 -36.61818686
OS 29.38794986 -36.61680002
OS 29.36714726 -36.61541318
OS 29.34218414 -36.61402634
OE
OB 30.16180658 -36.60015794 H
OS 30.16180658 -36.60154478
OS 30.16041974 -36.60431846
OS 30.16041974 -36.60986582
OS 30.15764606 -36.61541318
OS 30.15625922 -36.62512106
OS 30.15348554 -36.63482894
OS 30.14793818 -36.65840522
OS 30.14100398 -36.68614202
OS 30.1312961 -36.7166525
OS 30.12158822 -36.74993666
OS 30.10910666 -36.78460766
OS 30.00509366 -37.06474934
OS 30.32961422 -37.06474934
OS 30.22976174 -36.80124974
OS 30.22976174 -36.7998629
OS 30.2283749 -36.79570238
OS 30.22560122 -36.78876818
OS 30.22282754 -36.78044714
OS 30.21866702 -36.77073926
OS 30.2145065 -36.7582577
OS 30.21034598 -36.7443893
OS 30.20479862 -36.7305209
OS 30.1937039 -36.69862358
OS 30.18260918 -36.66533942
OS 30.17151446 -36.63205526
OS 30.16180658 -36.60015794
OE
OB 31.16033138 -36.60709214 H
OS 30.85800026 -36.60709214
OS 30.85800026 -36.9246785
OS 31.1436893 -36.9246785
OS 31.16033138 -36.92329166
OS 31.17974714 -36.92190482
OS 31.20193658 -36.92051798
OS 31.22412602 -36.9177443
OS 31.24631546 -36.91358378
OS 31.26573122 -36.90803642
OS 31.2685049 -36.90664958
OS 31.27405226 -36.9038759
OS 31.2823733 -36.89971538
OS 31.29346802 -36.89416802
OS 31.30594958 -36.88584698
OS 31.31843114 -36.8761391
OS 31.3309127 -36.86365754
OS 31.34062058 -36.84978914
OS 31.34200742 -36.8484023
OS 31.3447811 -36.84285494
OS 31.34894162 -36.8345339
OS 31.35448898 -36.82343918
OS 31.3586495 -36.81095762
OS 31.36281002 -36.79708922
OS 31.3655837 -36.78044714
OS 31.36697054 -36.76380506
OS 31.36697054 -36.76241822
OS 31.36697054 -36.76103138
OS 31.3655837 -36.75271034
OS 31.36419686 -36.74022878
OS 31.36142318 -36.7235867
OS 31.35448898 -36.70694462
OS 31.34616794 -36.68752886
OS 31.33368638 -36.66949994
OS 31.3170443 -36.65147102
OS 31.31427062 -36.65008418
OS 31.30733642 -36.64453682
OS 31.2962417 -36.63760262
OS 31.27821278 -36.62928158
OS 31.25741018 -36.62096054
OS 31.22967338 -36.61402634
OS 31.19777606 -36.60847898
OS 31.16033138 -36.60709214
OE
OB 36.29302622 -36.61402634 H
OS 36.06558446 -36.61402634
OS 36.06558446 -36.90248906
OS 36.30134726 -36.90248906
OS 36.31937618 -36.90110222
OS 36.33879194 -36.89971538
OS 36.3582077 -36.89832854
OS 36.37762346 -36.89555486
OS 36.3928787 -36.89278118
OS 36.39565238 -36.89139434
OS 36.40119974 -36.8900075
OS 36.40952078 -36.88584698
OS 36.4206155 -36.88029962
OS 36.43171022 -36.87475226
OS 36.44419178 -36.86643122
OS 36.45667334 -36.8553365
OS 36.46638122 -36.84424178
OS 36.46776806 -36.84285494
OS 36.47054174 -36.83869442
OS 36.47470226 -36.83037338
OS 36.47886278 -36.8206655
OS 36.4830233 -36.80957078
OS 36.48718382 -36.79570238
OS 36.4899575 -36.7790603
OS 36.49134434 -36.76103138
OS 36.49134434 -36.7582577
OS 36.49134434 -36.75271034
OS 36.4899575 -36.7443893
OS 36.48857066 -36.73329458
OS 36.48579698 -36.71942618
OS 36.48163646 -36.70555778
OS 36.4760891 -36.69168938
OS 36.46776806 -36.67782098
OS 36.46638122 -36.67643414
OS 36.46360754 -36.67227362
OS 36.45806018 -36.66533942
OS 36.45112598 -36.65840522
OS 36.4414181 -36.65008418
OS 36.43032338 -36.64176314
OS 36.41645498 -36.6334421
OS 36.40119974 -36.62789474
OS 36.3998129 -36.62789474
OS 36.3928787 -36.62512106
OS 36.38317082 -36.62373422
OS 36.36791558 -36.62096054
OS 36.34711298 -36.61818686
OS 36.3235367 -36.61680002
OS 36.29302622 -36.61402634
OE
OB 36.31798934 -37.01620994 H
OS 36.06558446 -37.01620994
OS 36.06558446 -37.34627786
OS 36.33879194 -37.34627786
OS 36.36791558 -37.34489102
OS 36.38039714 -37.34350418
OS 36.39149186 -37.34211734
OS 36.3928787 -37.34211734
OS 36.39842606 -37.3407305
OS 36.4067471 -37.33934366
OS 36.41645498 -37.33656998
OS 36.44003126 -37.32824894
OS 36.46360754 -37.31715422
OS 36.46499438 -37.31576738
OS 36.4691549 -37.3129937
OS 36.47470226 -37.30883318
OS 36.48163646 -37.30328582
OS 36.48857066 -37.29496478
OS 36.49827854 -37.28664374
OS 36.50521274 -37.27554902
OS 36.51353378 -37.26306746
OS 36.51492062 -37.26168062
OS 36.51630746 -37.2575201
OS 36.51908114 -37.24919906
OS 36.52324166 -37.23949118
OS 36.52740218 -37.22839646
OS 36.53017586 -37.21452806
OS 36.5315627 -37.19788598
OS 36.53294954 -37.1812439
OS 36.53294954 -37.17847022
OS 36.53294954 -37.17292286
OS 36.5315627 -37.16182814
OS 36.52878902 -37.14934658
OS 36.52601534 -37.13547818
OS 36.52046798 -37.12022294
OS 36.51353378 -37.1049677
OS 36.5038259 -37.08971246
OS 36.50243906 -37.08832562
OS 36.49827854 -37.08277826
OS 36.49273118 -37.07584406
OS 36.48441014 -37.06752302
OS 36.47331542 -37.05781514
OS 36.45944702 -37.04810726
OS 36.44419178 -37.03978622
OS 36.42616286 -37.03285202
OS 36.42338918 -37.03146518
OS 36.41784182 -37.03007834
OS 36.40536026 -37.02730466
OS 36.39010502 -37.02453098
OS 36.37068926 -37.0217573
OS 36.34711298 -37.01898362
OS 36.31798934 -37.01620994
OE
SE
S P 0
OB 40.9056459 -38.32112732 I
OS 40.92136342 -38.32205188
OS 40.9380055 -38.32297644
OS 40.95372302 -38.32482556
OS 40.96759142 -38.32667468
OS 40.96944054 -38.32667468
OS 40.97591246 -38.3285238
OS 40.9842335 -38.33037292
OS 40.99532822 -38.3331466
OS 41.0073475 -38.3377694
OS 41.02029134 -38.34331676
OS 41.03415974 -38.34978868
OS 41.04617902 -38.35718516
OS 41.04802814 -38.35810972
OS 41.05172638 -38.3608834
OS 41.05727374 -38.36643076
OS 41.06467022 -38.37290268
OS 41.07299126 -38.38122372
OS 41.0813123 -38.39231844
OS 41.0905579 -38.40433772
OS 41.09795438 -38.41820612
OS 41.09887894 -38.42005524
OS 41.10072806 -38.42467804
OS 41.1044263 -38.43299908
OS 41.10812454 -38.4440938
OS 41.11089822 -38.45703764
OS 41.11459646 -38.4718306
OS 41.11644558 -38.48847268
OS 41.11737014 -38.50603932
OS 41.11737014 -38.50696388
OS 41.11737014 -38.50973756
OS 41.11737014 -38.5134358
OS 41.11644558 -38.51990772
OS 41.11552102 -38.52637964
OS 41.11459646 -38.53470068
OS 41.11274734 -38.54394628
OS 41.11089822 -38.55411644
OS 41.1044263 -38.57538132
OS 41.10072806 -38.58647604
OS 41.0951807 -38.59849532
OS 41.08870878 -38.6105146
OS 41.08223686 -38.62160932
OS 41.07391582 -38.63270404
OS 41.06467022 -38.64379876
OS 41.06374566 -38.64472332
OS 41.06189654 -38.64657244
OS 41.05912286 -38.64934612
OS 41.05450006 -38.6521198
OS 41.0489527 -38.6567426
OS 41.04155622 -38.6613654
OS 41.03231062 -38.66691276
OS 41.02214046 -38.67153556
OS 41.01012118 -38.67708292
OS 40.99625278 -38.68263028
OS 40.98145982 -38.68725308
OS 40.96389318 -38.69095132
OS 40.94540198 -38.69464956
OS 40.92506166 -38.69742324
OS 40.90194766 -38.69927236
OS 40.8779091 -38.70019692
OS 40.71426198 -38.70019692
OS 40.71426198 -38.95999828
OS 40.62920246 -38.95999828
OS 40.62920246 -38.32020276
OS 40.8917775 -38.32020276
OS 40.9056459 -38.32112732
OE
OB 40.49791494 -38.98403684 I
OS 40.49791494 -38.9849614
OS 40.49791494 -38.98773508
OS 40.49791494 -38.99235788
OS 40.49791494 -38.99790524
OS 40.49699038 -39.00530172
OS 40.49699038 -39.0126982
OS 40.49514126 -39.0311894
OS 40.49236758 -39.05060516
OS 40.48866934 -39.07094548
OS 40.48312198 -39.08851212
OS 40.47942374 -39.09683316
OS 40.4757255 -39.10330508
OS 40.4757255 -39.10422964
OS 40.47480094 -39.1051542
OS 40.47017814 -39.109777
OS 40.46278166 -39.11717348
OS 40.45353606 -39.12549452
OS 40.44059222 -39.13381556
OS 40.42395014 -39.14028748
OS 40.40453438 -39.14583484
OS 40.39343966 -39.1467594
OS 40.38142038 -39.14768396
OS 40.37587302 -39.14768396
OS 40.37032566 -39.1467594
OS 40.36200462 -39.1467594
OS 40.35275902 -39.14583484
OS 40.34258886 -39.14398572
OS 40.32039942 -39.13843836
OS 40.33519238 -39.07187004
OS 40.33611694 -39.07187004
OS 40.33889062 -39.0727946
OS 40.34351342 -39.07371916
OS 40.34813622 -39.07464372
OS 40.3601555 -39.0774174
OS 40.36570286 -39.07834196
OS 40.37494846 -39.07834196
OS 40.37957126 -39.0774174
OS 40.38511862 -39.07649284
OS 40.39066598 -39.07464372
OS 40.39621334 -39.07094548
OS 40.40268526 -39.06724724
OS 40.40730806 -39.06169988
OS 40.40823262 -39.06077532
OS 40.40915718 -39.05800164
OS 40.4110063 -39.05337884
OS 40.41377998 -39.04598236
OS 40.4156291 -39.0358122
OS 40.41655366 -39.02841572
OS 40.41747822 -39.0219438
OS 40.41840278 -39.01362276
OS 40.41840278 -39.0034526
OS 40.41932734 -38.99328244
OS 40.41932734 -38.98218772
OS 40.41932734 -38.49586916
OS 40.49791494 -38.49586916
OS 40.49791494 -38.98403684
OE
OB 41.51770462 -38.3100326 I
OS 41.52602566 -38.31095716
OS 41.53619582 -38.31188172
OS 41.54636598 -38.31280628
OS 41.55838526 -38.31557996
OS 41.58334838 -38.32112732
OS 41.61108518 -38.32944836
OS 41.62495358 -38.33499572
OS 41.63789742 -38.34146764
OS 41.65084126 -38.34978868
OS 41.6637851 -38.35810972
OS 41.66470966 -38.35903428
OS 41.66655878 -38.35995884
OS 41.67025702 -38.36273252
OS 41.67487982 -38.36735532
OS 41.67950262 -38.37197812
OS 41.68597454 -38.37845004
OS 41.69244646 -38.38584652
OS 41.69984294 -38.393243
OS 41.70723942 -38.4024886
OS 41.7146359 -38.41358332
OS 41.72295694 -38.42467804
OS 41.73035342 -38.43669732
OS 41.73682534 -38.45056572
OS 41.74422182 -38.46443412
OS 41.74976918 -38.47922708
OS 41.75531654 -38.49586916
OS 41.67210614 -38.51528492
OS 41.67210614 -38.51436036
OS 41.67118158 -38.51251124
OS 41.66933246 -38.508813
OS 41.66748334 -38.5041902
OS 41.66563422 -38.49864284
OS 41.66286054 -38.49124636
OS 41.65546406 -38.4764534
OS 41.64621846 -38.45981132
OS 41.63512374 -38.44316924
OS 41.62125534 -38.42745172
OS 41.60646238 -38.41358332
OS 41.60461326 -38.4117342
OS 41.5990659 -38.40803596
OS 41.5898203 -38.40341316
OS 41.57780102 -38.39694124
OS 41.5620835 -38.39139388
OS 41.54451686 -38.38584652
OS 41.52325198 -38.38214828
OS 41.50013798 -38.38122372
OS 41.4927415 -38.38122372
OS 41.4881187 -38.38214828
OS 41.48164678 -38.38214828
OS 41.4742503 -38.38307284
OS 41.45668366 -38.38584652
OS 41.4372679 -38.38954476
OS 41.41692758 -38.39601668
OS 41.3956627 -38.40526228
OS 41.37624694 -38.41728156
OS 41.37532238 -38.41728156
OS 41.37439782 -38.41913068
OS 41.3679259 -38.42375348
OS 41.35960486 -38.43114996
OS 41.3494347 -38.44224468
OS 41.33741542 -38.45611308
OS 41.3263207 -38.4718306
OS 41.31615054 -38.49124636
OS 41.30690494 -38.51251124
OS 41.30690494 -38.5134358
OS 41.30598038 -38.51528492
OS 41.30505582 -38.5180586
OS 41.30413126 -38.5226814
OS 41.30228214 -38.52822876
OS 41.30043302 -38.53470068
OS 41.29765934 -38.5504182
OS 41.2939611 -38.5689094
OS 41.29026286 -38.58924972
OS 41.28841374 -38.61143916
OS 41.28748918 -38.63547772
OS 41.28748918 -38.63640228
OS 41.28748918 -38.63917596
OS 41.28748918 -38.64379876
OS 41.28748918 -38.64934612
OS 41.28841374 -38.65581804
OS 41.28841374 -38.66413908
OS 41.2893383 -38.67338468
OS 41.29026286 -38.68355484
OS 41.29303654 -38.70574428
OS 41.29765934 -38.72978284
OS 41.3032067 -38.7538214
OS 41.31060318 -38.77785996
OS 41.31060318 -38.77878452
OS 41.31152774 -38.78063364
OS 41.31337686 -38.78340732
OS 41.31522598 -38.78803012
OS 41.32077334 -38.79912484
OS 41.32909438 -38.81206868
OS 41.33926454 -38.82686164
OS 41.35220838 -38.84257916
OS 41.36700134 -38.85644756
OS 41.38456798 -38.8693914
OS 41.38549254 -38.8693914
OS 41.38734166 -38.87031596
OS 41.39011534 -38.87216508
OS 41.39381358 -38.8740142
OS 41.39843638 -38.87586332
OS 41.40398374 -38.878637
OS 41.41692758 -38.88418436
OS 41.43356966 -38.88973172
OS 41.45206086 -38.89435452
OS 41.47240118 -38.89805276
OS 41.49366606 -38.89897732
OS 41.50013798 -38.89897732
OS 41.50568534 -38.89805276
OS 41.51215726 -38.89805276
OS 41.51862918 -38.8971282
OS 41.53527126 -38.89342996
OS 41.55468702 -38.88880716
OS 41.57410278 -38.88141068
OS 41.5944431 -38.87124052
OS 41.60461326 -38.86569316
OS 41.61385886 -38.85829668
OS 41.61478342 -38.85737212
OS 41.61570798 -38.85644756
OS 41.61848166 -38.85367388
OS 41.6221799 -38.8509002
OS 41.62587814 -38.8462774
OS 41.63050094 -38.84073004
OS 41.6360483 -38.83518268
OS 41.6406711 -38.8277862
OS 41.64621846 -38.81946516
OS 41.65269038 -38.81021956
OS 41.65823774 -38.80097396
OS 41.6637851 -38.78987924
OS 41.6684079 -38.77785996
OS 41.6730307 -38.76491612
OS 41.6776535 -38.75104772
OS 41.68135174 -38.73625476
OS 41.76641126 -38.75751964
OS 41.76641126 -38.7584442
OS 41.7654867 -38.76214244
OS 41.76363758 -38.7676898
OS 41.7608639 -38.77508628
OS 41.75809022 -38.78340732
OS 41.75439198 -38.79357748
OS 41.74976918 -38.8046722
OS 41.74422182 -38.81669148
OS 41.73127798 -38.84257916
OS 41.7146359 -38.86846684
OS 41.70446574 -38.88141068
OS 41.69429558 -38.89435452
OS 41.68320086 -38.90544924
OS 41.67025702 -38.91654396
OS 41.66933246 -38.91746852
OS 41.66748334 -38.91931764
OS 41.66286054 -38.92116676
OS 41.65823774 -38.924865
OS 41.65084126 -38.9294878
OS 41.64344478 -38.9341106
OS 41.63327462 -38.9387334
OS 41.62310446 -38.9433562
OS 41.61108518 -38.94890356
OS 41.59814134 -38.95352636
OS 41.58427294 -38.95814916
OS 41.56947998 -38.96277196
OS 41.55376246 -38.9664702
OS 41.53712038 -38.96831932
OS 41.51955374 -38.97016844
OS 41.50106254 -38.971093
OS 41.49089238 -38.971093
OS 41.4834959 -38.97016844
OS 41.47517486 -38.97016844
OS 41.4650047 -38.96924388
OS 41.45390998 -38.96739476
OS 41.44096614 -38.96554564
OS 41.4141539 -38.96092284
OS 41.3864171 -38.95352636
OS 41.3586803 -38.9433562
OS 41.34573646 -38.93688428
OS 41.33279262 -38.9294878
OS 41.33186806 -38.92856324
OS 41.33001894 -38.92763868
OS 41.3263207 -38.924865
OS 41.32262246 -38.92116676
OS 41.3170751 -38.91746852
OS 41.31060318 -38.91192116
OS 41.3032067 -38.90544924
OS 41.29581022 -38.89805276
OS 41.28841374 -38.88973172
OS 41.2800927 -38.88141068
OS 41.26345062 -38.8601458
OS 41.2477331 -38.83518268
OS 41.2338647 -38.80744588
OS 41.2338647 -38.80652132
OS 41.23201558 -38.80374764
OS 41.23109102 -38.79912484
OS 41.22831734 -38.79357748
OS 41.22646822 -38.786181
OS 41.22369454 -38.7769354
OS 41.2199963 -38.76676524
OS 41.21722262 -38.75567052
OS 41.21444894 -38.74365124
OS 41.2107507 -38.72978284
OS 41.2061279 -38.70112148
OS 41.20242966 -38.66876188
OS 41.20058054 -38.63547772
OS 41.20058054 -38.63455316
OS 41.20058054 -38.63085492
OS 41.20058054 -38.62530756
OS 41.2015051 -38.61883564
OS 41.2015051 -38.60959004
OS 41.20242966 -38.60034444
OS 41.20335422 -38.58832516
OS 41.20520334 -38.57630588
OS 41.20982614 -38.54949364
OS 41.21629806 -38.51990772
OS 41.22554366 -38.4903218
OS 41.2384875 -38.46166044
OS 41.23941206 -38.46073588
OS 41.24033662 -38.4579622
OS 41.24218574 -38.45426396
OS 41.24588398 -38.44964116
OS 41.24958222 -38.44316924
OS 41.25420502 -38.43577276
OS 41.2662243 -38.41913068
OS 41.28194182 -38.40063948
OS 41.30043302 -38.38214828
OS 41.3216979 -38.36365708
OS 41.34666102 -38.34793956
OS 41.34758558 -38.347015
OS 41.35035926 -38.34609044
OS 41.3540575 -38.34424132
OS 41.3586803 -38.34146764
OS 41.36607678 -38.33869396
OS 41.37347326 -38.33592028
OS 41.38271886 -38.33222204
OS 41.39288902 -38.3285238
OS 41.40398374 -38.32482556
OS 41.41600302 -38.32112732
OS 41.4418907 -38.31557996
OS 41.47147662 -38.31095716
OS 41.5019871 -38.30910804
OS 41.5112327 -38.30910804
OS 41.51770462 -38.3100326
OE
OB 42.90454462 -39.1375138 I
OS 42.38401734 -39.1375138
OS 42.38401734 -39.08111564
OS 42.90454462 -39.08111564
OS 42.90454462 -39.1375138
OE
OB 42.12514054 -38.32112732 I
OS 42.13253702 -38.32112732
OS 42.1491791 -38.32297644
OS 42.1676703 -38.32482556
OS 42.18708606 -38.3285238
OS 42.20650182 -38.3331466
OS 42.22406846 -38.33961852
OS 42.22499302 -38.33961852
OS 42.22591758 -38.34054308
OS 42.23146494 -38.34331676
OS 42.23978598 -38.34793956
OS 42.24903158 -38.35441148
OS 42.2601263 -38.36273252
OS 42.27214558 -38.37290268
OS 42.2832403 -38.38584652
OS 42.29341046 -38.39971492
OS 42.29433502 -38.40156404
OS 42.2971087 -38.4071114
OS 42.3017315 -38.41450788
OS 42.3063543 -38.4256026
OS 42.3109771 -38.43854644
OS 42.3155999 -38.45241484
OS 42.31837358 -38.46813236
OS 42.31929814 -38.48384988
OS 42.31929814 -38.485699
OS 42.31929814 -38.4903218
OS 42.31837358 -38.49864284
OS 42.31652446 -38.508813
OS 42.31375078 -38.52083228
OS 42.30912798 -38.53377612
OS 42.30358062 -38.54671996
OS 42.29618414 -38.56058836
OS 42.29525958 -38.56243748
OS 42.2924859 -38.56613572
OS 42.28693854 -38.5735322
OS 42.27954206 -38.58092868
OS 42.27029646 -38.59017428
OS 42.25920174 -38.60034444
OS 42.24533334 -38.60959004
OS 42.22961582 -38.61883564
OS 42.23054038 -38.61883564
OS 42.2323895 -38.6197602
OS 42.23516318 -38.62068476
OS 42.23886142 -38.62253388
OS 42.24995614 -38.62623212
OS 42.26289998 -38.63270404
OS 42.27676838 -38.64102508
OS 42.2924859 -38.65119524
OS 42.3063543 -38.66321452
OS 42.31929814 -38.67800748
OS 42.3202227 -38.6798566
OS 42.32392094 -38.68540396
OS 42.3294683 -38.693725
OS 42.33501566 -38.70481972
OS 42.34056302 -38.71961268
OS 42.34611038 -38.7353302
OS 42.34980862 -38.7538214
OS 42.35073318 -38.77416172
OS 42.35073318 -38.77508628
OS 42.35073318 -38.77601084
OS 42.35073318 -38.7815582
OS 42.34980862 -38.7908038
OS 42.3479595 -38.80189852
OS 42.34611038 -38.81484236
OS 42.34241214 -38.82871076
OS 42.33778934 -38.84350372
OS 42.33131742 -38.85829668
OS 42.33039286 -38.8601458
OS 42.32761918 -38.8647686
OS 42.32392094 -38.87124052
OS 42.31837358 -38.88048612
OS 42.3109771 -38.88973172
OS 42.30358062 -38.89990188
OS 42.29433502 -38.91007204
OS 42.28416486 -38.91839308
OS 42.2832403 -38.91931764
OS 42.27954206 -38.92209132
OS 42.27307014 -38.92578956
OS 42.2647491 -38.9294878
OS 42.25457894 -38.93503516
OS 42.24255966 -38.94058252
OS 42.22961582 -38.94520532
OS 42.2138983 -38.94982812
OS 42.21204918 -38.94982812
OS 42.20650182 -38.95167724
OS 42.19725622 -38.9526018
OS 42.18523694 -38.95445092
OS 42.17044398 -38.95630004
OS 42.15287734 -38.95814916
OS 42.13346158 -38.95907372
OS 42.11127214 -38.95999828
OS 41.8671883 -38.95999828
OS 41.8671883 -38.32020276
OS 42.11866862 -38.32020276
OS 42.12514054 -38.32112732
OE
OB 40.30745558 -38.48662356 I
OS 40.31762574 -38.48847268
OS 40.32964502 -38.49217092
OS 40.34258886 -38.49679372
OS 40.35738182 -38.50326564
OS 40.37309934 -38.51158668
OS 40.34443798 -38.58370236
OS 40.34351342 -38.5827778
OS 40.33981518 -38.58092868
OS 40.33426782 -38.578155
OS 40.32687134 -38.57538132
OS 40.3185503 -38.57260764
OS 40.30838014 -38.56983396
OS 40.29820998 -38.56798484
OS 40.28803982 -38.56706028
OS 40.28341702 -38.56706028
OS 40.27879422 -38.56798484
OS 40.2723223 -38.5689094
OS 40.26585038 -38.57075852
OS 40.25752934 -38.5735322
OS 40.2492083 -38.57723044
OS 40.24181182 -38.5827778
OS 40.24088726 -38.58370236
OS 40.23811358 -38.58555148
OS 40.2353399 -38.58924972
OS 40.2307171 -38.59387252
OS 40.2260943 -38.60034444
OS 40.2214715 -38.60774092
OS 40.2168487 -38.61606196
OS 40.21315046 -38.62623212
OS 40.2122259 -38.62808124
OS 40.21130134 -38.6336286
OS 40.20945222 -38.64194964
OS 40.20667854 -38.65304436
OS 40.20390486 -38.66691276
OS 40.20205574 -38.68263028
OS 40.20113118 -38.69927236
OS 40.20020662 -38.71776356
OS 40.20020662 -38.95999828
OS 40.12161902 -38.95999828
OS 40.12161902 -38.49586916
OS 40.19281014 -38.49586916
OS 40.19281014 -38.56613572
OS 40.1937347 -38.56521116
OS 40.19743294 -38.55873924
OS 40.20205574 -38.5504182
OS 40.20945222 -38.54024804
OS 40.2168487 -38.53007788
OS 40.22516974 -38.51898316
OS 40.23349078 -38.50973756
OS 40.24181182 -38.50234108
OS 40.24273638 -38.50141652
OS 40.24551006 -38.4995674
OS 40.25105742 -38.49679372
OS 40.25660478 -38.49402004
OS 40.26400126 -38.49124636
OS 40.27324686 -38.48847268
OS 40.28249246 -38.48662356
OS 40.29266262 -38.485699
OS 40.29913454 -38.485699
OS 40.30745558 -38.48662356
OE
OB 39.48829542 -38.95999828 I
OS 39.3986131 -38.95999828
OS 39.3986131 -38.87031596
OS 39.48829542 -38.87031596
OS 39.48829542 -38.95999828
OE
OB 38.6404739 -38.95999828 I
OS 38.55171614 -38.95999828
OS 38.30393406 -38.32020276
OS 38.39639006 -38.32020276
OS 38.56281086 -38.78525644
OS 38.56281086 -38.786181
OS 38.56373542 -38.78803012
OS 38.56465998 -38.7908038
OS 38.5665091 -38.79450204
OS 38.56743366 -38.8000494
OS 38.56928278 -38.80559676
OS 38.57390558 -38.81946516
OS 38.57945294 -38.83518268
OS 38.5850003 -38.85274932
OS 38.59609502 -38.88973172
OS 38.59609502 -38.88880716
OS 38.59701958 -38.88695804
OS 38.59794414 -38.88418436
OS 38.5988687 -38.88048612
OS 38.60164238 -38.87031596
OS 38.60626518 -38.85644756
OS 38.61088798 -38.84073004
OS 38.61643534 -38.8231634
OS 38.62290726 -38.8046722
OS 38.63030374 -38.78525644
OS 38.80412102 -38.32020276
OS 38.8901051 -38.32020276
OS 38.6404739 -38.95999828
OE
OB 39.27564662 -38.42745172 I
OS 39.25438174 -38.54671996
OS 39.20538006 -38.54671996
OS 39.1859643 -38.42745172
OS 39.1859643 -38.32020276
OS 39.27564662 -38.32020276
OS 39.27564662 -38.42745172
OE
OB 40.49791494 -38.4117342 I
OS 40.41932734 -38.4117342
OS 40.41932734 -38.32020276
OS 40.49791494 -38.32020276
OS 40.49791494 -38.4117342
OE
OB 39.84517558 -38.48662356 I
OS 39.8516475 -38.48754812
OS 39.8655159 -38.48939724
OS 39.88215798 -38.49309548
OS 39.89972462 -38.49864284
OS 39.91729126 -38.50696388
OS 39.9348579 -38.51713404
OS 39.93578246 -38.51713404
OS 39.93670702 -38.51898316
OS 39.94225438 -38.5226814
OS 39.95057542 -38.53007788
OS 39.96074558 -38.53932348
OS 39.9718403 -38.55134276
OS 39.98293502 -38.56613572
OS 39.99402974 -38.58370236
OS 40.00327534 -38.60311812
OS 40.00327534 -38.60404268
OS 40.0041999 -38.6058918
OS 40.00512446 -38.60866548
OS 40.00697358 -38.61236372
OS 40.0088227 -38.61791108
OS 40.01067182 -38.624383
OS 40.01529462 -38.63917596
OS 40.01991742 -38.65766716
OS 40.02361566 -38.67800748
OS 40.02638934 -38.70112148
OS 40.0273139 -38.72516004
OS 40.0273139 -38.7260846
OS 40.0273139 -38.72793372
OS 40.0273139 -38.73163196
OS 40.0273139 -38.73717932
OS 40.02638934 -38.74365124
OS 40.02638934 -38.75104772
OS 40.02454022 -38.7676898
OS 40.02084198 -38.78803012
OS 40.01621918 -38.809295
OS 40.00974726 -38.83148444
OS 40.00142622 -38.85367388
OS 40.00142622 -38.85459844
OS 40.00050166 -38.85644756
OS 39.99865254 -38.85922124
OS 39.99680342 -38.86291948
OS 39.9903315 -38.87308964
OS 39.98201046 -38.88603348
OS 39.9718403 -38.89990188
OS 39.95889646 -38.91377028
OS 39.9441035 -38.92763868
OS 39.92653686 -38.94058252
OS 39.9256123 -38.94058252
OS 39.92468774 -38.94150708
OS 39.92191406 -38.9433562
OS 39.91821582 -38.94520532
OS 39.90897022 -38.94982812
OS 39.89602638 -38.95537548
OS 39.88030886 -38.96092284
OS 39.86366678 -38.96554564
OS 39.84425102 -38.96924388
OS 39.82483526 -38.97016844
OS 39.81836334 -38.97016844
OS 39.81096686 -38.96924388
OS 39.80172126 -38.96831932
OS 39.79062654 -38.9664702
OS 39.77860726 -38.96369652
OS 39.76658798 -38.95999828
OS 39.7545687 -38.95445092
OS 39.75364414 -38.95352636
OS 39.74902134 -38.95167724
OS 39.74347398 -38.947979
OS 39.7360775 -38.94243164
OS 39.72868102 -38.93688428
OS 39.71943542 -38.9294878
OS 39.71111438 -38.92116676
OS 39.7037179 -38.91192116
OS 39.7037179 -39.1375138
OS 39.6251303 -39.1375138
OS 39.6251303 -38.49586916
OS 39.69632142 -38.49586916
OS 39.69632142 -38.55689012
OS 39.69724598 -38.555041
OS 39.70094422 -38.55134276
OS 39.70556702 -38.54487084
OS 39.7129635 -38.53747436
OS 39.72128454 -38.52822876
OS 39.73053014 -38.51990772
OS 39.74162486 -38.51158668
OS 39.75271958 -38.5041902
OS 39.7545687 -38.50326564
OS 39.75826694 -38.50141652
OS 39.76566342 -38.49864284
OS 39.77490902 -38.4949446
OS 39.78600374 -38.49124636
OS 39.79894758 -38.48847268
OS 39.81374054 -38.48662356
OS 39.83038262 -38.485699
OS 39.84055278 -38.485699
OS 39.84517558 -38.48662356
OE
OB 44.92193454 -38.40988508 I
OS 44.84334694 -38.40988508
OS 44.84334694 -38.32020276
OS 44.92193454 -38.32020276
OS 44.92193454 -38.40988508
OE
OB 45.24553054 -38.48662356 I
OS 45.25385158 -38.48754812
OS 45.26309718 -38.48939724
OS 45.27326734 -38.49124636
OS 45.28528662 -38.49309548
OS 45.31024974 -38.50141652
OS 45.32319358 -38.50603932
OS 45.33613742 -38.51251124
OS 45.34908126 -38.51898316
OS 45.3620251 -38.52822876
OS 45.37404438 -38.53747436
OS 45.38606366 -38.54856908
OS 45.38698822 -38.54949364
OS 45.38883734 -38.55134276
OS 45.39161102 -38.555041
OS 45.39530926 -38.5596638
OS 45.39993206 -38.56613572
OS 45.40547942 -38.57445676
OS 45.41102678 -38.58370236
OS 45.41657414 -38.59387252
OS 45.4221215 -38.60496724
OS 45.42766886 -38.61883564
OS 45.43321622 -38.63270404
OS 45.43783902 -38.64842156
OS 45.44153726 -38.66506364
OS 45.44431094 -38.68263028
OS 45.44616006 -38.70112148
OS 45.44708462 -38.7214618
OS 45.44708462 -38.72238636
OS 45.44708462 -38.72516004
OS 45.44708462 -38.72978284
OS 45.44708462 -38.73625476
OS 45.44616006 -38.74365124
OS 45.4452355 -38.75289684
OS 45.4452355 -38.76214244
OS 45.44338638 -38.7723126
OS 45.4406127 -38.7954266
OS 45.43506534 -38.8185406
OS 45.42859342 -38.8416546
OS 45.41934782 -38.86291948
OS 45.41934782 -38.86384404
OS 45.41842326 -38.8647686
OS 45.41657414 -38.86754228
OS 45.41472502 -38.87124052
OS 45.4082531 -38.88048612
OS 45.39993206 -38.89158084
OS 45.38883734 -38.90452468
OS 45.37496894 -38.91746852
OS 45.35925142 -38.93041236
OS 45.34076022 -38.94243164
OS 45.33983566 -38.94243164
OS 45.3389111 -38.9433562
OS 45.33613742 -38.94520532
OS 45.33151462 -38.94705444
OS 45.32689182 -38.94890356
OS 45.32134446 -38.95075268
OS 45.30747606 -38.95630004
OS 45.29175854 -38.96092284
OS 45.27234278 -38.96554564
OS 45.25200246 -38.96924388
OS 45.22981302 -38.97016844
OS 45.22056742 -38.97016844
OS 45.21317094 -38.96924388
OS 45.2048499 -38.96831932
OS 45.1956043 -38.9664702
OS 45.18450958 -38.96462108
OS 45.17341486 -38.96277196
OS 45.14845174 -38.95537548
OS 45.13458334 -38.94982812
OS 45.1216395 -38.94428076
OS 45.10869566 -38.93688428
OS 45.09575182 -38.92856324
OS 45.08373254 -38.91931764
OS 45.07171326 -38.90822292
OS 45.0707887 -38.90729836
OS 45.06893958 -38.90544924
OS 45.0661659 -38.901751
OS 45.06246766 -38.89620364
OS 45.05784486 -38.88973172
OS 45.05322206 -38.88233524
OS 45.0476747 -38.87308964
OS 45.04212734 -38.86199492
OS 45.03657998 -38.84997564
OS 45.03103262 -38.83610724
OS 45.02640982 -38.82131428
OS 45.02178702 -38.80559676
OS 45.01808878 -38.78803012
OS 45.0153151 -38.76953892
OS 45.01346598 -38.7491986
OS 45.01254142 -38.72793372
OS 45.01254142 -38.7260846
OS 45.01254142 -38.72238636
OS 45.01346598 -38.71591444
OS 45.01346598 -38.70666884
OS 45.01439054 -38.69649868
OS 45.01623966 -38.68355484
OS 45.01808878 -38.670611
OS 45.02178702 -38.65581804
OS 45.02548526 -38.64102508
OS 45.03010806 -38.62530756
OS 45.03565542 -38.60866548
OS 45.0430519 -38.59294796
OS 45.05044838 -38.578155
OS 45.06061854 -38.56336204
OS 45.0707887 -38.54949364
OS 45.08373254 -38.53747436
OS 45.0846571 -38.5365498
OS 45.08650622 -38.53562524
OS 45.09020446 -38.53285156
OS 45.09482726 -38.52915332
OS 45.10037462 -38.52545508
OS 45.1077711 -38.52083228
OS 45.11516758 -38.51620948
OS 45.12441318 -38.51158668
OS 45.13458334 -38.50696388
OS 45.14567806 -38.50234108
OS 45.17064118 -38.49402004
OS 45.19930254 -38.48754812
OS 45.2140955 -38.48662356
OS 45.22981302 -38.485699
OS 45.23905862 -38.485699
OS 45.24553054 -38.48662356
OE
OB 44.92193454 -38.95999828 I
OS 44.84334694 -38.95999828
OS 44.84334694 -38.49586916
OS 44.92193454 -38.49586916
OS 44.92193454 -38.95999828
OE
OB 46.10722046 -38.42745172 I
OS 46.08595558 -38.54671996
OS 46.0369539 -38.54671996
OS 46.01753814 -38.42745172
OS 46.01753814 -38.32020276
OS 46.10722046 -38.32020276
OS 46.10722046 -38.42745172
OE
OB 45.77160518 -38.48662356 I
OS 45.78177534 -38.48754812
OS 45.79379462 -38.48939724
OS 45.80673846 -38.49217092
OS 45.82060686 -38.49586916
OS 45.8335507 -38.50141652
OS 45.83539982 -38.50234108
OS 45.83909806 -38.5041902
OS 45.84556998 -38.50696388
OS 45.85296646 -38.51158668
OS 45.86221206 -38.51713404
OS 45.8705331 -38.52453052
OS 45.87885414 -38.531927
OS 45.88625062 -38.5411726
OS 45.88717518 -38.54209716
OS 45.8890243 -38.5457954
OS 45.89179798 -38.5504182
OS 45.89642078 -38.55689012
OS 45.90011902 -38.56613572
OS 45.90381726 -38.57538132
OS 45.90844006 -38.58647604
OS 45.91121374 -38.59849532
OS 45.91121374 -38.59941988
OS 45.9121383 -38.60311812
OS 45.91306286 -38.60866548
OS 45.91398742 -38.61606196
OS 45.91398742 -38.62715668
OS 45.91491198 -38.64010052
OS 45.91583654 -38.65581804
OS 45.91583654 -38.6752338
OS 45.91583654 -38.95999828
OS 45.83724894 -38.95999828
OS 45.83724894 -38.67893204
OS 45.83724894 -38.67800748
OS 45.83724894 -38.67708292
OS 45.83724894 -38.670611
OS 45.83724894 -38.66228996
OS 45.83632438 -38.6521198
OS 45.83539982 -38.64010052
OS 45.8335507 -38.62808124
OS 45.83077702 -38.61698652
OS 45.82800334 -38.60681636
OS 45.82800334 -38.6058918
OS 45.82615422 -38.60311812
OS 45.82338054 -38.59849532
OS 45.82060686 -38.59294796
OS 45.81598406 -38.5874006
OS 45.8104367 -38.58092868
OS 45.80304022 -38.57445676
OS 45.79471918 -38.5689094
OS 45.79379462 -38.56798484
OS 45.79102094 -38.56613572
OS 45.78547358 -38.5642866
OS 45.77900166 -38.56151292
OS 45.77160518 -38.55873924
OS 45.76235958 -38.55596556
OS 45.75126486 -38.555041
OS 45.74017014 -38.55411644
OS 45.73554734 -38.55411644
OS 45.7318491 -38.555041
OS 45.7226035 -38.55596556
OS 45.71058422 -38.55781468
OS 45.69764038 -38.56243748
OS 45.68284742 -38.56798484
OS 45.66805446 -38.57538132
OS 45.65418606 -38.58647604
OS 45.65233694 -38.58832516
OS 45.6486387 -38.59294796
OS 45.64586502 -38.5966462
OS 45.64309134 -38.601269
OS 45.6393931 -38.60681636
OS 45.63661942 -38.61328828
OS 45.63292118 -38.62068476
OS 45.62922294 -38.62993036
OS 45.62644926 -38.64010052
OS 45.62367558 -38.65119524
OS 45.62182646 -38.66321452
OS 45.61997734 -38.67615836
OS 45.61812822 -38.69187588
OS 45.61812822 -38.7075934
OS 45.61812822 -38.95999828
OS 45.53954062 -38.95999828
OS 45.53954062 -38.49586916
OS 45.60980718 -38.49586916
OS 45.60980718 -38.56243748
OS 45.61073174 -38.56151292
OS 45.61258086 -38.55873924
OS 45.61535454 -38.555041
OS 45.61905278 -38.5504182
OS 45.62460014 -38.54487084
OS 45.63107206 -38.53839892
OS 45.63846854 -38.53100244
OS 45.64771414 -38.52360596
OS 45.65695974 -38.51713404
OS 45.66805446 -38.50973756
OS 45.68007374 -38.50326564
OS 45.69301758 -38.49771828
OS 45.70781054 -38.49309548
OS 45.7226035 -38.48939724
OS 45.73924558 -38.48662356
OS 45.75681222 -38.485699
OS 45.7642087 -38.485699
OS 45.77160518 -38.48662356
OE
OB 44.2756671 -38.95999828 I
OS 44.1970795 -38.95999828
OS 44.1970795 -38.49586916
OS 44.2756671 -38.49586916
OS 44.2756671 -38.95999828
OE
OB 43.4574315 -38.48662356 I
OS 43.46482798 -38.48754812
OS 43.47407358 -38.48939724
OS 43.48424374 -38.49124636
OS 43.49626302 -38.49402004
OS 43.50735774 -38.49679372
OS 43.52030158 -38.50141652
OS 43.53232086 -38.50603932
OS 43.5452647 -38.51251124
OS 43.55820854 -38.51990772
OS 43.57115238 -38.52822876
OS 43.58317166 -38.53839892
OS 43.59426638 -38.54949364
OS 43.59519094 -38.5504182
OS 43.59704006 -38.55226732
OS 43.59981374 -38.55596556
OS 43.60351198 -38.56151292
OS 43.60813478 -38.56798484
OS 43.61275758 -38.57538132
OS 43.61830494 -38.58462692
OS 43.6238523 -38.59572164
OS 43.62939966 -38.60774092
OS 43.63494702 -38.62068476
OS 43.63956982 -38.63547772
OS 43.64419262 -38.65119524
OS 43.64789086 -38.66876188
OS 43.65066454 -38.68725308
OS 43.65251366 -38.70666884
OS 43.65343822 -38.72793372
OS 43.65343822 -38.72885828
OS 43.65343822 -38.73255652
OS 43.65343822 -38.73902844
OS 43.65251366 -38.74827404
OS 43.30580366 -38.74827404
OS 43.30580366 -38.7491986
OS 43.30580366 -38.75197228
OS 43.30672822 -38.75567052
OS 43.30672822 -38.76121788
OS 43.30765278 -38.7676898
OS 43.3095019 -38.77508628
OS 43.31227558 -38.79172836
OS 43.31782294 -38.81021956
OS 43.32521942 -38.83055988
OS 43.33538958 -38.84905108
OS 43.34833342 -38.86569316
OS 43.34925798 -38.86569316
OS 43.35018254 -38.86754228
OS 43.3557299 -38.87216508
OS 43.36405094 -38.878637
OS 43.37514566 -38.88510892
OS 43.38993862 -38.8925054
OS 43.4065807 -38.89897732
OS 43.4250719 -38.90360012
OS 43.43524206 -38.90452468
OS 43.44633678 -38.90544924
OS 43.45373326 -38.90544924
OS 43.4620543 -38.90452468
OS 43.47222446 -38.90267556
OS 43.48331918 -38.89990188
OS 43.49626302 -38.89620364
OS 43.5082823 -38.89065628
OS 43.52030158 -38.8832598
OS 43.52122614 -38.88233524
OS 43.52584894 -38.878637
OS 43.5313963 -38.87308964
OS 43.53786822 -38.86569316
OS 43.5452647 -38.855523
OS 43.55358574 -38.84257916
OS 43.56190678 -38.8277862
OS 43.56930326 -38.81021956
OS 43.65066454 -38.82038972
OS 43.65066454 -38.82131428
OS 43.64973998 -38.8231634
OS 43.64881542 -38.82686164
OS 43.6469663 -38.832409
OS 43.64419262 -38.83795636
OS 43.64141894 -38.84535284
OS 43.63402246 -38.86107036
OS 43.62477686 -38.878637
OS 43.61183302 -38.8971282
OS 43.59704006 -38.91469484
OS 43.57854886 -38.93133692
OS 43.5776243 -38.93133692
OS 43.57577518 -38.93318604
OS 43.5730015 -38.93503516
OS 43.56930326 -38.93780884
OS 43.5637559 -38.94058252
OS 43.55820854 -38.9433562
OS 43.55081206 -38.94705444
OS 43.54249102 -38.95075268
OS 43.53324542 -38.95445092
OS 43.52399982 -38.95814916
OS 43.50088582 -38.96369652
OS 43.47499814 -38.96831932
OS 43.44633678 -38.97016844
OS 43.43616662 -38.97016844
OS 43.4296947 -38.96924388
OS 43.42137366 -38.96831932
OS 43.4112035 -38.9664702
OS 43.40010878 -38.96462108
OS 43.3880895 -38.96277196
OS 43.36220182 -38.95537548
OS 43.34833342 -38.94982812
OS 43.33538958 -38.94428076
OS 43.32152118 -38.93688428
OS 43.30857734 -38.92856324
OS 43.29655806 -38.91931764
OS 43.28453878 -38.90822292
OS 43.28361422 -38.90729836
OS 43.2817651 -38.90544924
OS 43.27899142 -38.901751
OS 43.27529318 -38.89620364
OS 43.27067038 -38.88973172
OS 43.26604758 -38.88233524
OS 43.26050022 -38.87308964
OS 43.25495286 -38.86291948
OS 43.2494055 -38.8509002
OS 43.24385814 -38.83795636
OS 43.23923534 -38.8231634
OS 43.23461254 -38.80744588
OS 43.2309143 -38.7908038
OS 43.22814062 -38.7723126
OS 43.2262915 -38.75289684
OS 43.22536694 -38.73255652
OS 43.22536694 -38.73163196
OS 43.22536694 -38.72700916
OS 43.22536694 -38.7214618
OS 43.2262915 -38.71314076
OS 43.22721606 -38.7029706
OS 43.22814062 -38.69187588
OS 43.22998974 -38.67893204
OS 43.23276342 -38.6659882
OS 43.2401599 -38.63640228
OS 43.2447827 -38.62160932
OS 43.25033006 -38.6058918
OS 43.25772654 -38.59109884
OS 43.26604758 -38.57723044
OS 43.27529318 -38.56336204
OS 43.28546334 -38.5504182
OS 43.2863879 -38.54949364
OS 43.28823702 -38.54764452
OS 43.29193526 -38.54487084
OS 43.29655806 -38.54024804
OS 43.30210542 -38.53562524
OS 43.3095019 -38.53007788
OS 43.31782294 -38.52360596
OS 43.3279931 -38.5180586
OS 43.33816326 -38.51158668
OS 43.35018254 -38.50603932
OS 43.36312638 -38.50049196
OS 43.37699478 -38.49586916
OS 43.39178774 -38.49124636
OS 43.40750526 -38.48847268
OS 43.42414734 -38.48662356
OS 43.44171398 -38.485699
OS 43.45095958 -38.485699
OS 43.4574315 -38.48662356
OE
OB 43.13938286 -38.48662356 I
OS 43.14955302 -38.48847268
OS 43.1615723 -38.49217092
OS 43.17451614 -38.49679372
OS 43.1893091 -38.50326564
OS 43.20502662 -38.51158668
OS 43.17636526 -38.58370236
OS 43.1754407 -38.5827778
OS 43.17174246 -38.58092868
OS 43.1661951 -38.578155
OS 43.15879862 -38.57538132
OS 43.15047758 -38.57260764
OS 43.14030742 -38.56983396
OS 43.13013726 -38.56798484
OS 43.1199671 -38.56706028
OS 43.1153443 -38.56706028
OS 43.1107215 -38.56798484
OS 43.10424958 -38.5689094
OS 43.09777766 -38.57075852
OS 43.08945662 -38.5735322
OS 43.08113558 -38.57723044
OS 43.0737391 -38.5827778
OS 43.07281454 -38.58370236
OS 43.07004086 -38.58555148
OS 43.06726718 -38.58924972
OS 43.06264438 -38.59387252
OS 43.05802158 -38.60034444
OS 43.05339878 -38.60774092
OS 43.04877598 -38.61606196
OS 43.04507774 -38.62623212
OS 43.04415318 -38.62808124
OS 43.04322862 -38.6336286
OS 43.0413795 -38.64194964
OS 43.03860582 -38.65304436
OS 43.03583214 -38.66691276
OS 43.03398302 -38.68263028
OS 43.03305846 -38.69927236
OS 43.0321339 -38.71776356
OS 43.0321339 -38.95999828
OS 42.9535463 -38.95999828
OS 42.9535463 -38.49586916
OS 43.02473742 -38.49586916
OS 43.02473742 -38.56613572
OS 43.02566198 -38.56521116
OS 43.02936022 -38.55873924
OS 43.03398302 -38.5504182
OS 43.0413795 -38.54024804
OS 43.04877598 -38.53007788
OS 43.05709702 -38.51898316
OS 43.06541806 -38.50973756
OS 43.0737391 -38.50234108
OS 43.07466366 -38.50141652
OS 43.07743734 -38.4995674
OS 43.0829847 -38.49679372
OS 43.08853206 -38.49402004
OS 43.09592854 -38.49124636
OS 43.10517414 -38.48847268
OS 43.11441974 -38.48662356
OS 43.1245899 -38.485699
OS 43.13106182 -38.485699
OS 43.13938286 -38.48662356
OE
OB 43.95022198 -38.95999828 I
OS 43.87533262 -38.95999828
OS 43.70059078 -38.49586916
OS 43.78380118 -38.49586916
OS 43.88365366 -38.77416172
OS 43.88365366 -38.77508628
OS 43.88457822 -38.77601084
OS 43.88550278 -38.77878452
OS 43.88642734 -38.7815582
OS 43.88920102 -38.7908038
OS 43.89289926 -38.80282308
OS 43.89752206 -38.81669148
OS 43.90306942 -38.832409
OS 43.90769222 -38.84997564
OS 43.91323958 -38.86754228
OS 43.91416414 -38.86569316
OS 43.9150887 -38.86107036
OS 43.91786238 -38.85367388
OS 43.92063606 -38.84257916
OS 43.92525886 -38.83055988
OS 43.92988166 -38.81484236
OS 43.93635358 -38.79820028
OS 43.9428255 -38.77970908
OS 44.04545166 -38.49586916
OS 44.12681294 -38.49586916
OS 43.95022198 -38.95999828
OE
OB 44.2756671 -38.40988508 I
OS 44.1970795 -38.40988508
OS 44.1970795 -38.32020276
OS 44.2756671 -38.32020276
OS 44.2756671 -38.40988508
OE
OB 44.5669035 -38.48662356 I
OS 44.5807719 -38.48754812
OS 44.59556486 -38.48939724
OS 44.61128238 -38.49309548
OS 44.62792446 -38.49679372
OS 44.64364198 -38.50234108
OS 44.64456654 -38.50234108
OS 44.6454911 -38.50326564
OS 44.6501139 -38.50511476
OS 44.65751038 -38.508813
OS 44.66675598 -38.5134358
OS 44.67692614 -38.51990772
OS 44.6870963 -38.5273042
OS 44.6963419 -38.53562524
OS 44.70466294 -38.54487084
OS 44.7055875 -38.5457954
OS 44.70743662 -38.54949364
OS 44.71113486 -38.55596556
OS 44.71575766 -38.56336204
OS 44.72038046 -38.57445676
OS 44.72500326 -38.58647604
OS 44.7287015 -38.60034444
OS 44.73239974 -38.61606196
OS 44.65566126 -38.62623212
OS 44.65566126 -38.624383
OS 44.6547367 -38.62068476
OS 44.65288758 -38.61421284
OS 44.6501139 -38.6058918
OS 44.6454911 -38.59757076
OS 44.63994374 -38.58832516
OS 44.63347182 -38.57907956
OS 44.62422622 -38.57075852
OS 44.62330166 -38.56983396
OS 44.61960342 -38.56798484
OS 44.61405606 -38.5642866
OS 44.60573502 -38.56058836
OS 44.59648942 -38.55689012
OS 44.58447014 -38.55319188
OS 44.56967718 -38.55134276
OS 44.55395966 -38.5504182
OS 44.54471406 -38.5504182
OS 44.53546846 -38.55134276
OS 44.52344918 -38.55226732
OS 44.5114299 -38.555041
OS 44.49848606 -38.55781468
OS 44.48646678 -38.56243748
OS 44.47629662 -38.5689094
OS 44.47537206 -38.56983396
OS 44.47259838 -38.57168308
OS 44.46890014 -38.57538132
OS 44.4652019 -38.58092868
OS 44.4605791 -38.58647604
OS 44.45688086 -38.59387252
OS 44.45410718 -38.60219356
OS 44.45318262 -38.6105146
OS 44.45318262 -38.61143916
OS 44.45318262 -38.61328828
OS 44.45410718 -38.61606196
OS 44.45410718 -38.6197602
OS 44.45688086 -38.6290058
OS 44.46242822 -38.6382514
OS 44.46335278 -38.63917596
OS 44.46427734 -38.64010052
OS 44.46612646 -38.6428742
OS 44.4698247 -38.64564788
OS 44.47352294 -38.64842156
OS 44.4790703 -38.6521198
OS 44.48554222 -38.65489348
OS 44.4929387 -38.65859172
OS 44.49386326 -38.65859172
OS 44.49571238 -38.65951628
OS 44.49941062 -38.66044084
OS 44.50588254 -38.66321452
OS 44.51512814 -38.6659882
OS 44.52714742 -38.66876188
OS 44.5345439 -38.67153556
OS 44.54286494 -38.67338468
OS 44.55211054 -38.67615836
OS 44.5622807 -38.67893204
OS 44.56320526 -38.67893204
OS 44.56597894 -38.6798566
OS 44.57060174 -38.68078116
OS 44.5761491 -38.68263028
OS 44.58262102 -38.6844794
OS 44.59094206 -38.68632852
OS 44.6085087 -38.69187588
OS 44.62792446 -38.69742324
OS 44.64734022 -38.70389516
OS 44.66490686 -38.71036708
OS 44.67230334 -38.71314076
OS 44.67877526 -38.71591444
OS 44.68062438 -38.716839
OS 44.68432262 -38.71868812
OS 44.68986998 -38.7214618
OS 44.69819102 -38.7260846
OS 44.70651206 -38.73163196
OS 44.7148331 -38.73902844
OS 44.72315414 -38.74734948
OS 44.73055062 -38.75659508
OS 44.73147518 -38.75751964
OS 44.7333243 -38.76121788
OS 44.73702254 -38.76676524
OS 44.74072078 -38.77508628
OS 44.74349446 -38.78525644
OS 44.7471927 -38.79635116
OS 44.74904182 -38.809295
OS 44.74996638 -38.82408796
OS 44.74996638 -38.82593708
OS 44.74996638 -38.83055988
OS 44.74904182 -38.83795636
OS 44.7471927 -38.84812652
OS 44.74441902 -38.85922124
OS 44.73979622 -38.87124052
OS 44.73424886 -38.88510892
OS 44.72685238 -38.89805276
OS 44.72592782 -38.89990188
OS 44.72222958 -38.90360012
OS 44.71760678 -38.91007204
OS 44.7102103 -38.91746852
OS 44.70004014 -38.92578956
OS 44.68894542 -38.93503516
OS 44.67600158 -38.9433562
OS 44.66028406 -38.95167724
OS 44.6593595 -38.95167724
OS 44.65843494 -38.9526018
OS 44.65288758 -38.95445092
OS 44.64364198 -38.9572246
OS 44.6316227 -38.96092284
OS 44.61682974 -38.96462108
OS 44.60018766 -38.96739476
OS 44.58262102 -38.96924388
OS 44.5622807 -38.97016844
OS 44.55395966 -38.97016844
OS 44.54748774 -38.96924388
OS 44.54009126 -38.96924388
OS 44.53084566 -38.96831932
OS 44.52160006 -38.96739476
OS 44.5114299 -38.96554564
OS 44.48924046 -38.96092284
OS 44.46612646 -38.95445092
OS 44.44393702 -38.94520532
OS 44.43376686 -38.93965796
OS 44.42452126 -38.93318604
OS 44.4235967 -38.93226148
OS 44.42267214 -38.93133692
OS 44.41712478 -38.92578956
OS 44.40880374 -38.91746852
OS 44.39955814 -38.90452468
OS 44.38938798 -38.88880716
OS 44.37921782 -38.87031596
OS 44.37089678 -38.84720196
OS 44.36442486 -38.82131428
OS 44.4420879 -38.809295
OS 44.4420879 -38.81021956
OS 44.4420879 -38.81114412
OS 44.44393702 -38.81669148
OS 44.44578614 -38.82593708
OS 44.44948438 -38.83610724
OS 44.45410718 -38.84720196
OS 44.45965454 -38.85922124
OS 44.46797558 -38.87124052
OS 44.47814574 -38.88141068
OS 44.47999486 -38.88233524
OS 44.4836931 -38.88510892
OS 44.49108958 -38.88880716
OS 44.50033518 -38.89342996
OS 44.51235446 -38.89805276
OS 44.52622286 -38.901751
OS 44.54286494 -38.90452468
OS 44.5622807 -38.90544924
OS 44.5715263 -38.90544924
OS 44.5807719 -38.90452468
OS 44.59279118 -38.90267556
OS 44.60573502 -38.89990188
OS 44.61960342 -38.89620364
OS 44.6316227 -38.89158084
OS 44.64271742 -38.88418436
OS 44.64364198 -38.8832598
OS 44.64734022 -38.88048612
OS 44.65103846 -38.87586332
OS 44.65658582 -38.8693914
OS 44.66120862 -38.86199492
OS 44.66583142 -38.85274932
OS 44.6686051 -38.84350372
OS 44.66952966 -38.832409
OS 44.66952966 -38.83148444
OS 44.66952966 -38.8277862
OS 44.6686051 -38.8231634
OS 44.66675598 -38.81669148
OS 44.6639823 -38.81021956
OS 44.6593595 -38.80374764
OS 44.65381214 -38.79635116
OS 44.6454911 -38.7908038
OS 44.64456654 -38.78987924
OS 44.64179286 -38.78895468
OS 44.63717006 -38.786181
OS 44.62977358 -38.78340732
OS 44.61867886 -38.77970908
OS 44.61220694 -38.7769354
OS 44.60481046 -38.77508628
OS 44.59648942 -38.7723126
OS 44.58724382 -38.76953892
OS 44.57707366 -38.76676524
OS 44.56505438 -38.76399156
OS 44.56412982 -38.76399156
OS 44.56135614 -38.763067
OS 44.55673334 -38.76214244
OS 44.55118598 -38.76029332
OS 44.5437895 -38.7584442
OS 44.53546846 -38.75567052
OS 44.51790182 -38.75104772
OS 44.4975615 -38.7445758
OS 44.47814574 -38.73902844
OS 44.45965454 -38.73255652
OS 44.4513335 -38.72885828
OS 44.44486158 -38.7260846
OS 44.44301246 -38.72516004
OS 44.43931422 -38.72331092
OS 44.43376686 -38.71961268
OS 44.42637038 -38.71498988
OS 44.41804934 -38.70851796
OS 44.4097283 -38.70112148
OS 44.40140726 -38.69280044
OS 44.39401078 -38.68263028
OS 44.39308622 -38.68170572
OS 44.3912371 -38.67800748
OS 44.38846342 -38.67153556
OS 44.38568974 -38.66413908
OS 44.38291606 -38.65489348
OS 44.38014238 -38.64379876
OS 44.37829326 -38.63270404
OS 44.3773687 -38.6197602
OS 44.3773687 -38.61791108
OS 44.3773687 -38.61421284
OS 44.37829326 -38.60866548
OS 44.37921782 -38.60034444
OS 44.38106694 -38.5920234
OS 44.38291606 -38.58185324
OS 44.3866143 -38.57260764
OS 44.3912371 -38.56243748
OS 44.39216166 -38.56151292
OS 44.39401078 -38.55781468
OS 44.39678446 -38.55319188
OS 44.40140726 -38.54671996
OS 44.40695462 -38.54024804
OS 44.41342654 -38.531927
OS 44.42082302 -38.52453052
OS 44.43006862 -38.5180586
OS 44.43099318 -38.51713404
OS 44.43376686 -38.51620948
OS 44.4374651 -38.5134358
OS 44.44301246 -38.51066212
OS 44.45040894 -38.50696388
OS 44.45872998 -38.50326564
OS 44.46890014 -38.4995674
OS 44.47999486 -38.49586916
OS 44.48184398 -38.4949446
OS 44.48554222 -38.49402004
OS 44.49201414 -38.49217092
OS 44.50033518 -38.4903218
OS 44.51050534 -38.48847268
OS 44.52160006 -38.48754812
OS 44.5345439 -38.485699
OS 44.55673334 -38.485699
OS 44.5669035 -38.48662356
OE
OB 33.15968222 -38.32112732 I
OS 33.17539974 -38.32205188
OS 33.19204182 -38.32297644
OS 33.20775934 -38.32482556
OS 33.22162774 -38.32667468
OS 33.22347686 -38.32667468
OS 33.22994878 -38.3285238
OS 33.23826982 -38.33037292
OS 33.24936454 -38.3331466
OS 33.26138382 -38.3377694
OS 33.27432766 -38.34331676
OS 33.28819606 -38.34978868
OS 33.30021534 -38.35718516
OS 33.30206446 -38.35810972
OS 33.3057627 -38.3608834
OS 33.31131006 -38.36643076
OS 33.31870654 -38.37290268
OS 33.32702758 -38.38122372
OS 33.33534862 -38.39231844
OS 33.34459422 -38.40433772
OS 33.3519907 -38.41820612
OS 33.35291526 -38.42005524
OS 33.35476438 -38.42467804
OS 33.35846262 -38.43299908
OS 33.36216086 -38.4440938
OS 33.36493454 -38.45703764
OS 33.36863278 -38.4718306
OS 33.3704819 -38.48847268
OS 33.37140646 -38.50603932
OS 33.37140646 -38.50696388
OS 33.37140646 -38.50973756
OS 33.37140646 -38.5134358
OS 33.3704819 -38.51990772
OS 33.36955734 -38.52637964
OS 33.36863278 -38.53470068
OS 33.36678366 -38.54394628
OS 33.36493454 -38.55411644
OS 33.35846262 -38.57538132
OS 33.35476438 -38.58647604
OS 33.34921702 -38.59849532
OS 33.3427451 -38.6105146
OS 33.33627318 -38.62160932
OS 33.32795214 -38.63270404
OS 33.31870654 -38.64379876
OS 33.31778198 -38.64472332
OS 33.31593286 -38.64657244
OS 33.31315918 -38.64934612
OS 33.30853638 -38.6521198
OS 33.30298902 -38.6567426
OS 33.29559254 -38.6613654
OS 33.28634694 -38.66691276
OS 33.27617678 -38.67153556
OS 33.2641575 -38.67708292
OS 33.2502891 -38.68263028
OS 33.23549614 -38.68725308
OS 33.2179295 -38.69095132
OS 33.1994383 -38.69464956
OS 33.17909798 -38.69742324
OS 33.15598398 -38.69927236
OS 33.13194542 -38.70019692
OS 32.9682983 -38.70019692
OS 32.9682983 -38.95999828
OS 32.88323878 -38.95999828
OS 32.88323878 -38.32020276
OS 33.14581382 -38.32020276
OS 33.15968222 -38.32112732
OE
OB 32.75195126 -38.98403684 I
OS 32.75195126 -38.9849614
OS 32.75195126 -38.98773508
OS 32.75195126 -38.99235788
OS 32.75195126 -38.99790524
OS 32.7510267 -39.00530172
OS 32.7510267 -39.0126982
OS 32.74917758 -39.0311894
OS 32.7464039 -39.05060516
OS 32.74270566 -39.07094548
OS 32.7371583 -39.08851212
OS 32.73346006 -39.09683316
OS 32.72976182 -39.10330508
OS 32.72976182 -39.10422964
OS 32.72883726 -39.1051542
OS 32.72421446 -39.109777
OS 32.71681798 -39.11717348
OS 32.70757238 -39.12549452
OS 32.69462854 -39.13381556
OS 32.67798646 -39.14028748
OS 32.6585707 -39.14583484
OS 32.64747598 -39.1467594
OS 32.6354567 -39.14768396
OS 32.62990934 -39.14768396
OS 32.62436198 -39.1467594
OS 32.61604094 -39.1467594
OS 32.60679534 -39.14583484
OS 32.59662518 -39.14398572
OS 32.57443574 -39.13843836
OS 32.5892287 -39.07187004
OS 32.59015326 -39.07187004
OS 32.59292694 -39.0727946
OS 32.59754974 -39.07371916
OS 32.60217254 -39.07464372
OS 32.61419182 -39.0774174
OS 32.61973918 -39.07834196
OS 32.62898478 -39.07834196
OS 32.63360758 -39.0774174
OS 32.63915494 -39.07649284
OS 32.6447023 -39.07464372
OS 32.65024966 -39.07094548
OS 32.65672158 -39.06724724
OS 32.66134438 -39.06169988
OS 32.66226894 -39.06077532
OS 32.6631935 -39.05800164
OS 32.66504262 -39.05337884
OS 32.6678163 -39.04598236
OS 32.66966542 -39.0358122
OS 32.67058998 -39.02841572
OS 32.67151454 -39.0219438
OS 32.6724391 -39.01362276
OS 32.6724391 -39.0034526
OS 32.67336366 -38.99328244
OS 32.67336366 -38.98218772
OS 32.67336366 -38.49586916
OS 32.75195126 -38.49586916
OS 32.75195126 -38.98403684
OE
OB 33.77174094 -38.3100326 I
OS 33.78006198 -38.31095716
OS 33.79023214 -38.31188172
OS 33.8004023 -38.31280628
OS 33.81242158 -38.31557996
OS 33.8373847 -38.32112732
OS 33.8651215 -38.32944836
OS 33.8789899 -38.33499572
OS 33.89193374 -38.34146764
OS 33.90487758 -38.34978868
OS 33.91782142 -38.35810972
OS 33.91874598 -38.35903428
OS 33.9205951 -38.35995884
OS 33.92429334 -38.36273252
OS 33.92891614 -38.36735532
OS 33.93353894 -38.37197812
OS 33.94001086 -38.37845004
OS 33.94648278 -38.38584652
OS 33.95387926 -38.393243
OS 33.96127574 -38.4024886
OS 33.96867222 -38.41358332
OS 33.97699326 -38.42467804
OS 33.98438974 -38.43669732
OS 33.99086166 -38.45056572
OS 33.99825814 -38.46443412
OS 34.0038055 -38.47922708
OS 34.00935286 -38.49586916
OS 33.92614246 -38.51528492
OS 33.92614246 -38.51436036
OS 33.9252179 -38.51251124
OS 33.92336878 -38.508813
OS 33.92151966 -38.5041902
OS 33.91967054 -38.49864284
OS 33.91689686 -38.49124636
OS 33.90950038 -38.4764534
OS 33.90025478 -38.45981132
OS 33.88916006 -38.44316924
OS 33.87529166 -38.42745172
OS 33.8604987 -38.41358332
OS 33.85864958 -38.4117342
OS 33.85310222 -38.40803596
OS 33.84385662 -38.40341316
OS 33.83183734 -38.39694124
OS 33.81611982 -38.39139388
OS 33.79855318 -38.38584652
OS 33.7772883 -38.38214828
OS 33.7541743 -38.38122372
OS 33.74677782 -38.38122372
OS 33.74215502 -38.38214828
OS 33.7356831 -38.38214828
OS 33.72828662 -38.38307284
OS 33.71071998 -38.38584652
OS 33.69130422 -38.38954476
OS 33.6709639 -38.39601668
OS 33.64969902 -38.40526228
OS 33.63028326 -38.41728156
OS 33.6293587 -38.41728156
OS 33.62843414 -38.41913068
OS 33.62196222 -38.42375348
OS 33.61364118 -38.43114996
OS 33.60347102 -38.44224468
OS 33.59145174 -38.45611308
OS 33.58035702 -38.4718306
OS 33.57018686 -38.49124636
OS 33.56094126 -38.51251124
OS 33.56094126 -38.5134358
OS 33.5600167 -38.51528492
OS 33.55909214 -38.5180586
OS 33.55816758 -38.5226814
OS 33.55631846 -38.52822876
OS 33.55446934 -38.53470068
OS 33.55169566 -38.5504182
OS 33.54799742 -38.5689094
OS 33.54429918 -38.58924972
OS 33.54245006 -38.61143916
OS 33.5415255 -38.63547772
OS 33.5415255 -38.63640228
OS 33.5415255 -38.63917596
OS 33.5415255 -38.64379876
OS 33.5415255 -38.64934612
OS 33.54245006 -38.65581804
OS 33.54245006 -38.66413908
OS 33.54337462 -38.67338468
OS 33.54429918 -38.68355484
OS 33.54707286 -38.70574428
OS 33.55169566 -38.72978284
OS 33.55724302 -38.7538214
OS 33.5646395 -38.77785996
OS 33.5646395 -38.77878452
OS 33.56556406 -38.78063364
OS 33.56741318 -38.78340732
OS 33.5692623 -38.78803012
OS 33.57480966 -38.79912484
OS 33.5831307 -38.81206868
OS 33.59330086 -38.82686164
OS 33.6062447 -38.84257916
OS 33.62103766 -38.85644756
OS 33.6386043 -38.8693914
OS 33.63952886 -38.8693914
OS 33.64137798 -38.87031596
OS 33.64415166 -38.87216508
OS 33.6478499 -38.8740142
OS 33.6524727 -38.87586332
OS 33.65802006 -38.878637
OS 33.6709639 -38.88418436
OS 33.68760598 -38.88973172
OS 33.70609718 -38.89435452
OS 33.7264375 -38.89805276
OS 33.74770238 -38.89897732
OS 33.7541743 -38.89897732
OS 33.75972166 -38.89805276
OS 33.76619358 -38.89805276
OS 33.7726655 -38.8971282
OS 33.78930758 -38.89342996
OS 33.80872334 -38.88880716
OS 33.8281391 -38.88141068
OS 33.84847942 -38.87124052
OS 33.85864958 -38.86569316
OS 33.86789518 -38.85829668
OS 33.86881974 -38.85737212
OS 33.8697443 -38.85644756
OS 33.87251798 -38.85367388
OS 33.87621622 -38.8509002
OS 33.87991446 -38.8462774
OS 33.88453726 -38.84073004
OS 33.89008462 -38.83518268
OS 33.89470742 -38.8277862
OS 33.90025478 -38.81946516
OS 33.9067267 -38.81021956
OS 33.91227406 -38.80097396
OS 33.91782142 -38.78987924
OS 33.92244422 -38.77785996
OS 33.92706702 -38.76491612
OS 33.93168982 -38.75104772
OS 33.93538806 -38.73625476
OS 34.02044758 -38.75751964
OS 34.02044758 -38.7584442
OS 34.01952302 -38.76214244
OS 34.0176739 -38.7676898
OS 34.01490022 -38.77508628
OS 34.01212654 -38.78340732
OS 34.0084283 -38.79357748
OS 34.0038055 -38.8046722
OS 33.99825814 -38.81669148
OS 33.9853143 -38.84257916
OS 33.96867222 -38.86846684
OS 33.95850206 -38.88141068
OS 33.9483319 -38.89435452
OS 33.93723718 -38.90544924
OS 33.92429334 -38.91654396
OS 33.92336878 -38.91746852
OS 33.92151966 -38.91931764
OS 33.91689686 -38.92116676
OS 33.91227406 -38.924865
OS 33.90487758 -38.9294878
OS 33.8974811 -38.9341106
OS 33.88731094 -38.9387334
OS 33.87714078 -38.9433562
OS 33.8651215 -38.94890356
OS 33.85217766 -38.95352636
OS 33.83830926 -38.95814916
OS 33.8235163 -38.96277196
OS 33.80779878 -38.9664702
OS 33.7911567 -38.96831932
OS 33.77359006 -38.97016844
OS 33.75509886 -38.971093
OS 33.7449287 -38.971093
OS 33.73753222 -38.97016844
OS 33.72921118 -38.97016844
OS 33.71904102 -38.96924388
OS 33.7079463 -38.96739476
OS 33.69500246 -38.96554564
OS 33.66819022 -38.96092284
OS 33.64045342 -38.95352636
OS 33.61271662 -38.9433562
OS 33.59977278 -38.93688428
OS 33.58682894 -38.9294878
OS 33.58590438 -38.92856324
OS 33.58405526 -38.92763868
OS 33.58035702 -38.924865
OS 33.57665878 -38.92116676
OS 33.57111142 -38.91746852
OS 33.5646395 -38.91192116
OS 33.55724302 -38.90544924
OS 33.54984654 -38.89805276
OS 33.54245006 -38.88973172
OS 33.53412902 -38.88141068
OS 33.51748694 -38.8601458
OS 33.50176942 -38.83518268
OS 33.48790102 -38.80744588
OS 33.48790102 -38.80652132
OS 33.4860519 -38.80374764
OS 33.48512734 -38.79912484
OS 33.48235366 -38.79357748
OS 33.48050454 -38.786181
OS 33.47773086 -38.7769354
OS 33.47403262 -38.76676524
OS 33.47125894 -38.75567052
OS 33.46848526 -38.74365124
OS 33.46478702 -38.72978284
OS 33.46016422 -38.70112148
OS 33.45646598 -38.66876188
OS 33.45461686 -38.63547772
OS 33.45461686 -38.63455316
OS 33.45461686 -38.63085492
OS 33.45461686 -38.62530756
OS 33.45554142 -38.61883564
OS 33.45554142 -38.60959004
OS 33.45646598 -38.60034444
OS 33.45739054 -38.58832516
OS 33.45923966 -38.57630588
OS 33.46386246 -38.54949364
OS 33.47033438 -38.51990772
OS 33.47957998 -38.4903218
OS 33.49252382 -38.46166044
OS 33.49344838 -38.46073588
OS 33.49437294 -38.4579622
OS 33.49622206 -38.45426396
OS 33.4999203 -38.44964116
OS 33.50361854 -38.44316924
OS 33.50824134 -38.43577276
OS 33.52026062 -38.41913068
OS 33.53597814 -38.40063948
OS 33.55446934 -38.38214828
OS 33.57573422 -38.36365708
OS 33.60069734 -38.34793956
OS 33.6016219 -38.347015
OS 33.60439558 -38.34609044
OS 33.60809382 -38.34424132
OS 33.61271662 -38.34146764
OS 33.6201131 -38.33869396
OS 33.62750958 -38.33592028
OS 33.63675518 -38.33222204
OS 33.64692534 -38.3285238
OS 33.65802006 -38.32482556
OS 33.67003934 -38.32112732
OS 33.69592702 -38.31557996
OS 33.72551294 -38.31095716
OS 33.75602342 -38.30910804
OS 33.76526902 -38.30910804
OS 33.77174094 -38.3100326
OE
OB 35.15858094 -39.1375138 I
OS 34.63805366 -39.1375138
OS 34.63805366 -39.08111564
OS 35.15858094 -39.08111564
OS 35.15858094 -39.1375138
OE
OB 34.37917686 -38.32112732 I
OS 34.38657334 -38.32112732
OS 34.40321542 -38.32297644
OS 34.42170662 -38.32482556
OS 34.44112238 -38.3285238
OS 34.46053814 -38.3331466
OS 34.47810478 -38.33961852
OS 34.47902934 -38.33961852
OS 34.4799539 -38.34054308
OS 34.48550126 -38.34331676
OS 34.4938223 -38.34793956
OS 34.5030679 -38.35441148
OS 34.51416262 -38.36273252
OS 34.5261819 -38.37290268
OS 34.53727662 -38.38584652
OS 34.54744678 -38.39971492
OS 34.54837134 -38.40156404
OS 34.55114502 -38.4071114
OS 34.55576782 -38.41450788
OS 34.56039062 -38.4256026
OS 34.56501342 -38.43854644
OS 34.56963622 -38.45241484
OS 34.5724099 -38.46813236
OS 34.57333446 -38.48384988
OS 34.57333446 -38.485699
OS 34.57333446 -38.4903218
OS 34.5724099 -38.49864284
OS 34.57056078 -38.508813
OS 34.5677871 -38.52083228
OS 34.5631643 -38.53377612
OS 34.55761694 -38.54671996
OS 34.55022046 -38.56058836
OS 34.5492959 -38.56243748
OS 34.54652222 -38.56613572
OS 34.54097486 -38.5735322
OS 34.53357838 -38.58092868
OS 34.52433278 -38.59017428
OS 34.51323806 -38.60034444
OS 34.49936966 -38.60959004
OS 34.48365214 -38.61883564
OS 34.4845767 -38.61883564
OS 34.48642582 -38.6197602
OS 34.4891995 -38.62068476
OS 34.49289774 -38.62253388
OS 34.50399246 -38.62623212
OS 34.5169363 -38.63270404
OS 34.5308047 -38.64102508
OS 34.54652222 -38.65119524
OS 34.56039062 -38.66321452
OS 34.57333446 -38.67800748
OS 34.57425902 -38.6798566
OS 34.57795726 -38.68540396
OS 34.58350462 -38.693725
OS 34.58905198 -38.70481972
OS 34.59459934 -38.71961268
OS 34.6001467 -38.7353302
OS 34.60384494 -38.7538214
OS 34.6047695 -38.77416172
OS 34.6047695 -38.77508628
OS 34.6047695 -38.77601084
OS 34.6047695 -38.7815582
OS 34.60384494 -38.7908038
OS 34.60199582 -38.80189852
OS 34.6001467 -38.81484236
OS 34.59644846 -38.82871076
OS 34.59182566 -38.84350372
OS 34.58535374 -38.85829668
OS 34.58442918 -38.8601458
OS 34.5816555 -38.8647686
OS 34.57795726 -38.87124052
OS 34.5724099 -38.88048612
OS 34.56501342 -38.88973172
OS 34.55761694 -38.89990188
OS 34.54837134 -38.91007204
OS 34.53820118 -38.91839308
OS 34.53727662 -38.91931764
OS 34.53357838 -38.92209132
OS 34.52710646 -38.92578956
OS 34.51878542 -38.9294878
OS 34.50861526 -38.93503516
OS 34.49659598 -38.94058252
OS 34.48365214 -38.94520532
OS 34.46793462 -38.94982812
OS 34.4660855 -38.94982812
OS 34.46053814 -38.95167724
OS 34.45129254 -38.9526018
OS 34.43927326 -38.95445092
OS 34.4244803 -38.95630004
OS 34.40691366 -38.95814916
OS 34.3874979 -38.95907372
OS 34.36530846 -38.95999828
OS 34.12122462 -38.95999828
OS 34.12122462 -38.32020276
OS 34.37270494 -38.32020276
OS 34.37917686 -38.32112732
OE
OB 31.74233174 -38.95999828 I
OS 31.65264942 -38.95999828
OS 31.65264942 -38.87031596
OS 31.74233174 -38.87031596
OS 31.74233174 -38.95999828
OE
OB 31.52968294 -38.42745172 I
OS 31.50841806 -38.54671996
OS 31.45941638 -38.54671996
OS 31.44000062 -38.42745172
OS 31.44000062 -38.32020276
OS 31.52968294 -38.32020276
OS 31.52968294 -38.42745172
OE
OB 32.0992119 -38.48662356 I
OS 32.10568382 -38.48754812
OS 32.11955222 -38.48939724
OS 32.1361943 -38.49309548
OS 32.15376094 -38.49864284
OS 32.17132758 -38.50696388
OS 32.18889422 -38.51713404
OS 32.18981878 -38.51713404
OS 32.19074334 -38.51898316
OS 32.1962907 -38.5226814
OS 32.20461174 -38.53007788
OS 32.2147819 -38.53932348
OS 32.22587662 -38.55134276
OS 32.23697134 -38.56613572
OS 32.24806606 -38.58370236
OS 32.25731166 -38.60311812
OS 32.25731166 -38.60404268
OS 32.25823622 -38.6058918
OS 32.25916078 -38.60866548
OS 32.2610099 -38.61236372
OS 32.26285902 -38.61791108
OS 32.26470814 -38.624383
OS 32.26933094 -38.63917596
OS 32.27395374 -38.65766716
OS 32.27765198 -38.67800748
OS 32.28042566 -38.70112148
OS 32.28135022 -38.72516004
OS 32.28135022 -38.7260846
OS 32.28135022 -38.72793372
OS 32.28135022 -38.73163196
OS 32.28135022 -38.73717932
OS 32.28042566 -38.74365124
OS 32.28042566 -38.75104772
OS 32.27857654 -38.7676898
OS 32.2748783 -38.78803012
OS 32.2702555 -38.809295
OS 32.26378358 -38.83148444
OS 32.25546254 -38.85367388
OS 32.25546254 -38.85459844
OS 32.25453798 -38.85644756
OS 32.25268886 -38.85922124
OS 32.25083974 -38.86291948
OS 32.24436782 -38.87308964
OS 32.23604678 -38.88603348
OS 32.22587662 -38.89990188
OS 32.21293278 -38.91377028
OS 32.19813982 -38.92763868
OS 32.18057318 -38.94058252
OS 32.17964862 -38.94058252
OS 32.17872406 -38.94150708
OS 32.17595038 -38.9433562
OS 32.17225214 -38.94520532
OS 32.16300654 -38.94982812
OS 32.1500627 -38.95537548
OS 32.13434518 -38.96092284
OS 32.1177031 -38.96554564
OS 32.09828734 -38.96924388
OS 32.07887158 -38.97016844
OS 32.07239966 -38.97016844
OS 32.06500318 -38.96924388
OS 32.05575758 -38.96831932
OS 32.04466286 -38.9664702
OS 32.03264358 -38.96369652
OS 32.0206243 -38.95999828
OS 32.00860502 -38.95445092
OS 32.00768046 -38.95352636
OS 32.00305766 -38.95167724
OS 31.9975103 -38.947979
OS 31.99011382 -38.94243164
OS 31.98271734 -38.93688428
OS 31.97347174 -38.9294878
OS 31.9651507 -38.92116676
OS 31.95775422 -38.91192116
OS 31.95775422 -39.1375138
OS 31.87916662 -39.1375138
OS 31.87916662 -38.49586916
OS 31.95035774 -38.49586916
OS 31.95035774 -38.55689012
OS 31.9512823 -38.555041
OS 31.95498054 -38.55134276
OS 31.95960334 -38.54487084
OS 31.96699982 -38.53747436
OS 31.97532086 -38.52822876
OS 31.98456646 -38.51990772
OS 31.99566118 -38.51158668
OS 32.0067559 -38.5041902
OS 32.00860502 -38.50326564
OS 32.01230326 -38.50141652
OS 32.01969974 -38.49864284
OS 32.02894534 -38.4949446
OS 32.04004006 -38.49124636
OS 32.0529839 -38.48847268
OS 32.06777686 -38.48662356
OS 32.08441894 -38.485699
OS 32.0945891 -38.485699
OS 32.0992119 -38.48662356
OE
OB 32.5614919 -38.48662356 I
OS 32.57166206 -38.48847268
OS 32.58368134 -38.49217092
OS 32.59662518 -38.49679372
OS 32.61141814 -38.50326564
OS 32.62713566 -38.51158668
OS 32.5984743 -38.58370236
OS 32.59754974 -38.5827778
OS 32.5938515 -38.58092868
OS 32.58830414 -38.578155
OS 32.58090766 -38.57538132
OS 32.57258662 -38.57260764
OS 32.56241646 -38.56983396
OS 32.5522463 -38.56798484
OS 32.54207614 -38.56706028
OS 32.53745334 -38.56706028
OS 32.53283054 -38.56798484
OS 32.52635862 -38.5689094
OS 32.5198867 -38.57075852
OS 32.51156566 -38.5735322
OS 32.50324462 -38.57723044
OS 32.49584814 -38.5827778
OS 32.49492358 -38.58370236
OS 32.4921499 -38.58555148
OS 32.48937622 -38.58924972
OS 32.48475342 -38.59387252
OS 32.48013062 -38.60034444
OS 32.47550782 -38.60774092
OS 32.47088502 -38.61606196
OS 32.46718678 -38.62623212
OS 32.46626222 -38.62808124
OS 32.46533766 -38.6336286
OS 32.46348854 -38.64194964
OS 32.46071486 -38.65304436
OS 32.45794118 -38.66691276
OS 32.45609206 -38.68263028
OS 32.4551675 -38.69927236
OS 32.45424294 -38.71776356
OS 32.45424294 -38.95999828
OS 32.37565534 -38.95999828
OS 32.37565534 -38.49586916
OS 32.44684646 -38.49586916
OS 32.44684646 -38.56613572
OS 32.44777102 -38.56521116
OS 32.45146926 -38.55873924
OS 32.45609206 -38.5504182
OS 32.46348854 -38.54024804
OS 32.47088502 -38.53007788
OS 32.47920606 -38.51898316
OS 32.4875271 -38.50973756
OS 32.49584814 -38.50234108
OS 32.4967727 -38.50141652
OS 32.49954638 -38.4995674
OS 32.50509374 -38.49679372
OS 32.5106411 -38.49402004
OS 32.51803758 -38.49124636
OS 32.52728318 -38.48847268
OS 32.53652878 -38.48662356
OS 32.54669894 -38.485699
OS 32.55317086 -38.485699
OS 32.5614919 -38.48662356
OE
OB 32.75195126 -38.4117342 I
OS 32.67336366 -38.4117342
OS 32.67336366 -38.32020276
OS 32.75195126 -38.32020276
OS 32.75195126 -38.4117342
OE
OB 36.56668582 -38.95999828 I
OS 36.47885262 -38.95999828
OS 36.1441619 -38.4579622
OS 36.1441619 -38.95999828
OS 36.06280062 -38.95999828
OS 36.06280062 -38.32020276
OS 36.14970926 -38.32020276
OS 36.48532454 -38.8231634
OS 36.48532454 -38.32020276
OS 36.56668582 -38.32020276
OS 36.56668582 -38.95999828
OE
OB 35.74382742 -38.32112732 I
OS 35.75954494 -38.32205188
OS 35.77618702 -38.32297644
OS 35.79190454 -38.32482556
OS 35.80577294 -38.32667468
OS 35.80762206 -38.32667468
OS 35.81409398 -38.3285238
OS 35.82241502 -38.33037292
OS 35.83350974 -38.3331466
OS 35.84552902 -38.3377694
OS 35.85847286 -38.34331676
OS 35.87234126 -38.34978868
OS 35.88436054 -38.35718516
OS 35.88620966 -38.35810972
OS 35.8899079 -38.3608834
OS 35.89545526 -38.36643076
OS 35.90285174 -38.37290268
OS 35.91117278 -38.38122372
OS 35.91949382 -38.39231844
OS 35.92873942 -38.40433772
OS 35.9361359 -38.41820612
OS 35.93706046 -38.42005524
OS 35.93890958 -38.42467804
OS 35.94260782 -38.43299908
OS 35.94630606 -38.4440938
OS 35.94907974 -38.45703764
OS 35.95277798 -38.4718306
OS 35.9546271 -38.48847268
OS 35.95555166 -38.50603932
OS 35.95555166 -38.50696388
OS 35.95555166 -38.50973756
OS 35.95555166 -38.5134358
OS 35.9546271 -38.51990772
OS 35.95370254 -38.52637964
OS 35.95277798 -38.53470068
OS 35.95092886 -38.54394628
OS 35.94907974 -38.55411644
OS 35.94260782 -38.57538132
OS 35.93890958 -38.58647604
OS 35.93336222 -38.59849532
OS 35.9268903 -38.6105146
OS 35.92041838 -38.62160932
OS 35.91209734 -38.63270404
OS 35.90285174 -38.64379876
OS 35.90192718 -38.64472332
OS 35.90007806 -38.64657244
OS 35.89730438 -38.64934612
OS 35.89268158 -38.6521198
OS 35.88713422 -38.6567426
OS 35.87973774 -38.6613654
OS 35.87049214 -38.66691276
OS 35.86032198 -38.67153556
OS 35.8483027 -38.67708292
OS 35.8344343 -38.68263028
OS 35.81964134 -38.68725308
OS 35.8020747 -38.69095132
OS 35.7835835 -38.69464956
OS 35.76324318 -38.69742324
OS 35.74012918 -38.69927236
OS 35.71609062 -38.70019692
OS 35.5524435 -38.70019692
OS 35.5524435 -38.95999828
OS 35.46738398 -38.95999828
OS 35.46738398 -38.32020276
OS 35.72995902 -38.32020276
OS 35.74382742 -38.32112732
OE
OB 36.76916446 -38.42745172 I
OS 36.74789958 -38.54671996
OS 36.6988979 -38.54671996
OS 36.67948214 -38.42745172
OS 36.67948214 -38.32020276
OS 36.76916446 -38.32020276
OS 36.76916446 -38.42745172
OE
OB 38.2382903 -38.39601668 I
OS 37.86014526 -38.39601668
OS 37.86014526 -38.59109884
OS 38.21425174 -38.59109884
OS 38.21425174 -38.66691276
OS 37.86014526 -38.66691276
OS 37.86014526 -38.88418436
OS 38.25308326 -38.88418436
OS 38.25308326 -38.95999828
OS 37.77508574 -38.95999828
OS 37.77508574 -38.32020276
OS 38.2382903 -38.32020276
OS 38.2382903 -38.39601668
OE
OB 37.4339231 -38.32112732 I
OS 37.44224414 -38.32112732
OS 37.4616599 -38.32205188
OS 37.48200022 -38.32482556
OS 37.50418966 -38.32759924
OS 37.52452998 -38.33222204
OS 37.53470014 -38.33499572
OS 37.54302118 -38.3377694
OS 37.54394574 -38.3377694
OS 37.5448703 -38.33869396
OS 37.55041766 -38.34146764
OS 37.5587387 -38.34516588
OS 37.56890886 -38.3516378
OS 37.58000358 -38.35995884
OS 37.59202286 -38.37105356
OS 37.60311758 -38.3839974
OS 37.6142123 -38.39879036
OS 37.6142123 -38.39971492
OS 37.61513686 -38.40063948
OS 37.6188351 -38.40618684
OS 37.62253334 -38.41543244
OS 37.6280807 -38.42745172
OS 37.6327035 -38.44132012
OS 37.6373263 -38.4579622
OS 37.64009998 -38.47552884
OS 37.64102454 -38.4949446
OS 37.64102454 -38.49586916
OS 37.64102454 -38.49771828
OS 37.64102454 -38.50141652
OS 37.64009998 -38.50603932
OS 37.64009998 -38.51251124
OS 37.63917542 -38.51898316
OS 37.63547718 -38.53470068
OS 37.62992982 -38.55319188
OS 37.62253334 -38.57260764
OS 37.61143862 -38.5920234
OS 37.60404214 -38.601269
OS 37.59664566 -38.6105146
OS 37.5957211 -38.61143916
OS 37.59479654 -38.61236372
OS 37.59202286 -38.6151374
OS 37.58832462 -38.61791108
OS 37.58370182 -38.62160932
OS 37.57815446 -38.62530756
OS 37.57075798 -38.62993036
OS 37.5633615 -38.63547772
OS 37.5541159 -38.64010052
OS 37.54394574 -38.64472332
OS 37.53285102 -38.65027068
OS 37.52083174 -38.65489348
OS 37.50696334 -38.65859172
OS 37.49309494 -38.66321452
OS 37.47737742 -38.6659882
OS 37.46073534 -38.66876188
OS 37.46258446 -38.66968644
OS 37.4662827 -38.67153556
OS 37.47183006 -38.6752338
OS 37.47922654 -38.67893204
OS 37.49586862 -38.6891022
OS 37.50418966 -38.69557412
OS 37.51158614 -38.70112148
OS 37.51343526 -38.7029706
OS 37.51805806 -38.7075934
OS 37.52545454 -38.71498988
OS 37.53470014 -38.72423548
OS 37.5448703 -38.73717932
OS 37.55688958 -38.75104772
OS 37.56890886 -38.7676898
OS 37.5818527 -38.786181
OS 37.69187534 -38.95999828
OS 37.5864755 -38.95999828
OS 37.50234054 -38.82686164
OS 37.50234054 -38.82593708
OS 37.50049142 -38.82408796
OS 37.4986423 -38.82131428
OS 37.49586862 -38.81761604
OS 37.4893967 -38.80744588
OS 37.48107566 -38.79450204
OS 37.4709055 -38.78063364
OS 37.46073534 -38.76584068
OS 37.45056518 -38.75197228
OS 37.44131958 -38.73902844
OS 37.44039502 -38.73810388
OS 37.43762134 -38.73440564
OS 37.43299854 -38.72885828
OS 37.42652662 -38.72238636
OS 37.41265822 -38.70851796
OS 37.40526174 -38.70204604
OS 37.39786526 -38.69649868
OS 37.3969407 -38.69557412
OS 37.39509158 -38.69464956
OS 37.39139334 -38.69280044
OS 37.38584598 -38.69002676
OS 37.38029862 -38.68725308
OS 37.3738267 -38.6844794
OS 37.35903374 -38.6798566
OS 37.35810918 -38.6798566
OS 37.35626006 -38.67893204
OS 37.35256182 -38.67893204
OS 37.34793902 -38.67800748
OS 37.3414671 -38.67708292
OS 37.33407062 -38.67708292
OS 37.32390046 -38.67615836
OS 37.21480238 -38.67615836
OS 37.21480238 -38.95999828
OS 37.12974286 -38.95999828
OS 37.12974286 -38.32020276
OS 37.42652662 -38.32020276
OS 37.4339231 -38.32112732
OE
OB 35.31760526 -38.95999828 I
OS 35.23254574 -38.95999828
OS 35.23254574 -38.32020276
OS 35.31760526 -38.32020276
OS 35.31760526 -38.95999828
OE
OB 42.12051774 -38.66413908 H
OS 41.95224782 -38.66413908
OS 41.95224782 -38.88418436
OS 42.13438614 -38.88418436
OS 42.1538019 -38.8832598
OS 42.16212294 -38.88233524
OS 42.16951942 -38.88141068
OS 42.17044398 -38.88141068
OS 42.17414222 -38.88048612
OS 42.17968958 -38.87956156
OS 42.1861615 -38.87771244
OS 42.20187902 -38.87216508
OS 42.21759654 -38.8647686
OS 42.2185211 -38.86384404
OS 42.22129478 -38.86199492
OS 42.22499302 -38.85922124
OS 42.22961582 -38.855523
OS 42.23423862 -38.84997564
OS 42.24071054 -38.84442828
OS 42.24533334 -38.8370318
OS 42.2508807 -38.82871076
OS 42.25180526 -38.8277862
OS 42.25272982 -38.82501252
OS 42.25457894 -38.81946516
OS 42.25735262 -38.81299324
OS 42.2601263 -38.80559676
OS 42.26197542 -38.79635116
OS 42.26289998 -38.78525644
OS 42.26382454 -38.77416172
OS 42.26382454 -38.7723126
OS 42.26382454 -38.76861436
OS 42.26289998 -38.76121788
OS 42.26105086 -38.75289684
OS 42.25920174 -38.74365124
OS 42.2555035 -38.73348108
OS 42.2508807 -38.72331092
OS 42.24440878 -38.71314076
OS 42.24348422 -38.7122162
OS 42.24071054 -38.70851796
OS 42.2370123 -38.70389516
OS 42.23146494 -38.6983478
OS 42.22406846 -38.69187588
OS 42.21482286 -38.68540396
OS 42.2046527 -38.6798566
OS 42.19263342 -38.6752338
OS 42.1907843 -38.67430924
OS 42.18708606 -38.67338468
OS 42.17876502 -38.67153556
OS 42.16859486 -38.66968644
OS 42.15565102 -38.66783732
OS 42.1399335 -38.6659882
OS 42.12051774 -38.66413908
OE
OB 45.22981302 -38.5504182 H
OS 45.22426566 -38.5504182
OS 45.21964286 -38.55134276
OS 45.2094727 -38.55226732
OS 45.1956043 -38.55596556
OS 45.17988678 -38.56151292
OS 45.1632447 -38.5689094
OS 45.14752718 -38.58000412
OS 45.13920614 -38.5874006
OS 45.13180966 -38.59479708
OS 45.13180966 -38.59572164
OS 45.12996054 -38.5966462
OS 45.12811142 -38.59941988
OS 45.12533774 -38.60311812
OS 45.12256406 -38.60774092
OS 45.11979038 -38.61328828
OS 45.11609214 -38.62068476
OS 45.1123939 -38.62808124
OS 45.10869566 -38.63732684
OS 45.10499742 -38.64657244
OS 45.10222374 -38.65766716
OS 45.09945006 -38.66968644
OS 45.09667638 -38.68263028
OS 45.09482726 -38.69649868
OS 45.0939027 -38.7122162
OS 45.09297814 -38.72793372
OS 45.09297814 -38.72885828
OS 45.09297814 -38.73163196
OS 45.09297814 -38.73625476
OS 45.0939027 -38.74272668
OS 45.0939027 -38.75012316
OS 45.09482726 -38.7584442
OS 45.09760094 -38.77785996
OS 45.10222374 -38.8000494
OS 45.10962022 -38.82223884
OS 45.11886582 -38.84350372
OS 45.12533774 -38.85274932
OS 45.13180966 -38.86199492
OS 45.13273422 -38.86199492
OS 45.13365878 -38.86384404
OS 45.13920614 -38.86846684
OS 45.14752718 -38.87586332
OS 45.1586219 -38.8832598
OS 45.1724903 -38.89158084
OS 45.18913238 -38.89897732
OS 45.20854814 -38.90360012
OS 45.2187183 -38.90452468
OS 45.22981302 -38.90544924
OS 45.23536038 -38.90544924
OS 45.23998318 -38.90452468
OS 45.25015334 -38.90267556
OS 45.26402174 -38.89990188
OS 45.2788147 -38.89435452
OS 45.29545678 -38.88695804
OS 45.3111743 -38.87586332
OS 45.31949534 -38.86846684
OS 45.32689182 -38.86107036
OS 45.32781638 -38.8601458
OS 45.32874094 -38.85922124
OS 45.33059006 -38.85644756
OS 45.33336374 -38.85274932
OS 45.33613742 -38.84812652
OS 45.33983566 -38.84257916
OS 45.3435339 -38.83518268
OS 45.34723214 -38.8277862
OS 45.35093038 -38.8185406
OS 45.35370406 -38.80837044
OS 45.3574023 -38.79727572
OS 45.36017598 -38.78525644
OS 45.36294966 -38.77138804
OS 45.36479878 -38.75751964
OS 45.3666479 -38.74180212
OS 45.3666479 -38.72516004
OS 45.3666479 -38.72423548
OS 45.3666479 -38.7214618
OS 45.3666479 -38.716839
OS 45.36572334 -38.71129164
OS 45.36572334 -38.70389516
OS 45.36479878 -38.69557412
OS 45.3620251 -38.67615836
OS 45.3574023 -38.65581804
OS 45.35000582 -38.6336286
OS 45.33983566 -38.61328828
OS 45.3342883 -38.60311812
OS 45.32689182 -38.59479708
OS 45.32689182 -38.59387252
OS 45.3250427 -38.59294796
OS 45.31949534 -38.5874006
OS 45.3111743 -38.58092868
OS 45.30007958 -38.57260764
OS 45.28621118 -38.5642866
OS 45.2695691 -38.55689012
OS 45.2510779 -38.55226732
OS 45.24090774 -38.55134276
OS 45.22981302 -38.5504182
OE
OB 32.07702246 -38.54764452 H
OS 32.07239966 -38.54764452
OS 32.06870142 -38.54856908
OS 32.05945582 -38.5504182
OS 32.04743654 -38.55319188
OS 32.03356814 -38.55873924
OS 32.01877518 -38.56706028
OS 32.01045414 -38.57260764
OS 32.00305766 -38.57907956
OS 31.99566118 -38.58647604
OS 31.9882647 -38.59479708
OS 31.9882647 -38.59572164
OS 31.98641558 -38.5966462
OS 31.98456646 -38.59941988
OS 31.98271734 -38.60311812
OS 31.97994366 -38.60866548
OS 31.97624542 -38.61421284
OS 31.97254718 -38.62160932
OS 31.9697735 -38.6290058
OS 31.96607526 -38.6382514
OS 31.96237702 -38.64842156
OS 31.95960334 -38.65951628
OS 31.9559051 -38.67153556
OS 31.95405598 -38.68540396
OS 31.95220686 -38.69927236
OS 31.95035774 -38.71406532
OS 31.95035774 -38.7307074
OS 31.95035774 -38.73163196
OS 31.95035774 -38.73440564
OS 31.95035774 -38.73902844
OS 31.9512823 -38.74550036
OS 31.9512823 -38.75289684
OS 31.95220686 -38.76121788
OS 31.95498054 -38.78063364
OS 31.95960334 -38.80282308
OS 31.9651507 -38.82408796
OS 31.9743963 -38.84535284
OS 31.97994366 -38.85459844
OS 31.98641558 -38.86291948
OS 31.9882647 -38.8647686
OS 31.9928875 -38.8693914
OS 32.00028398 -38.87678788
OS 32.01045414 -38.88418436
OS 32.02339798 -38.89158084
OS 32.03819094 -38.89897732
OS 32.05483302 -38.90360012
OS 32.06407862 -38.90452468
OS 32.07332422 -38.90544924
OS 32.07887158 -38.90544924
OS 32.08256982 -38.90452468
OS 32.09181542 -38.90267556
OS 32.10475926 -38.89990188
OS 32.11862766 -38.89435452
OS 32.13342062 -38.88695804
OS 32.14821358 -38.87586332
OS 32.15561006 -38.8693914
OS 32.16300654 -38.86199492
OS 32.16300654 -38.86107036
OS 32.16485566 -38.8601458
OS 32.16670478 -38.85737212
OS 32.1685539 -38.85367388
OS 32.17225214 -38.84905108
OS 32.17502582 -38.84257916
OS 32.17872406 -38.83610724
OS 32.1824223 -38.8277862
OS 32.18519598 -38.81946516
OS 32.18889422 -38.80837044
OS 32.19259246 -38.79727572
OS 32.19536614 -38.78525644
OS 32.19721526 -38.77138804
OS 32.19906438 -38.75659508
OS 32.2009135 -38.74087756
OS 32.2009135 -38.72423548
OS 32.2009135 -38.72331092
OS 32.2009135 -38.72053724
OS 32.2009135 -38.71591444
OS 32.19998894 -38.70944252
OS 32.19998894 -38.70204604
OS 32.19906438 -38.693725
OS 32.1962907 -38.67430924
OS 32.1916679 -38.65304436
OS 32.18519598 -38.63177948
OS 32.17595038 -38.6105146
OS 32.17040302 -38.60034444
OS 32.1639311 -38.5920234
OS 32.1639311 -38.59109884
OS 32.16208198 -38.59017428
OS 32.15745918 -38.58462692
OS 32.1500627 -38.578155
OS 32.13989254 -38.56983396
OS 32.1269487 -38.56151292
OS 32.11215574 -38.55411644
OS 32.09551366 -38.54949364
OS 32.08626806 -38.54856908
OS 32.07702246 -38.54764452
OE
OB 42.10387566 -38.39601668 H
OS 41.95224782 -38.39601668
OS 41.95224782 -38.58832516
OS 42.10942302 -38.58832516
OS 42.1214423 -38.5874006
OS 42.13438614 -38.58647604
OS 42.14732998 -38.58555148
OS 42.16027382 -38.58370236
OS 42.17044398 -38.58185324
OS 42.1722931 -38.58092868
OS 42.17599134 -38.58000412
OS 42.1815387 -38.57723044
OS 42.18893518 -38.5735322
OS 42.19633166 -38.56983396
OS 42.2046527 -38.5642866
OS 42.21297374 -38.55689012
OS 42.21944566 -38.54949364
OS 42.22037022 -38.54856908
OS 42.22221934 -38.5457954
OS 42.22499302 -38.54024804
OS 42.2277667 -38.53377612
OS 42.23054038 -38.52637964
OS 42.23331406 -38.51713404
OS 42.23516318 -38.50603932
OS 42.23608774 -38.49402004
OS 42.23608774 -38.49217092
OS 42.23608774 -38.48847268
OS 42.23516318 -38.48292532
OS 42.23423862 -38.47552884
OS 42.2323895 -38.46628324
OS 42.22961582 -38.45703764
OS 42.22591758 -38.44779204
OS 42.22037022 -38.43854644
OS 42.21944566 -38.43762188
OS 42.21759654 -38.4348482
OS 42.2138983 -38.4302254
OS 42.2092755 -38.4256026
OS 42.20280358 -38.42005524
OS 42.1954071 -38.41450788
OS 42.1861615 -38.40896052
OS 42.17599134 -38.40526228
OS 42.17506678 -38.40526228
OS 42.17044398 -38.40341316
OS 42.16397206 -38.4024886
OS 42.1538019 -38.40063948
OS 42.1399335 -38.39879036
OS 42.12421598 -38.3978658
OS 42.10387566 -38.39601668
OE
OB 37.41635646 -38.39139388 H
OS 37.21480238 -38.39139388
OS 37.21480238 -38.60311812
OS 37.40526174 -38.60311812
OS 37.41635646 -38.60219356
OS 37.4293003 -38.601269
OS 37.44409326 -38.60034444
OS 37.45888622 -38.59849532
OS 37.47367918 -38.59572164
OS 37.48662302 -38.5920234
OS 37.48847214 -38.59109884
OS 37.49217038 -38.58924972
OS 37.49771774 -38.58647604
OS 37.50511422 -38.5827778
OS 37.51343526 -38.57723044
OS 37.5217563 -38.57075852
OS 37.53007734 -38.56243748
OS 37.53654926 -38.55319188
OS 37.53747382 -38.55226732
OS 37.53932294 -38.54856908
OS 37.54209662 -38.54302172
OS 37.54579486 -38.53562524
OS 37.54856854 -38.5273042
OS 37.55134222 -38.5180586
OS 37.55319134 -38.50696388
OS 37.5541159 -38.49586916
OS 37.5541159 -38.4949446
OS 37.5541159 -38.49402004
OS 37.55319134 -38.48847268
OS 37.55226678 -38.48015164
OS 37.55041766 -38.46905692
OS 37.54579486 -38.4579622
OS 37.5402475 -38.44501836
OS 37.53192646 -38.43299908
OS 37.52083174 -38.4209798
OS 37.51898262 -38.42005524
OS 37.51435982 -38.416357
OS 37.50696334 -38.4117342
OS 37.49494406 -38.40618684
OS 37.48107566 -38.40063948
OS 37.46258446 -38.39601668
OS 37.44131958 -38.39231844
OS 37.41635646 -38.39139388
OE
OB 39.82298614 -38.54764452 H
OS 39.81836334 -38.54764452
OS 39.8146651 -38.54856908
OS 39.8054195 -38.5504182
OS 39.79340022 -38.55319188
OS 39.77953182 -38.55873924
OS 39.76473886 -38.56706028
OS 39.75641782 -38.57260764
OS 39.74902134 -38.57907956
OS 39.74162486 -38.58647604
OS 39.73422838 -38.59479708
OS 39.73422838 -38.59572164
OS 39.73237926 -38.5966462
OS 39.73053014 -38.59941988
OS 39.72868102 -38.60311812
OS 39.72590734 -38.60866548
OS 39.7222091 -38.61421284
OS 39.71851086 -38.62160932
OS 39.71573718 -38.6290058
OS 39.71203894 -38.6382514
OS 39.7083407 -38.64842156
OS 39.70556702 -38.65951628
OS 39.70186878 -38.67153556
OS 39.70001966 -38.68540396
OS 39.69817054 -38.69927236
OS 39.69632142 -38.71406532
OS 39.69632142 -38.7307074
OS 39.69632142 -38.73163196
OS 39.69632142 -38.73440564
OS 39.69632142 -38.73902844
OS 39.69724598 -38.74550036
OS 39.69724598 -38.75289684
OS 39.69817054 -38.76121788
OS 39.70094422 -38.78063364
OS 39.70556702 -38.80282308
OS 39.71111438 -38.82408796
OS 39.72035998 -38.84535284
OS 39.72590734 -38.85459844
OS 39.73237926 -38.86291948
OS 39.73422838 -38.8647686
OS 39.73885118 -38.8693914
OS 39.74624766 -38.87678788
OS 39.75641782 -38.88418436
OS 39.76936166 -38.89158084
OS 39.78415462 -38.89897732
OS 39.8007967 -38.90360012
OS 39.8100423 -38.90452468
OS 39.8192879 -38.90544924
OS 39.82483526 -38.90544924
OS 39.8285335 -38.90452468
OS 39.8377791 -38.90267556
OS 39.85072294 -38.89990188
OS 39.86459134 -38.89435452
OS 39.8793843 -38.88695804
OS 39.89417726 -38.87586332
OS 39.90157374 -38.8693914
OS 39.90897022 -38.86199492
OS 39.90897022 -38.86107036
OS 39.91081934 -38.8601458
OS 39.91266846 -38.85737212
OS 39.91451758 -38.85367388
OS 39.91821582 -38.84905108
OS 39.9209895 -38.84257916
OS 39.92468774 -38.83610724
OS 39.92838598 -38.8277862
OS 39.93115966 -38.81946516
OS 39.9348579 -38.80837044
OS 39.93855614 -38.79727572
OS 39.94132982 -38.78525644
OS 39.94317894 -38.77138804
OS 39.94502806 -38.75659508
OS 39.94687718 -38.74087756
OS 39.94687718 -38.72423548
OS 39.94687718 -38.72331092
OS 39.94687718 -38.72053724
OS 39.94687718 -38.71591444
OS 39.94595262 -38.70944252
OS 39.94595262 -38.70204604
OS 39.94502806 -38.693725
OS 39.94225438 -38.67430924
OS 39.93763158 -38.65304436
OS 39.93115966 -38.63177948
OS 39.92191406 -38.6105146
OS 39.9163667 -38.60034444
OS 39.90989478 -38.5920234
OS 39.90989478 -38.59109884
OS 39.90804566 -38.59017428
OS 39.90342286 -38.58462692
OS 39.89602638 -38.578155
OS 39.88585622 -38.56983396
OS 39.87291238 -38.56151292
OS 39.85811942 -38.55411644
OS 39.84147734 -38.54949364
OS 39.83223174 -38.54856908
OS 39.82298614 -38.54764452
OE
OB 35.73550638 -38.39601668 H
OS 35.5524435 -38.39601668
OS 35.5524435 -38.624383
OS 35.72441166 -38.624383
OS 35.73088358 -38.62345844
OS 35.7373555 -38.62345844
OS 35.74475198 -38.62253388
OS 35.76231862 -38.62068476
OS 35.78173438 -38.61698652
OS 35.80115014 -38.61143916
OS 35.81871678 -38.60404268
OS 35.82703782 -38.59941988
OS 35.83350974 -38.59387252
OS 35.83535886 -38.5920234
OS 35.8390571 -38.58832516
OS 35.84460446 -38.58092868
OS 35.85107638 -38.57168308
OS 35.8575483 -38.5596638
OS 35.86309566 -38.54487084
OS 35.8667939 -38.52822876
OS 35.86864302 -38.508813
OS 35.86864302 -38.50788844
OS 35.86864302 -38.50696388
OS 35.86864302 -38.50234108
OS 35.86771846 -38.49402004
OS 35.86586934 -38.48477444
OS 35.86402022 -38.47460428
OS 35.86032198 -38.462585
OS 35.85477462 -38.45149028
OS 35.8483027 -38.44039556
OS 35.84737814 -38.439471
OS 35.84460446 -38.43577276
OS 35.83998166 -38.43114996
OS 35.8344343 -38.42467804
OS 35.82611326 -38.41820612
OS 35.81686766 -38.41265876
OS 35.8066975 -38.4071114
OS 35.79467822 -38.4024886
OS 35.79375366 -38.4024886
OS 35.79005542 -38.40156404
OS 35.78450806 -38.40063948
OS 35.77711158 -38.39879036
OS 35.76601686 -38.3978658
OS 35.75214846 -38.39694124
OS 35.73550638 -38.39601668
OE
OB 43.44263854 -38.5504182 H
OS 43.43709118 -38.5504182
OS 43.43339294 -38.55134276
OS 43.42322278 -38.55226732
OS 43.4112035 -38.555041
OS 43.39641054 -38.5596638
OS 43.38069302 -38.56613572
OS 43.36590006 -38.57538132
OS 43.3511071 -38.5874006
OS 43.34925798 -38.58924972
OS 43.34555974 -38.59387252
OS 43.33908782 -38.60219356
OS 43.3326159 -38.61328828
OS 43.32521942 -38.62623212
OS 43.3187475 -38.6428742
OS 43.31320014 -38.66228996
OS 43.31042646 -38.68355484
OS 43.57022782 -38.68355484
OS 43.57022782 -38.68263028
OS 43.57022782 -38.68078116
OS 43.56930326 -38.67800748
OS 43.56930326 -38.67430924
OS 43.56745414 -38.66321452
OS 43.56468046 -38.65119524
OS 43.56005766 -38.63640228
OS 43.55543486 -38.62253388
OS 43.54803838 -38.60866548
OS 43.53971734 -38.5966462
OS 43.53971734 -38.59572164
OS 43.53786822 -38.59479708
OS 43.53324542 -38.58924972
OS 43.52492438 -38.58185324
OS 43.51382966 -38.5735322
OS 43.49996126 -38.56521116
OS 43.48331918 -38.55781468
OS 43.46390342 -38.55226732
OS 43.45373326 -38.55134276
OS 43.44263854 -38.5504182
OE
OB 34.35791198 -38.39601668 H
OS 34.20628414 -38.39601668
OS 34.20628414 -38.58832516
OS 34.36345934 -38.58832516
OS 34.37547862 -38.5874006
OS 34.38842246 -38.58647604
OS 34.4013663 -38.58555148
OS 34.41431014 -38.58370236
OS 34.4244803 -38.58185324
OS 34.42632942 -38.58092868
OS 34.43002766 -38.58000412
OS 34.43557502 -38.57723044
OS 34.4429715 -38.5735322
OS 34.45036798 -38.56983396
OS 34.45868902 -38.5642866
OS 34.46701006 -38.55689012
OS 34.47348198 -38.54949364
OS 34.47440654 -38.54856908
OS 34.47625566 -38.5457954
OS 34.47902934 -38.54024804
OS 34.48180302 -38.53377612
OS 34.4845767 -38.52637964
OS 34.48735038 -38.51713404
OS 34.4891995 -38.50603932
OS 34.49012406 -38.49402004
OS 34.49012406 -38.49217092
OS 34.49012406 -38.48847268
OS 34.4891995 -38.48292532
OS 34.48827494 -38.47552884
OS 34.48642582 -38.46628324
OS 34.48365214 -38.45703764
OS 34.4799539 -38.44779204
OS 34.47440654 -38.43854644
OS 34.47348198 -38.43762188
OS 34.47163286 -38.4348482
OS 34.46793462 -38.4302254
OS 34.46331182 -38.4256026
OS 34.4568399 -38.42005524
OS 34.44944342 -38.41450788
OS 34.44019782 -38.40896052
OS 34.43002766 -38.40526228
OS 34.4291031 -38.40526228
OS 34.4244803 -38.40341316
OS 34.41800838 -38.4024886
OS 34.40783822 -38.40063948
OS 34.39396982 -38.39879036
OS 34.3782523 -38.3978658
OS 34.35791198 -38.39601668
OE
OB 40.89732486 -38.39601668 H
OS 40.71426198 -38.39601668
OS 40.71426198 -38.624383
OS 40.88623014 -38.624383
OS 40.89270206 -38.62345844
OS 40.89917398 -38.62345844
OS 40.90657046 -38.62253388
OS 40.9241371 -38.62068476
OS 40.94355286 -38.61698652
OS 40.96296862 -38.61143916
OS 40.98053526 -38.60404268
OS 40.9888563 -38.59941988
OS 40.99532822 -38.59387252
OS 40.99717734 -38.5920234
OS 41.00087558 -38.58832516
OS 41.00642294 -38.58092868
OS 41.01289486 -38.57168308
OS 41.01936678 -38.5596638
OS 41.02491414 -38.54487084
OS 41.02861238 -38.52822876
OS 41.0304615 -38.508813
OS 41.0304615 -38.50788844
OS 41.0304615 -38.50696388
OS 41.0304615 -38.50234108
OS 41.02953694 -38.49402004
OS 41.02768782 -38.48477444
OS 41.0258387 -38.47460428
OS 41.02214046 -38.462585
OS 41.0165931 -38.45149028
OS 41.01012118 -38.44039556
OS 41.00919662 -38.439471
OS 41.00642294 -38.43577276
OS 41.00180014 -38.43114996
OS 40.99625278 -38.42467804
OS 40.98793174 -38.41820612
OS 40.97868614 -38.41265876
OS 40.96851598 -38.4071114
OS 40.9564967 -38.4024886
OS 40.95557214 -38.4024886
OS 40.9518739 -38.40156404
OS 40.94632654 -38.40063948
OS 40.93893006 -38.39879036
OS 40.92783534 -38.3978658
OS 40.91396694 -38.39694124
OS 40.89732486 -38.39601668
OE
OB 33.15136118 -38.39601668 H
OS 32.9682983 -38.39601668
OS 32.9682983 -38.624383
OS 33.14026646 -38.624383
OS 33.14673838 -38.62345844
OS 33.1532103 -38.62345844
OS 33.16060678 -38.62253388
OS 33.17817342 -38.62068476
OS 33.19758918 -38.61698652
OS 33.21700494 -38.61143916
OS 33.23457158 -38.60404268
OS 33.24289262 -38.59941988
OS 33.24936454 -38.59387252
OS 33.25121366 -38.5920234
OS 33.2549119 -38.58832516
OS 33.26045926 -38.58092868
OS 33.26693118 -38.57168308
OS 33.2734031 -38.5596638
OS 33.27895046 -38.54487084
OS 33.2826487 -38.52822876
OS 33.28449782 -38.508813
OS 33.28449782 -38.50788844
OS 33.28449782 -38.50696388
OS 33.28449782 -38.50234108
OS 33.28357326 -38.49402004
OS 33.28172414 -38.48477444
OS 33.27987502 -38.47460428
OS 33.27617678 -38.462585
OS 33.27062942 -38.45149028
OS 33.2641575 -38.44039556
OS 33.26323294 -38.439471
OS 33.26045926 -38.43577276
OS 33.25583646 -38.43114996
OS 33.2502891 -38.42467804
OS 33.24196806 -38.41820612
OS 33.23272246 -38.41265876
OS 33.2225523 -38.4071114
OS 33.21053302 -38.4024886
OS 33.20960846 -38.4024886
OS 33.20591022 -38.40156404
OS 33.20036286 -38.40063948
OS 33.19296638 -38.39879036
OS 33.18187166 -38.3978658
OS 33.16800326 -38.39694124
OS 33.15136118 -38.39601668
OE
OB 34.37455406 -38.66413908 H
OS 34.20628414 -38.66413908
OS 34.20628414 -38.88418436
OS 34.38842246 -38.88418436
OS 34.40783822 -38.8832598
OS 34.41615926 -38.88233524
OS 34.42355574 -38.88141068
OS 34.4244803 -38.88141068
OS 34.42817854 -38.88048612
OS 34.4337259 -38.87956156
OS 34.44019782 -38.87771244
OS 34.45591534 -38.87216508
OS 34.47163286 -38.8647686
OS 34.47255742 -38.86384404
OS 34.4753311 -38.86199492
OS 34.47902934 -38.85922124
OS 34.48365214 -38.855523
OS 34.48827494 -38.84997564
OS 34.49474686 -38.84442828
OS 34.49936966 -38.8370318
OS 34.50491702 -38.82871076
OS 34.50584158 -38.8277862
OS 34.50676614 -38.82501252
OS 34.50861526 -38.81946516
OS 34.51138894 -38.81299324
OS 34.51416262 -38.80559676
OS 34.51601174 -38.79635116
OS 34.5169363 -38.78525644
OS 34.51786086 -38.77416172
OS 34.51786086 -38.7723126
OS 34.51786086 -38.76861436
OS 34.5169363 -38.76121788
OS 34.51508718 -38.75289684
OS 34.51323806 -38.74365124
OS 34.50953982 -38.73348108
OS 34.50491702 -38.72331092
OS 34.4984451 -38.71314076
OS 34.49752054 -38.7122162
OS 34.49474686 -38.70851796
OS 34.49104862 -38.70389516
OS 34.48550126 -38.6983478
OS 34.47810478 -38.69187588
OS 34.46885918 -38.68540396
OS 34.45868902 -38.6798566
OS 34.44666974 -38.6752338
OS 34.44482062 -38.67430924
OS 34.44112238 -38.67338468
OS 34.43280134 -38.67153556
OS 34.42263118 -38.66968644
OS 34.40968734 -38.66783732
OS 34.39396982 -38.6659882
OS 34.37455406 -38.66413908
OE
SE
S P 0
OB 48.49040086 -36.61402634 I
OS 48.17420134 -36.61402634
OS 48.17420134 -37.45999874
OS 48.04661206 -37.45999874
OS 48.04661206 -36.61402634
OS 47.73041254 -36.61402634
OS 47.73041254 -36.50030546
OS 48.49040086 -36.50030546
OS 48.49040086 -36.61402634
OE
OB 47.69990206 -37.45999874 I
OS 47.5556707 -37.45999874
OS 47.44333666 -37.16876234
OS 47.04115306 -37.16876234
OS 46.93714006 -37.45999874
OS 46.80261658 -37.45999874
OS 47.16874234 -36.50030546
OS 47.30742634 -36.50030546
OS 47.69990206 -37.45999874
OE
OB 49.31834434 -36.61402634 I
OS 48.75112678 -36.61402634
OS 48.75112678 -36.90664958
OS 49.2822865 -36.90664958
OS 49.2822865 -37.02037046
OS 48.75112678 -37.02037046
OS 48.75112678 -37.34627786
OS 49.34053378 -37.34627786
OS 49.34053378 -37.45999874
OS 48.6235375 -37.45999874
OS 48.6235375 -36.50030546
OS 49.31834434 -36.50030546
OS 49.31834434 -36.61402634
OE
OB 46.33386466 -36.5016923 I
OS 46.36160146 -36.50307914
OS 46.38933826 -36.50585282
OS 46.41707506 -36.51001334
OS 46.44065134 -36.51417386
OS 46.44203818 -36.51417386
OS 46.44481186 -36.5155607
OS 46.44897238 -36.5155607
OS 46.45451974 -36.51833438
OS 46.46977498 -36.5224949
OS 46.48919074 -36.5294291
OS 46.51138018 -36.53913698
OS 46.53495646 -36.55161854
OS 46.55853274 -36.56548694
OS 46.58072218 -36.58351586
OS 46.58210902 -36.5849027
OS 46.58349586 -36.58628954
OS 46.58765638 -36.59045006
OS 46.59320374 -36.59461058
OS 46.60707214 -36.60847898
OS 46.62371422 -36.62789474
OS 46.64174314 -36.65147102
OS 46.6611589 -36.67920782
OS 46.67918782 -36.71110514
OS 46.69444306 -36.74716298
OS 46.69444306 -36.74854982
OS 46.6958299 -36.7513235
OS 46.69860358 -36.75687086
OS 46.69999042 -36.7651919
OS 46.70415094 -36.77489978
OS 46.70692462 -36.7859945
OS 46.7096983 -36.79847606
OS 46.71385882 -36.8137313
OS 46.71801934 -36.82898654
OS 46.72079302 -36.84701546
OS 46.72772722 -36.88584698
OS 46.73188774 -36.92883902
OS 46.73327458 -36.97599158
OS 46.73327458 -36.97737842
OS 46.73327458 -36.9801521
OS 46.73327458 -36.9870863
OS 46.73327458 -36.9940205
OS 46.73188774 -37.00372838
OS 46.73188774 -37.0148231
OS 46.7305009 -37.04117306
OS 46.72634038 -37.07168354
OS 46.72217986 -37.10358086
OS 46.71524566 -37.13686502
OS 46.70692462 -37.17014918
OS 46.70692462 -37.17153602
OS 46.70553778 -37.1743097
OS 46.70415094 -37.17847022
OS 46.7027641 -37.18401758
OS 46.69721674 -37.19927282
OS 46.6888957 -37.21868858
OS 46.68057466 -37.24087802
OS 46.66947994 -37.26306746
OS 46.65561154 -37.28664374
OS 46.64174314 -37.30883318
OS 46.6403563 -37.31160686
OS 46.63480894 -37.31854106
OS 46.6264879 -37.32824894
OS 46.61539318 -37.3407305
OS 46.60291162 -37.3545989
OS 46.58765638 -37.3684673
OS 46.57240114 -37.38372254
OS 46.55437222 -37.3962041
OS 46.55159854 -37.39759094
OS 46.54605118 -37.40175146
OS 46.5363433 -37.40729882
OS 46.5224749 -37.41423302
OS 46.50583282 -37.42255406
OS 46.48641706 -37.42948826
OS 46.46422762 -37.4378093
OS 46.4392645 -37.4447435
OS 46.43649082 -37.4447435
OS 46.4323303 -37.44613034
OS 46.42816978 -37.44751718
OS 46.41430138 -37.44890402
OS 46.39488562 -37.4516777
OS 46.37269618 -37.45445138
OS 46.34634622 -37.45722506
OS 46.31722258 -37.4586119
OS 46.28532526 -37.45999874
OS 45.9400021 -37.45999874
OS 45.9400021 -36.50030546
OS 46.30890154 -36.50030546
OS 46.33386466 -36.5016923
OE
OB 46.28948578 -36.61402634 H
OS 46.06759138 -36.61402634
OS 46.06759138 -37.34627786
OS 46.29503314 -37.34627786
OS 46.30474102 -37.34489102
OS 46.32554362 -37.34350418
OS 46.3491199 -37.34211734
OS 46.37408302 -37.33934366
OS 46.39904614 -37.33518314
OS 46.41984874 -37.32963578
OS 46.42262242 -37.32824894
OS 46.42955662 -37.3268621
OS 46.4392645 -37.32270158
OS 46.45174606 -37.31715422
OS 46.46561446 -37.30883318
OS 46.47948286 -37.30051214
OS 46.49335126 -37.29080426
OS 46.50721966 -37.27970954
OS 46.5086065 -37.27693586
OS 46.51415386 -37.2713885
OS 46.5224749 -37.26168062
OS 46.53218278 -37.24781222
OS 46.5432775 -37.2297833
OS 46.55575906 -37.2089807
OS 46.56685378 -37.18540442
OS 46.57656166 -37.15905446
OS 46.57656166 -37.15766762
OS 46.5779485 -37.15489394
OS 46.57933534 -37.15073342
OS 46.58072218 -37.14518606
OS 46.58210902 -37.13825186
OS 46.5848827 -37.12854398
OS 46.58765638 -37.1188361
OS 46.59043006 -37.10774138
OS 46.59459058 -37.08000458
OS 46.5987511 -37.04810726
OS 46.60152478 -37.01204942
OS 46.60291162 -36.9732179
OS 46.60291162 -36.97183106
OS 46.60291162 -36.9662837
OS 46.60291162 -36.9593495
OS 46.60152478 -36.94825478
OS 46.60152478 -36.93577322
OS 46.60013794 -36.92190482
OS 46.5987511 -36.90526274
OS 46.59736426 -36.88862066
OS 46.59043006 -36.85117598
OS 46.58210902 -36.81234446
OS 46.56962746 -36.77628662
OS 46.56130642 -36.7582577
OS 46.55298538 -36.74300246
OS 46.55298538 -36.74161562
OS 46.5502117 -36.73884194
OS 46.54743802 -36.73468142
OS 46.54466434 -36.72913406
OS 46.53356962 -36.71526566
OS 46.51970122 -36.69862358
OS 46.5016723 -36.68059466
OS 46.4808697 -36.66256574
OS 46.45729342 -36.6473105
OS 46.4323303 -36.63482894
OS 46.42955662 -36.6334421
OS 46.42262242 -36.63205526
OS 46.41014086 -36.62789474
OS 46.39211194 -36.62373422
OS 46.3699225 -36.62096054
OS 46.3421857 -36.61680002
OS 46.32554362 -36.61541318
OS 46.3075147 -36.61541318
OS 46.28948578 -36.61402634
OE
OB 47.23531066 -36.60015794 H
OS 47.23531066 -36.60154478
OS 47.23392382 -36.60431846
OS 47.23392382 -36.60986582
OS 47.23115014 -36.61541318
OS 47.2297633 -36.62512106
OS 47.22698962 -36.63482894
OS 47.22144226 -36.65840522
OS 47.21450806 -36.68614202
OS 47.20480018 -36.7166525
OS 47.1950923 -36.74993666
OS 47.18261074 -36.78460766
OS 47.07859774 -37.06474934
OS 47.4031183 -37.06474934
OS 47.30326582 -36.80124974
OS 47.30326582 -36.7998629
OS 47.30187898 -36.79570238
OS 47.2991053 -36.78876818
OS 47.29633162 -36.78044714
OS 47.2921711 -36.77073926
OS 47.28801058 -36.7582577
OS 47.28385006 -36.7443893
OS 47.2783027 -36.7305209
OS 47.26720798 -36.69862358
OS 47.25611326 -36.66533942
OS 47.24501854 -36.63205526
OS 47.23531066 -36.60015794
OE
SE
S P 0
OB 53.64989524 -38.94890356 I
OS 53.57130764 -38.94890356
OS 53.57130764 -38.4487166
OS 53.57038308 -38.44964116
OS 53.56576028 -38.4533394
OS 53.56021292 -38.45888676
OS 53.55096732 -38.46535868
OS 53.54079716 -38.47367972
OS 53.52785332 -38.48292532
OS 53.51306036 -38.49309548
OS 53.49641828 -38.50326564
OS 53.49549372 -38.50326564
OS 53.49456916 -38.5041902
OS 53.4890218 -38.50788844
OS 53.4797762 -38.51251124
OS 53.46868148 -38.5180586
OS 53.45573764 -38.52453052
OS 53.44186924 -38.53100244
OS 53.42800084 -38.53747436
OS 53.41413244 -38.54302172
OS 53.41413244 -38.4672078
OS 53.415057 -38.4672078
OS 53.41690612 -38.46535868
OS 53.42060436 -38.46443412
OS 53.42522716 -38.46166044
OS 53.43077452 -38.45888676
OS 53.43724644 -38.45518852
OS 53.45296396 -38.44594292
OS 53.47145516 -38.43577276
OS 53.48994636 -38.42282892
OS 53.50936212 -38.40803596
OS 53.52877788 -38.39231844
OS 53.52970244 -38.39139388
OS 53.530627 -38.39046932
OS 53.53340068 -38.38769564
OS 53.53709892 -38.38492196
OS 53.54541996 -38.37567636
OS 53.55651468 -38.36458164
OS 53.5676094 -38.3516378
OS 53.57962868 -38.33684484
OS 53.58979884 -38.32205188
OS 53.59904444 -38.30633436
OS 53.64989524 -38.30633436
OS 53.64989524 -38.94890356
OE
OB 54.07334372 -38.30725892 I
OS 54.0807402 -38.30818348
OS 54.08906124 -38.30910804
OS 54.09830684 -38.3100326
OS 54.10755244 -38.31280628
OS 54.12974188 -38.31835364
OS 54.15193132 -38.32667468
OS 54.16302604 -38.33222204
OS 54.17412076 -38.33869396
OS 54.18429092 -38.347015
OS 54.19446108 -38.35533604
OS 54.19538564 -38.3562606
OS 54.1963102 -38.35718516
OS 54.19908388 -38.35995884
OS 54.20278212 -38.36365708
OS 54.20648036 -38.36920444
OS 54.21110316 -38.3747518
OS 54.22034876 -38.3886202
OS 54.22959436 -38.40618684
OS 54.2379154 -38.42652716
OS 54.24438732 -38.44964116
OS 54.24531188 -38.46166044
OS 54.24623644 -38.47460428
OS 54.24623644 -38.47552884
OS 54.24623644 -38.4764534
OS 54.24623644 -38.48200076
OS 54.24531188 -38.4903218
OS 54.24346276 -38.50049196
OS 54.24068908 -38.5134358
OS 54.23606628 -38.52637964
OS 54.23051892 -38.53932348
OS 54.22219788 -38.55226732
OS 54.22127332 -38.55411644
OS 54.21757508 -38.55781468
OS 54.21202772 -38.56336204
OS 54.20463124 -38.57075852
OS 54.19446108 -38.57907956
OS 54.1824418 -38.5874006
OS 54.1685734 -38.59572164
OS 54.15193132 -38.60311812
OS 54.15285588 -38.60311812
OS 54.154705 -38.60404268
OS 54.15747868 -38.60496724
OS 54.16117692 -38.60681636
OS 54.17227164 -38.61143916
OS 54.18521548 -38.61791108
OS 54.19908388 -38.62715668
OS 54.21387684 -38.63732684
OS 54.22774524 -38.65027068
OS 54.24068908 -38.66506364
OS 54.24068908 -38.6659882
OS 54.24161364 -38.66691276
OS 54.24531188 -38.67246012
OS 54.25085924 -38.68170572
OS 54.2564066 -38.693725
OS 54.26195396 -38.70851796
OS 54.26750132 -38.7260846
OS 54.27119956 -38.74550036
OS 54.27212412 -38.76676524
OS 54.27212412 -38.7676898
OS 54.27212412 -38.77046348
OS 54.27212412 -38.77508628
OS 54.27119956 -38.78063364
OS 54.270275 -38.78710556
OS 54.26935044 -38.7954266
OS 54.26750132 -38.8046722
OS 54.26472764 -38.81484236
OS 54.25825572 -38.83610724
OS 54.25363292 -38.84812652
OS 54.247161 -38.85922124
OS 54.24068908 -38.87124052
OS 54.2332926 -38.88233524
OS 54.224047 -38.89342996
OS 54.21387684 -38.90452468
OS 54.21295228 -38.90544924
OS 54.21110316 -38.90729836
OS 54.20832948 -38.91007204
OS 54.20370668 -38.91284572
OS 54.19723476 -38.91746852
OS 54.19076284 -38.92209132
OS 54.1824418 -38.92671412
OS 54.1731962 -38.93226148
OS 54.16302604 -38.93780884
OS 54.15100676 -38.94243164
OS 54.13806292 -38.94705444
OS 54.12511908 -38.95167724
OS 54.11032612 -38.95445092
OS 54.0946086 -38.9572246
OS 54.07889108 -38.95907372
OS 54.06132444 -38.95999828
OS 54.05207884 -38.95999828
OS 54.04560692 -38.95907372
OS 54.03728588 -38.95814916
OS 54.02804028 -38.9572246
OS 54.01787012 -38.95537548
OS 54.0067754 -38.9526018
OS 53.98181228 -38.94612988
OS 53.96886844 -38.94150708
OS 53.95684916 -38.93688428
OS 53.94390532 -38.93041236
OS 53.93096148 -38.92301588
OS 53.9189422 -38.91469484
OS 53.90784748 -38.90452468
OS 53.90692292 -38.90360012
OS 53.9050738 -38.901751
OS 53.90230012 -38.89897732
OS 53.89860188 -38.89435452
OS 53.89490364 -38.88880716
OS 53.88935628 -38.88233524
OS 53.88473348 -38.87493876
OS 53.87918612 -38.86569316
OS 53.87363876 -38.85644756
OS 53.86901596 -38.84535284
OS 53.85977036 -38.82223884
OS 53.85607212 -38.80837044
OS 53.85329844 -38.79450204
OS 53.85144932 -38.77970908
OS 53.85052476 -38.76491612
OS 53.85052476 -38.76399156
OS 53.85052476 -38.76214244
OS 53.85052476 -38.7584442
OS 53.85144932 -38.75474596
OS 53.85144932 -38.7491986
OS 53.85237388 -38.74272668
OS 53.854223 -38.72793372
OS 53.85792124 -38.71129164
OS 53.8634686 -38.69464956
OS 53.87178964 -38.67708292
OS 53.8819598 -38.66044084
OS 53.8819598 -38.65951628
OS 53.88380892 -38.65859172
OS 53.88750716 -38.65396892
OS 53.89490364 -38.64657244
OS 53.9050738 -38.63732684
OS 53.91801764 -38.62808124
OS 53.93373516 -38.61791108
OS 53.9513018 -38.60959004
OS 53.97256668 -38.60311812
OS 53.97164212 -38.60311812
OS 53.97071756 -38.60219356
OS 53.96794388 -38.601269
OS 53.96424564 -38.59941988
OS 53.9559246 -38.59572164
OS 53.94482988 -38.59017428
OS 53.9328106 -38.5827778
OS 53.92079132 -38.5735322
OS 53.9096966 -38.56336204
OS 53.89952644 -38.55226732
OS 53.89860188 -38.5504182
OS 53.8958282 -38.54671996
OS 53.89212996 -38.53932348
OS 53.88843172 -38.53007788
OS 53.88380892 -38.5180586
OS 53.88011068 -38.5041902
OS 53.877337 -38.48847268
OS 53.87641244 -38.4718306
OS 53.87641244 -38.47090604
OS 53.87641244 -38.46905692
OS 53.87641244 -38.46535868
OS 53.877337 -38.45981132
OS 53.87826156 -38.45426396
OS 53.87918612 -38.44686748
OS 53.88288436 -38.43114996
OS 53.88843172 -38.41265876
OS 53.89767732 -38.393243
OS 53.90322468 -38.38307284
OS 53.9096966 -38.37290268
OS 53.91801764 -38.36365708
OS 53.92633868 -38.35441148
OS 53.92726324 -38.35348692
OS 53.92911236 -38.35256236
OS 53.93188604 -38.34978868
OS 53.93558428 -38.347015
OS 53.94020708 -38.34331676
OS 53.946679 -38.33961852
OS 53.95407548 -38.33499572
OS 53.96147196 -38.33037292
OS 53.97071756 -38.32575012
OS 53.98088772 -38.32112732
OS 53.99198244 -38.31742908
OS 54.00400172 -38.31373084
OS 54.0298894 -38.30818348
OS 54.04468236 -38.30725892
OS 54.05947532 -38.30633436
OS 54.06779636 -38.30633436
OS 54.07334372 -38.30725892
OE
OB 53.23846604 -38.94890356 I
OS 53.14878372 -38.94890356
OS 53.14878372 -38.85922124
OS 53.23846604 -38.85922124
OS 53.23846604 -38.94890356
OE
OB 53.00177868 -38.39231844 I
OS 52.74567556 -38.39231844
OS 52.71146684 -38.56521116
OS 52.7123914 -38.5642866
OS 52.71424052 -38.56336204
OS 52.7170142 -38.56151292
OS 52.721637 -38.55873924
OS 52.72718436 -38.55596556
OS 52.73365628 -38.55226732
OS 52.74844924 -38.54487084
OS 52.76694044 -38.53747436
OS 52.78728076 -38.53100244
OS 52.8094702 -38.52637964
OS 52.82056492 -38.52453052
OS 52.84090524 -38.52453052
OS 52.8464526 -38.52545508
OS 52.85384908 -38.52637964
OS 52.86217012 -38.5273042
OS 52.87141572 -38.52915332
OS 52.88158588 -38.531927
OS 52.90377532 -38.53839892
OS 52.9157946 -38.54302172
OS 52.92781388 -38.54949364
OS 52.93983316 -38.55596556
OS 52.95185244 -38.56336204
OS 52.96294716 -38.57260764
OS 52.97404188 -38.5827778
OS 52.97496644 -38.58370236
OS 52.97681556 -38.58555148
OS 52.97958924 -38.58832516
OS 52.98328748 -38.59294796
OS 52.98791028 -38.59941988
OS 52.99253308 -38.6058918
OS 52.99808044 -38.61421284
OS 53.0036278 -38.62345844
OS 53.0082506 -38.6336286
OS 53.01379796 -38.64472332
OS 53.01842076 -38.65766716
OS 53.02304356 -38.670611
OS 53.0267418 -38.6844794
OS 53.02951548 -38.70019692
OS 53.0313646 -38.71591444
OS 53.03228916 -38.73255652
OS 53.03228916 -38.73348108
OS 53.03228916 -38.73625476
OS 53.03228916 -38.74087756
OS 53.0313646 -38.74734948
OS 53.03044004 -38.75474596
OS 53.02951548 -38.763067
OS 53.02766636 -38.77323716
OS 53.02581724 -38.78340732
OS 53.02026988 -38.80744588
OS 53.01102428 -38.832409
OS 53.00547692 -38.84535284
OS 52.99808044 -38.85737212
OS 52.99068396 -38.87031596
OS 52.98143836 -38.88233524
OS 52.9805138 -38.8832598
OS 52.97866468 -38.88603348
OS 52.97496644 -38.88973172
OS 52.97034364 -38.89435452
OS 52.96387172 -38.89990188
OS 52.95647524 -38.90729836
OS 52.94722964 -38.91377028
OS 52.93705948 -38.92116676
OS 52.92596476 -38.92856324
OS 52.91302092 -38.93503516
OS 52.89915252 -38.94150708
OS 52.88435956 -38.947979
OS 52.86864204 -38.9526018
OS 52.8510754 -38.95630004
OS 52.8325842 -38.95907372
OS 52.81316844 -38.95999828
OS 52.8048474 -38.95999828
OS 52.79837548 -38.95907372
OS 52.790979 -38.95814916
OS 52.78265796 -38.9572246
OS 52.7724878 -38.95630004
OS 52.76231764 -38.95352636
OS 52.73920364 -38.947979
OS 52.71608964 -38.93965796
OS 52.70407036 -38.9341106
OS 52.69205108 -38.92763868
OS 52.68095636 -38.9202422
OS 52.66986164 -38.91192116
OS 52.66893708 -38.9109966
OS 52.66708796 -38.91007204
OS 52.66523884 -38.9063738
OS 52.6615406 -38.90267556
OS 52.6569178 -38.89805276
OS 52.652295 -38.8925054
OS 52.64674764 -38.88510892
OS 52.64212484 -38.87678788
OS 52.63657748 -38.86846684
OS 52.63103012 -38.85829668
OS 52.62085996 -38.83610724
OS 52.61253892 -38.81021956
OS 52.60976524 -38.79635116
OS 52.60791612 -38.7815582
OS 52.69020196 -38.77508628
OS 52.69020196 -38.77601084
OS 52.69020196 -38.77785996
OS 52.69112652 -38.78063364
OS 52.69205108 -38.78525644
OS 52.69482476 -38.7954266
OS 52.698523 -38.809295
OS 52.70407036 -38.8231634
OS 52.71146684 -38.83888092
OS 52.72071244 -38.85274932
OS 52.73180716 -38.86569316
OS 52.73365628 -38.86661772
OS 52.73735452 -38.87031596
OS 52.744751 -38.87493876
OS 52.75492116 -38.88048612
OS 52.76601588 -38.88603348
OS 52.77988428 -38.89065628
OS 52.7956018 -38.89435452
OS 52.81316844 -38.89527908
OS 52.8187158 -38.89527908
OS 52.82241404 -38.89435452
OS 52.83350876 -38.89342996
OS 52.8464526 -38.88973172
OS 52.86217012 -38.88510892
OS 52.87788764 -38.87771244
OS 52.89452972 -38.86661772
OS 52.9019262 -38.8601458
OS 52.90932268 -38.85274932
OS 52.91024724 -38.85182476
OS 52.9111718 -38.8509002
OS 52.91302092 -38.84812652
OS 52.9157946 -38.84535284
OS 52.92226652 -38.83518268
OS 52.929663 -38.82223884
OS 52.93613492 -38.80652132
OS 52.94260684 -38.78710556
OS 52.94722964 -38.76399156
OS 52.94907876 -38.75197228
OS 52.94907876 -38.73902844
OS 52.94907876 -38.73810388
OS 52.94907876 -38.73625476
OS 52.94907876 -38.73255652
OS 52.9481542 -38.72793372
OS 52.9481542 -38.72238636
OS 52.94722964 -38.71591444
OS 52.94445596 -38.70112148
OS 52.93983316 -38.68355484
OS 52.93336124 -38.6659882
OS 52.92411564 -38.64934612
OS 52.9111718 -38.6336286
OS 52.9111718 -38.63270404
OS 52.90932268 -38.63177948
OS 52.90469988 -38.62715668
OS 52.89637884 -38.62068476
OS 52.88528412 -38.61328828
OS 52.87049116 -38.60681636
OS 52.85384908 -38.60034444
OS 52.83443332 -38.59572164
OS 52.8233386 -38.59387252
OS 52.80577196 -38.59387252
OS 52.79837548 -38.59479708
OS 52.78912988 -38.59572164
OS 52.77803516 -38.59849532
OS 52.76694044 -38.601269
OS 52.75492116 -38.6058918
OS 52.74290188 -38.61143916
OS 52.74197732 -38.61236372
OS 52.73827908 -38.61421284
OS 52.73273172 -38.61883564
OS 52.72533524 -38.62345844
OS 52.71793876 -38.62993036
OS 52.71054228 -38.6382514
OS 52.70222124 -38.64657244
OS 52.69574932 -38.6567426
OS 52.62178452 -38.64657244
OS 52.68373004 -38.31742908
OS 53.00177868 -38.31742908
OS 53.00177868 -38.39231844
OE
OB 53.23846604 -38.57445676 I
OS 53.14878372 -38.57445676
OS 53.14878372 -38.48477444
OS 53.23846604 -38.48477444
OS 53.23846604 -38.57445676
OE
OB 54.48199924 -38.57445676 I
OS 54.39231692 -38.57445676
OS 54.39231692 -38.48477444
OS 54.48199924 -38.48477444
OS 54.48199924 -38.57445676
OE
OB 56.14990548 -38.3100326 I
OS 56.165623 -38.31095716
OS 56.18226508 -38.31188172
OS 56.1979826 -38.31373084
OS 56.211851 -38.31557996
OS 56.21370012 -38.31557996
OS 56.22017204 -38.31742908
OS 56.22849308 -38.3192782
OS 56.2395878 -38.32205188
OS 56.25160708 -38.32667468
OS 56.26455092 -38.33222204
OS 56.27841932 -38.33869396
OS 56.2904386 -38.34609044
OS 56.29228772 -38.347015
OS 56.29598596 -38.34978868
OS 56.30153332 -38.35533604
OS 56.3089298 -38.36180796
OS 56.31725084 -38.370129
OS 56.32557188 -38.38122372
OS 56.33481748 -38.393243
OS 56.34221396 -38.4071114
OS 56.34313852 -38.40896052
OS 56.34498764 -38.41358332
OS 56.34868588 -38.42190436
OS 56.35238412 -38.43299908
OS 56.3551578 -38.44594292
OS 56.35885604 -38.46073588
OS 56.36070516 -38.47737796
OS 56.36162972 -38.4949446
OS 56.36162972 -38.49586916
OS 56.36162972 -38.49864284
OS 56.36162972 -38.50234108
OS 56.36070516 -38.508813
OS 56.3597806 -38.51528492
OS 56.35885604 -38.52360596
OS 56.35700692 -38.53285156
OS 56.3551578 -38.54302172
OS 56.34868588 -38.5642866
OS 56.34498764 -38.57538132
OS 56.33944028 -38.5874006
OS 56.33296836 -38.59941988
OS 56.32649644 -38.6105146
OS 56.3181754 -38.62160932
OS 56.3089298 -38.63270404
OS 56.30800524 -38.6336286
OS 56.30615612 -38.63547772
OS 56.30338244 -38.6382514
OS 56.29875964 -38.64102508
OS 56.29321228 -38.64564788
OS 56.2858158 -38.65027068
OS 56.2765702 -38.65581804
OS 56.26640004 -38.66044084
OS 56.25438076 -38.6659882
OS 56.24051236 -38.67153556
OS 56.2257194 -38.67615836
OS 56.20815276 -38.6798566
OS 56.18966156 -38.68355484
OS 56.16932124 -38.68632852
OS 56.14620724 -38.68817764
OS 56.12216868 -38.6891022
OS 55.95852156 -38.6891022
OS 55.95852156 -38.94890356
OS 55.87346204 -38.94890356
OS 55.87346204 -38.30910804
OS 56.13603708 -38.30910804
OS 56.14990548 -38.3100326
OE
OB 57.07723916 -38.94890356 I
OS 56.99587788 -38.94890356
OS 56.99587788 -38.41358332
OS 56.80911676 -38.94890356
OS 56.73330284 -38.94890356
OS 56.54839084 -38.40433772
OS 56.54839084 -38.94890356
OS 56.46702956 -38.94890356
OS 56.46702956 -38.30910804
OS 56.59369428 -38.30910804
OS 56.74532212 -38.763067
OS 56.74532212 -38.76399156
OS 56.74624668 -38.76584068
OS 56.74717124 -38.76861436
OS 56.74902036 -38.77323716
OS 56.7527186 -38.78433188
OS 56.7573414 -38.79820028
OS 56.7619642 -38.8139178
OS 56.76751156 -38.82963532
OS 56.77213436 -38.84442828
OS 56.7758326 -38.85737212
OS 56.77675716 -38.855523
OS 56.77768172 -38.8509002
OS 56.7804554 -38.84257916
OS 56.78415364 -38.83148444
OS 56.78877644 -38.81669148
OS 56.79524836 -38.79912484
OS 56.80172028 -38.77878452
OS 56.81004132 -38.75474596
OS 56.96351828 -38.30910804
OS 57.07723916 -38.30910804
OS 57.07723916 -38.94890356
OE
OB 55.39084172 -38.94890356 I
OS 55.31225412 -38.94890356
OS 55.31225412 -38.4487166
OS 55.31132956 -38.44964116
OS 55.30670676 -38.4533394
OS 55.3011594 -38.45888676
OS 55.2919138 -38.46535868
OS 55.28174364 -38.47367972
OS 55.2687998 -38.48292532
OS 55.25400684 -38.49309548
OS 55.23736476 -38.50326564
OS 55.2364402 -38.50326564
OS 55.23551564 -38.5041902
OS 55.22996828 -38.50788844
OS 55.22072268 -38.51251124
OS 55.20962796 -38.5180586
OS 55.19668412 -38.52453052
OS 55.18281572 -38.53100244
OS 55.16894732 -38.53747436
OS 55.15507892 -38.54302172
OS 55.15507892 -38.4672078
OS 55.15600348 -38.4672078
OS 55.1578526 -38.46535868
OS 55.16155084 -38.46443412
OS 55.16617364 -38.46166044
OS 55.171721 -38.45888676
OS 55.17819292 -38.45518852
OS 55.19391044 -38.44594292
OS 55.21240164 -38.43577276
OS 55.23089284 -38.42282892
OS 55.2503086 -38.40803596
OS 55.26972436 -38.39231844
OS 55.27064892 -38.39139388
OS 55.27157348 -38.39046932
OS 55.27434716 -38.38769564
OS 55.2780454 -38.38492196
OS 55.28636644 -38.37567636
OS 55.29746116 -38.36458164
OS 55.30855588 -38.3516378
OS 55.32057516 -38.33684484
OS 55.33074532 -38.32205188
OS 55.33999092 -38.30633436
OS 55.39084172 -38.30633436
OS 55.39084172 -38.94890356
OE
OB 54.48199924 -38.94890356 I
OS 54.39231692 -38.94890356
OS 54.39231692 -38.85922124
OS 54.48199924 -38.85922124
OS 54.48199924 -38.94890356
OE
OB 54.825011 -38.30725892 I
OS 54.83703028 -38.30910804
OS 54.85089868 -38.31188172
OS 54.86569164 -38.31557996
OS 54.88140916 -38.32020276
OS 54.89620212 -38.32759924
OS 54.89712668 -38.32759924
OS 54.89805124 -38.3285238
OS 54.90267404 -38.33129748
OS 54.91007052 -38.33592028
OS 54.91931612 -38.3423922
OS 54.92948628 -38.3516378
OS 54.940581 -38.36180796
OS 54.95075116 -38.37382724
OS 54.96092132 -38.38769564
OS 54.96184588 -38.38954476
OS 54.96554412 -38.39416756
OS 54.96924236 -38.4024886
OS 54.97571428 -38.41450788
OS 54.98126164 -38.42837628
OS 54.98865812 -38.4440938
OS 54.99513004 -38.462585
OS 55.0006774 -38.48292532
OS 55.0006774 -38.48384988
OS 55.00160196 -38.485699
OS 55.00252652 -38.48847268
OS 55.00345108 -38.49309548
OS 55.00437564 -38.49864284
OS 55.0053002 -38.50511476
OS 55.00714932 -38.5134358
OS 55.00807388 -38.5226814
OS 55.009923 -38.53285156
OS 55.01084756 -38.54394628
OS 55.01177212 -38.55689012
OS 55.01362124 -38.56983396
OS 55.0145458 -38.58462692
OS 55.0145458 -38.59941988
OS 55.01547036 -38.61606196
OS 55.01547036 -38.6336286
OS 55.01547036 -38.63455316
OS 55.01547036 -38.6382514
OS 55.01547036 -38.64472332
OS 55.01547036 -38.6521198
OS 55.0145458 -38.66228996
OS 55.0145458 -38.67338468
OS 55.01362124 -38.68540396
OS 55.01269668 -38.6983478
OS 55.009923 -38.72793372
OS 55.0053002 -38.7584442
OS 54.99975284 -38.78803012
OS 54.9960546 -38.80189852
OS 54.9914318 -38.81576692
OS 54.9914318 -38.81669148
OS 54.99050724 -38.8185406
OS 54.98865812 -38.82223884
OS 54.986809 -38.82686164
OS 54.98495988 -38.83333356
OS 54.98126164 -38.83980548
OS 54.97386516 -38.855523
OS 54.96461956 -38.87216508
OS 54.95260028 -38.89065628
OS 54.93873188 -38.90729836
OS 54.9220898 -38.92301588
OS 54.92116524 -38.92301588
OS 54.92024068 -38.924865
OS 54.917467 -38.92671412
OS 54.91376876 -38.92856324
OS 54.90914596 -38.93133692
OS 54.90452316 -38.93503516
OS 54.89065476 -38.94150708
OS 54.87401268 -38.947979
OS 54.85459692 -38.95445092
OS 54.83148292 -38.95814916
OS 54.8065198 -38.95999828
OS 54.7972742 -38.95999828
OS 54.79080228 -38.95907372
OS 54.7834058 -38.95814916
OS 54.7741602 -38.95630004
OS 54.76399004 -38.95445092
OS 54.75289532 -38.95167724
OS 54.7418006 -38.947979
OS 54.72978132 -38.94428076
OS 54.71776204 -38.9387334
OS 54.70574276 -38.93226148
OS 54.69372348 -38.924865
OS 54.6817042 -38.9156194
OS 54.67060948 -38.90544924
OS 54.66043932 -38.89435452
OS 54.65951476 -38.89342996
OS 54.65766564 -38.89065628
OS 54.65489196 -38.88603348
OS 54.65026916 -38.878637
OS 54.64564636 -38.87031596
OS 54.64102356 -38.85922124
OS 54.63455164 -38.8462774
OS 54.62900428 -38.83148444
OS 54.62345692 -38.81484236
OS 54.61790956 -38.7954266
OS 54.6123622 -38.77416172
OS 54.6077394 -38.75012316
OS 54.6031166 -38.72423548
OS 54.60034292 -38.69649868
OS 54.5984938 -38.6659882
OS 54.59756924 -38.6336286
OS 54.59756924 -38.63270404
OS 54.59756924 -38.6290058
OS 54.59756924 -38.62253388
OS 54.59756924 -38.6151374
OS 54.5984938 -38.60496724
OS 54.5984938 -38.59387252
OS 54.59941836 -38.58185324
OS 54.60034292 -38.56798484
OS 54.6031166 -38.53932348
OS 54.6077394 -38.508813
OS 54.61328676 -38.47830252
OS 54.616985 -38.46443412
OS 54.62068324 -38.45056572
OS 54.62068324 -38.44964116
OS 54.6216078 -38.44779204
OS 54.62345692 -38.4440938
OS 54.62530604 -38.439471
OS 54.62715516 -38.43299908
OS 54.6308534 -38.42652716
OS 54.63824988 -38.41080964
OS 54.64749548 -38.39416756
OS 54.65951476 -38.37660092
OS 54.67338316 -38.35903428
OS 54.69002524 -38.34424132
OS 54.6909498 -38.34424132
OS 54.69187436 -38.3423922
OS 54.69464804 -38.34054308
OS 54.69834628 -38.33869396
OS 54.70296908 -38.33499572
OS 54.70851644 -38.33222204
OS 54.72238484 -38.32482556
OS 54.73902692 -38.31835364
OS 54.75844268 -38.31188172
OS 54.78155668 -38.30818348
OS 54.8065198 -38.30633436
OS 54.81484084 -38.30633436
OS 54.825011 -38.30725892
OE
OB 49.95350436 -38.72331092 I
OS 50.040413 -38.72331092
OS 50.040413 -38.7954266
OS 49.95350436 -38.7954266
OS 49.95350436 -38.94890356
OS 49.87491676 -38.94890356
OS 49.87491676 -38.7954266
OS 49.5966242 -38.7954266
OS 49.5966242 -38.72331092
OS 49.88970972 -38.30910804
OS 49.95350436 -38.30910804
OS 49.95350436 -38.72331092
OE
OB 50.1467374 -38.95999828 I
OS 50.08386732 -38.95999828
OS 50.26970388 -38.29801332
OS 50.33257396 -38.29801332
OS 50.1467374 -38.95999828
OE
OB 50.59699812 -38.30725892 I
OS 50.6043946 -38.30818348
OS 50.6136402 -38.30910804
OS 50.62381036 -38.31095716
OS 50.63398052 -38.31280628
OS 50.65801908 -38.3192782
OS 50.68205764 -38.3285238
OS 50.69407692 -38.33407116
OS 50.7060962 -38.34054308
OS 50.71719092 -38.34886412
OS 50.72736108 -38.35810972
OS 50.72828564 -38.35903428
OS 50.73013476 -38.35995884
OS 50.73198388 -38.36365708
OS 50.73568212 -38.36735532
OS 50.74030492 -38.37197812
OS 50.74492772 -38.37845004
OS 50.74955052 -38.38492196
OS 50.75509788 -38.393243
OS 50.76434348 -38.41080964
OS 50.77358908 -38.43299908
OS 50.77728732 -38.4440938
OS 50.77913644 -38.45703764
OS 50.78098556 -38.46998148
OS 50.78191012 -38.48384988
OS 50.78191012 -38.485699
OS 50.78191012 -38.4903218
OS 50.78098556 -38.49771828
OS 50.780061 -38.50788844
OS 50.77821188 -38.51898316
OS 50.77451364 -38.531927
OS 50.7708154 -38.5457954
OS 50.76526804 -38.5596638
OS 50.76434348 -38.56151292
OS 50.76249436 -38.56613572
OS 50.75879612 -38.5735322
OS 50.75324876 -38.58370236
OS 50.74585228 -38.59479708
OS 50.73660668 -38.60866548
OS 50.72551196 -38.62253388
OS 50.71256812 -38.6382514
OS 50.710719 -38.64010052
OS 50.7060962 -38.64564788
OS 50.7014734 -38.65027068
OS 50.6968506 -38.65489348
OS 50.69130324 -38.66044084
OS 50.68390676 -38.66783732
OS 50.67651028 -38.6752338
OS 50.66726468 -38.68355484
OS 50.65801908 -38.69280044
OS 50.64692436 -38.7029706
OS 50.63490508 -38.71314076
OS 50.62196124 -38.72516004
OS 50.60716828 -38.73717932
OS 50.59237532 -38.75012316
OS 50.59145076 -38.75104772
OS 50.58960164 -38.75289684
OS 50.5859034 -38.75567052
OS 50.5812806 -38.75936876
OS 50.57573324 -38.76491612
OS 50.56926132 -38.77046348
OS 50.55446836 -38.78248276
OS 50.53875084 -38.79635116
OS 50.52395788 -38.81021956
OS 50.51101404 -38.82223884
OS 50.50546668 -38.82686164
OS 50.50084388 -38.83148444
OS 50.49991932 -38.832409
OS 50.49714564 -38.83518268
OS 50.4934474 -38.83888092
OS 50.4888246 -38.84442828
OS 50.4842018 -38.8509002
OS 50.47865444 -38.85737212
OS 50.46755972 -38.87308964
OS 50.78283468 -38.87308964
OS 50.78283468 -38.94890356
OS 50.35846164 -38.94890356
OS 50.35846164 -38.947979
OS 50.35846164 -38.94428076
OS 50.35846164 -38.9387334
OS 50.3593862 -38.93133692
OS 50.36031076 -38.92301588
OS 50.36215988 -38.91377028
OS 50.364009 -38.90452468
OS 50.36770724 -38.89435452
OS 50.36770724 -38.89342996
OS 50.3686318 -38.8925054
OS 50.37048092 -38.88695804
OS 50.37417916 -38.878637
OS 50.37972652 -38.86754228
OS 50.387123 -38.85459844
OS 50.3963686 -38.83980548
OS 50.40653876 -38.82501252
OS 50.4194826 -38.809295
OS 50.4194826 -38.80837044
OS 50.42133172 -38.80744588
OS 50.42595452 -38.80189852
OS 50.43427556 -38.79357748
OS 50.44629484 -38.7815582
OS 50.46016324 -38.7676898
OS 50.47772988 -38.75104772
OS 50.49899476 -38.73255652
OS 50.52210876 -38.71314076
OS 50.52303332 -38.7122162
OS 50.52673156 -38.70944252
OS 50.53227892 -38.70481972
OS 50.53875084 -38.69927236
OS 50.54707188 -38.69187588
OS 50.55724204 -38.68355484
OS 50.5674122 -38.67430924
OS 50.57943148 -38.66413908
OS 50.60254548 -38.64194964
OS 50.62565948 -38.6197602
OS 50.6367542 -38.60866548
OS 50.64692436 -38.59757076
OS 50.65616996 -38.5874006
OS 50.66356644 -38.57723044
OS 50.66356644 -38.57630588
OS 50.66541556 -38.57538132
OS 50.66726468 -38.57260764
OS 50.6691138 -38.5689094
OS 50.67558572 -38.55873924
OS 50.6829822 -38.54671996
OS 50.68945412 -38.531927
OS 50.69592604 -38.51620948
OS 50.69962428 -38.49864284
OS 50.7014734 -38.48200076
OS 50.7014734 -38.4810762
OS 50.7014734 -38.48015164
OS 50.70054884 -38.47460428
OS 50.69962428 -38.46535868
OS 50.6968506 -38.45518852
OS 50.69315236 -38.44224468
OS 50.68668044 -38.42930084
OS 50.6783594 -38.416357
OS 50.66726468 -38.40341316
OS 50.66541556 -38.40156404
OS 50.66079276 -38.3978658
OS 50.65432084 -38.393243
OS 50.64415068 -38.38677108
OS 50.63120684 -38.38122372
OS 50.61641388 -38.37567636
OS 50.59884724 -38.37197812
OS 50.57943148 -38.37105356
OS 50.57388412 -38.37105356
OS 50.57018588 -38.37197812
OS 50.55909116 -38.37290268
OS 50.54614732 -38.37567636
OS 50.53227892 -38.3793746
OS 50.5165614 -38.38584652
OS 50.50176844 -38.39416756
OS 50.48790004 -38.40526228
OS 50.48605092 -38.4071114
OS 50.48235268 -38.4117342
OS 50.47680532 -38.41913068
OS 50.47125796 -38.4302254
OS 50.46478604 -38.44316924
OS 50.45923868 -38.45981132
OS 50.45554044 -38.47830252
OS 50.45369132 -38.4995674
OS 50.3732546 -38.49124636
OS 50.3732546 -38.4903218
OS 50.37417916 -38.48754812
OS 50.37417916 -38.48292532
OS 50.37510372 -38.4764534
OS 50.37695284 -38.46905692
OS 50.37880196 -38.46073588
OS 50.38157564 -38.45056572
OS 50.38434932 -38.44039556
OS 50.3917458 -38.41820612
OS 50.40284052 -38.39601668
OS 50.40931244 -38.38492196
OS 50.41763348 -38.37382724
OS 50.42595452 -38.36365708
OS 50.43520012 -38.35441148
OS 50.43612468 -38.35348692
OS 50.4379738 -38.35256236
OS 50.44074748 -38.34978868
OS 50.44537028 -38.347015
OS 50.45091764 -38.34331676
OS 50.45738956 -38.33961852
OS 50.46478604 -38.33499572
OS 50.47403164 -38.33037292
OS 50.4842018 -38.32575012
OS 50.49529652 -38.32112732
OS 50.5073158 -38.31742908
OS 50.52025964 -38.31373084
OS 50.53412804 -38.31095716
OS 50.548921 -38.30818348
OS 50.56463852 -38.30725892
OS 50.5812806 -38.30633436
OS 50.5905262 -38.30633436
OS 50.59699812 -38.30725892
OE
OB 48.67576244 -38.94890356 I
OS 48.59717484 -38.94890356
OS 48.59717484 -38.4487166
OS 48.59625028 -38.44964116
OS 48.59162748 -38.4533394
OS 48.58608012 -38.45888676
OS 48.57683452 -38.46535868
OS 48.56666436 -38.47367972
OS 48.55372052 -38.48292532
OS 48.53892756 -38.49309548
OS 48.52228548 -38.50326564
OS 48.52136092 -38.50326564
OS 48.52043636 -38.5041902
OS 48.514889 -38.50788844
OS 48.5056434 -38.51251124
OS 48.49454868 -38.5180586
OS 48.48160484 -38.52453052
OS 48.46773644 -38.53100244
OS 48.45386804 -38.53747436
OS 48.43999964 -38.54302172
OS 48.43999964 -38.4672078
OS 48.4409242 -38.4672078
OS 48.44277332 -38.46535868
OS 48.44647156 -38.46443412
OS 48.45109436 -38.46166044
OS 48.45664172 -38.45888676
OS 48.46311364 -38.45518852
OS 48.47883116 -38.44594292
OS 48.49732236 -38.43577276
OS 48.51581356 -38.42282892
OS 48.53522932 -38.40803596
OS 48.55464508 -38.39231844
OS 48.55556964 -38.39139388
OS 48.5564942 -38.39046932
OS 48.55926788 -38.38769564
OS 48.56296612 -38.38492196
OS 48.57128716 -38.37567636
OS 48.58238188 -38.36458164
OS 48.5934766 -38.3516378
OS 48.60549588 -38.33684484
OS 48.61566604 -38.32205188
OS 48.62491164 -38.30633436
OS 48.67576244 -38.30633436
OS 48.67576244 -38.94890356
OE
OB 48.9032042 -38.95999828 I
OS 48.84033412 -38.95999828
OS 49.02617068 -38.29801332
OS 49.08904076 -38.29801332
OS 48.9032042 -38.95999828
OE
OB 49.35346492 -38.30725892 I
OS 49.3608614 -38.30818348
OS 49.370107 -38.30910804
OS 49.38027716 -38.31095716
OS 49.39044732 -38.31280628
OS 49.41448588 -38.3192782
OS 49.43852444 -38.3285238
OS 49.45054372 -38.33407116
OS 49.462563 -38.34054308
OS 49.47365772 -38.34886412
OS 49.48382788 -38.35810972
OS 49.48475244 -38.35903428
OS 49.48660156 -38.35995884
OS 49.48845068 -38.36365708
OS 49.49214892 -38.36735532
OS 49.49677172 -38.37197812
OS 49.50139452 -38.37845004
OS 49.50601732 -38.38492196
OS 49.51156468 -38.393243
OS 49.52081028 -38.41080964
OS 49.53005588 -38.43299908
OS 49.53375412 -38.4440938
OS 49.53560324 -38.45703764
OS 49.53745236 -38.46998148
OS 49.53837692 -38.48384988
OS 49.53837692 -38.485699
OS 49.53837692 -38.4903218
OS 49.53745236 -38.49771828
OS 49.5365278 -38.50788844
OS 49.53467868 -38.51898316
OS 49.53098044 -38.531927
OS 49.5272822 -38.5457954
OS 49.52173484 -38.5596638
OS 49.52081028 -38.56151292
OS 49.51896116 -38.56613572
OS 49.51526292 -38.5735322
OS 49.50971556 -38.58370236
OS 49.50231908 -38.59479708
OS 49.49307348 -38.60866548
OS 49.48197876 -38.62253388
OS 49.46903492 -38.6382514
OS 49.4671858 -38.64010052
OS 49.462563 -38.64564788
OS 49.4579402 -38.65027068
OS 49.4533174 -38.65489348
OS 49.44777004 -38.66044084
OS 49.44037356 -38.66783732
OS 49.43297708 -38.6752338
OS 49.42373148 -38.68355484
OS 49.41448588 -38.69280044
OS 49.40339116 -38.7029706
OS 49.39137188 -38.71314076
OS 49.37842804 -38.72516004
OS 49.36363508 -38.73717932
OS 49.34884212 -38.75012316
OS 49.34791756 -38.75104772
OS 49.34606844 -38.75289684
OS 49.3423702 -38.75567052
OS 49.3377474 -38.75936876
OS 49.33220004 -38.76491612
OS 49.32572812 -38.77046348
OS 49.31093516 -38.78248276
OS 49.29521764 -38.79635116
OS 49.28042468 -38.81021956
OS 49.26748084 -38.82223884
OS 49.26193348 -38.82686164
OS 49.25731068 -38.83148444
OS 49.25638612 -38.832409
OS 49.25361244 -38.83518268
OS 49.2499142 -38.83888092
OS 49.2452914 -38.84442828
OS 49.2406686 -38.8509002
OS 49.23512124 -38.85737212
OS 49.22402652 -38.87308964
OS 49.53930148 -38.87308964
OS 49.53930148 -38.94890356
OS 49.11492844 -38.94890356
OS 49.11492844 -38.947979
OS 49.11492844 -38.94428076
OS 49.11492844 -38.9387334
OS 49.115853 -38.93133692
OS 49.11677756 -38.92301588
OS 49.11862668 -38.91377028
OS 49.1204758 -38.90452468
OS 49.12417404 -38.89435452
OS 49.12417404 -38.89342996
OS 49.1250986 -38.8925054
OS 49.12694772 -38.88695804
OS 49.13064596 -38.878637
OS 49.13619332 -38.86754228
OS 49.1435898 -38.85459844
OS 49.1528354 -38.83980548
OS 49.16300556 -38.82501252
OS 49.1759494 -38.809295
OS 49.1759494 -38.80837044
OS 49.17779852 -38.80744588
OS 49.18242132 -38.80189852
OS 49.19074236 -38.79357748
OS 49.20276164 -38.7815582
OS 49.21663004 -38.7676898
OS 49.23419668 -38.75104772
OS 49.25546156 -38.73255652
OS 49.27857556 -38.71314076
OS 49.27950012 -38.7122162
OS 49.28319836 -38.70944252
OS 49.28874572 -38.70481972
OS 49.29521764 -38.69927236
OS 49.30353868 -38.69187588
OS 49.31370884 -38.68355484
OS 49.323879 -38.67430924
OS 49.33589828 -38.66413908
OS 49.35901228 -38.64194964
OS 49.38212628 -38.6197602
OS 49.393221 -38.60866548
OS 49.40339116 -38.59757076
OS 49.41263676 -38.5874006
OS 49.42003324 -38.57723044
OS 49.42003324 -38.57630588
OS 49.42188236 -38.57538132
OS 49.42373148 -38.57260764
OS 49.4255806 -38.5689094
OS 49.43205252 -38.55873924
OS 49.439449 -38.54671996
OS 49.44592092 -38.531927
OS 49.45239284 -38.51620948
OS 49.45609108 -38.49864284
OS 49.4579402 -38.48200076
OS 49.4579402 -38.4810762
OS 49.4579402 -38.48015164
OS 49.45701564 -38.47460428
OS 49.45609108 -38.46535868
OS 49.4533174 -38.45518852
OS 49.44961916 -38.44224468
OS 49.44314724 -38.42930084
OS 49.4348262 -38.416357
OS 49.42373148 -38.40341316
OS 49.42188236 -38.40156404
OS 49.41725956 -38.3978658
OS 49.41078764 -38.393243
OS 49.40061748 -38.38677108
OS 49.38767364 -38.38122372
OS 49.37288068 -38.37567636
OS 49.35531404 -38.37197812
OS 49.33589828 -38.37105356
OS 49.33035092 -38.37105356
OS 49.32665268 -38.37197812
OS 49.31555796 -38.37290268
OS 49.30261412 -38.37567636
OS 49.28874572 -38.3793746
OS 49.2730282 -38.38584652
OS 49.25823524 -38.39416756
OS 49.24436684 -38.40526228
OS 49.24251772 -38.4071114
OS 49.23881948 -38.4117342
OS 49.23327212 -38.41913068
OS 49.22772476 -38.4302254
OS 49.22125284 -38.44316924
OS 49.21570548 -38.45981132
OS 49.21200724 -38.47830252
OS 49.21015812 -38.4995674
OS 49.1297214 -38.49124636
OS 49.1297214 -38.4903218
OS 49.13064596 -38.48754812
OS 49.13064596 -38.48292532
OS 49.13157052 -38.4764534
OS 49.13341964 -38.46905692
OS 49.13526876 -38.46073588
OS 49.13804244 -38.45056572
OS 49.14081612 -38.44039556
OS 49.1482126 -38.41820612
OS 49.15930732 -38.39601668
OS 49.16577924 -38.38492196
OS 49.17410028 -38.37382724
OS 49.18242132 -38.36365708
OS 49.19166692 -38.35441148
OS 49.19259148 -38.35348692
OS 49.1944406 -38.35256236
OS 49.19721428 -38.34978868
OS 49.20183708 -38.347015
OS 49.20738444 -38.34331676
OS 49.21385636 -38.33961852
OS 49.22125284 -38.33499572
OS 49.23049844 -38.33037292
OS 49.2406686 -38.32575012
OS 49.25176332 -38.32112732
OS 49.2637826 -38.31742908
OS 49.27672644 -38.31373084
OS 49.29059484 -38.31095716
OS 49.3053878 -38.30818348
OS 49.32110532 -38.30725892
OS 49.3377474 -38.30633436
OS 49.346993 -38.30633436
OS 49.35346492 -38.30725892
OE
OB 51.0944114 -38.30725892 I
OS 51.10643068 -38.30910804
OS 51.12029908 -38.31188172
OS 51.13509204 -38.31557996
OS 51.15080956 -38.32020276
OS 51.16560252 -38.32759924
OS 51.16652708 -38.32759924
OS 51.16745164 -38.3285238
OS 51.17207444 -38.33129748
OS 51.17947092 -38.33592028
OS 51.18871652 -38.3423922
OS 51.19888668 -38.3516378
OS 51.2099814 -38.36180796
OS 51.22015156 -38.37382724
OS 51.23032172 -38.38769564
OS 51.23124628 -38.38954476
OS 51.23494452 -38.39416756
OS 51.23864276 -38.4024886
OS 51.24511468 -38.41450788
OS 51.25066204 -38.42837628
OS 51.25805852 -38.4440938
OS 51.26453044 -38.462585
OS 51.2700778 -38.48292532
OS 51.2700778 -38.48384988
OS 51.27100236 -38.485699
OS 51.27192692 -38.48847268
OS 51.27285148 -38.49309548
OS 51.27377604 -38.49864284
OS 51.2747006 -38.50511476
OS 51.27654972 -38.5134358
OS 51.27747428 -38.5226814
OS 51.2793234 -38.53285156
OS 51.28024796 -38.54394628
OS 51.28117252 -38.55689012
OS 51.28302164 -38.56983396
OS 51.2839462 -38.58462692
OS 51.2839462 -38.59941988
OS 51.28487076 -38.61606196
OS 51.28487076 -38.6336286
OS 51.28487076 -38.63455316
OS 51.28487076 -38.6382514
OS 51.28487076 -38.64472332
OS 51.28487076 -38.6521198
OS 51.2839462 -38.66228996
OS 51.2839462 -38.67338468
OS 51.28302164 -38.68540396
OS 51.28209708 -38.6983478
OS 51.2793234 -38.72793372
OS 51.2747006 -38.7584442
OS 51.26915324 -38.78803012
OS 51.265455 -38.80189852
OS 51.2608322 -38.81576692
OS 51.2608322 -38.81669148
OS 51.25990764 -38.8185406
OS 51.25805852 -38.82223884
OS 51.2562094 -38.82686164
OS 51.25436028 -38.83333356
OS 51.25066204 -38.83980548
OS 51.24326556 -38.855523
OS 51.23401996 -38.87216508
OS 51.22200068 -38.89065628
OS 51.20813228 -38.90729836
OS 51.1914902 -38.92301588
OS 51.19056564 -38.92301588
OS 51.18964108 -38.924865
OS 51.1868674 -38.92671412
OS 51.18316916 -38.92856324
OS 51.17854636 -38.93133692
OS 51.17392356 -38.93503516
OS 51.16005516 -38.94150708
OS 51.14341308 -38.947979
OS 51.12399732 -38.95445092
OS 51.10088332 -38.95814916
OS 51.0759202 -38.95999828
OS 51.0666746 -38.95999828
OS 51.06020268 -38.95907372
OS 51.0528062 -38.95814916
OS 51.0435606 -38.95630004
OS 51.03339044 -38.95445092
OS 51.02229572 -38.95167724
OS 51.011201 -38.947979
OS 50.99918172 -38.94428076
OS 50.98716244 -38.9387334
OS 50.97514316 -38.93226148
OS 50.96312388 -38.924865
OS 50.9511046 -38.9156194
OS 50.94000988 -38.90544924
OS 50.92983972 -38.89435452
OS 50.92891516 -38.89342996
OS 50.92706604 -38.89065628
OS 50.92429236 -38.88603348
OS 50.91966956 -38.878637
OS 50.91504676 -38.87031596
OS 50.91042396 -38.85922124
OS 50.90395204 -38.8462774
OS 50.89840468 -38.83148444
OS 50.89285732 -38.81484236
OS 50.88730996 -38.7954266
OS 50.8817626 -38.77416172
OS 50.8771398 -38.75012316
OS 50.872517 -38.72423548
OS 50.86974332 -38.69649868
OS 50.8678942 -38.6659882
OS 50.86696964 -38.6336286
OS 50.86696964 -38.63270404
OS 50.86696964 -38.6290058
OS 50.86696964 -38.62253388
OS 50.86696964 -38.6151374
OS 50.8678942 -38.60496724
OS 50.8678942 -38.59387252
OS 50.86881876 -38.58185324
OS 50.86974332 -38.56798484
OS 50.872517 -38.53932348
OS 50.8771398 -38.508813
OS 50.88268716 -38.47830252
OS 50.8863854 -38.46443412
OS 50.89008364 -38.45056572
OS 50.89008364 -38.44964116
OS 50.8910082 -38.44779204
OS 50.89285732 -38.4440938
OS 50.89470644 -38.439471
OS 50.89655556 -38.43299908
OS 50.9002538 -38.42652716
OS 50.90765028 -38.41080964
OS 50.91689588 -38.39416756
OS 50.92891516 -38.37660092
OS 50.94278356 -38.35903428
OS 50.95942564 -38.34424132
OS 50.9603502 -38.34424132
OS 50.96127476 -38.3423922
OS 50.96404844 -38.34054308
OS 50.96774668 -38.33869396
OS 50.97236948 -38.33499572
OS 50.97791684 -38.33222204
OS 50.99178524 -38.32482556
OS 51.00842732 -38.31835364
OS 51.02784308 -38.31188172
OS 51.05095708 -38.30818348
OS 51.0759202 -38.30633436
OS 51.08424124 -38.30633436
OS 51.0944114 -38.30725892
OE
OB 51.59182468 -38.30725892 I
OS 51.59922116 -38.30818348
OS 51.60846676 -38.30910804
OS 51.61863692 -38.31095716
OS 51.62880708 -38.31280628
OS 51.65284564 -38.3192782
OS 51.6768842 -38.3285238
OS 51.68890348 -38.33407116
OS 51.70092276 -38.34054308
OS 51.71201748 -38.34886412
OS 51.72218764 -38.35810972
OS 51.7231122 -38.35903428
OS 51.72496132 -38.35995884
OS 51.72681044 -38.36365708
OS 51.73050868 -38.36735532
OS 51.73513148 -38.37197812
OS 51.73975428 -38.37845004
OS 51.74437708 -38.38492196
OS 51.74992444 -38.393243
OS 51.75917004 -38.41080964
OS 51.76841564 -38.43299908
OS 51.77211388 -38.4440938
OS 51.773963 -38.45703764
OS 51.77581212 -38.46998148
OS 51.77673668 -38.48384988
OS 51.77673668 -38.485699
OS 51.77673668 -38.4903218
OS 51.77581212 -38.49771828
OS 51.77488756 -38.50788844
OS 51.77303844 -38.51898316
OS 51.7693402 -38.531927
OS 51.76564196 -38.5457954
OS 51.7600946 -38.5596638
OS 51.75917004 -38.56151292
OS 51.75732092 -38.56613572
OS 51.75362268 -38.5735322
OS 51.74807532 -38.58370236
OS 51.74067884 -38.59479708
OS 51.73143324 -38.60866548
OS 51.72033852 -38.62253388
OS 51.70739468 -38.6382514
OS 51.70554556 -38.64010052
OS 51.70092276 -38.64564788
OS 51.69629996 -38.65027068
OS 51.69167716 -38.65489348
OS 51.6861298 -38.66044084
OS 51.67873332 -38.66783732
OS 51.67133684 -38.6752338
OS 51.66209124 -38.68355484
OS 51.65284564 -38.69280044
OS 51.64175092 -38.7029706
OS 51.62973164 -38.71314076
OS 51.6167878 -38.72516004
OS 51.60199484 -38.73717932
OS 51.58720188 -38.75012316
OS 51.58627732 -38.75104772
OS 51.5844282 -38.75289684
OS 51.58072996 -38.75567052
OS 51.57610716 -38.75936876
OS 51.5705598 -38.76491612
OS 51.56408788 -38.77046348
OS 51.54929492 -38.78248276
OS 51.5335774 -38.79635116
OS 51.51878444 -38.81021956
OS 51.5058406 -38.82223884
OS 51.50029324 -38.82686164
OS 51.49567044 -38.83148444
OS 51.49474588 -38.832409
OS 51.4919722 -38.83518268
OS 51.48827396 -38.83888092
OS 51.48365116 -38.84442828
OS 51.47902836 -38.8509002
OS 51.473481 -38.85737212
OS 51.46238628 -38.87308964
OS 51.77766124 -38.87308964
OS 51.77766124 -38.94890356
OS 51.3532882 -38.94890356
OS 51.3532882 -38.947979
OS 51.3532882 -38.94428076
OS 51.3532882 -38.9387334
OS 51.35421276 -38.93133692
OS 51.35513732 -38.92301588
OS 51.35698644 -38.91377028
OS 51.35883556 -38.90452468
OS 51.3625338 -38.89435452
OS 51.3625338 -38.89342996
OS 51.36345836 -38.8925054
OS 51.36530748 -38.88695804
OS 51.36900572 -38.878637
OS 51.37455308 -38.86754228
OS 51.38194956 -38.85459844
OS 51.39119516 -38.83980548
OS 51.40136532 -38.82501252
OS 51.41430916 -38.809295
OS 51.41430916 -38.80837044
OS 51.41615828 -38.80744588
OS 51.42078108 -38.80189852
OS 51.42910212 -38.79357748
OS 51.4411214 -38.7815582
OS 51.4549898 -38.7676898
OS 51.47255644 -38.75104772
OS 51.49382132 -38.73255652
OS 51.51693532 -38.71314076
OS 51.51785988 -38.7122162
OS 51.52155812 -38.70944252
OS 51.52710548 -38.70481972
OS 51.5335774 -38.69927236
OS 51.54189844 -38.69187588
OS 51.5520686 -38.68355484
OS 51.56223876 -38.67430924
OS 51.57425804 -38.66413908
OS 51.59737204 -38.64194964
OS 51.62048604 -38.6197602
OS 51.63158076 -38.60866548
OS 51.64175092 -38.59757076
OS 51.65099652 -38.5874006
OS 51.658393 -38.57723044
OS 51.658393 -38.57630588
OS 51.66024212 -38.57538132
OS 51.66209124 -38.57260764
OS 51.66394036 -38.5689094
OS 51.67041228 -38.55873924
OS 51.67780876 -38.54671996
OS 51.68428068 -38.531927
OS 51.6907526 -38.51620948
OS 51.69445084 -38.49864284
OS 51.69629996 -38.48200076
OS 51.69629996 -38.4810762
OS 51.69629996 -38.48015164
OS 51.6953754 -38.47460428
OS 51.69445084 -38.46535868
OS 51.69167716 -38.45518852
OS 51.68797892 -38.44224468
OS 51.681507 -38.42930084
OS 51.67318596 -38.416357
OS 51.66209124 -38.40341316
OS 51.66024212 -38.40156404
OS 51.65561932 -38.3978658
OS 51.6491474 -38.393243
OS 51.63897724 -38.38677108
OS 51.6260334 -38.38122372
OS 51.61124044 -38.37567636
OS 51.5936738 -38.37197812
OS 51.57425804 -38.37105356
OS 51.56871068 -38.37105356
OS 51.56501244 -38.37197812
OS 51.55391772 -38.37290268
OS 51.54097388 -38.37567636
OS 51.52710548 -38.3793746
OS 51.51138796 -38.38584652
OS 51.496595 -38.39416756
OS 51.4827266 -38.40526228
OS 51.48087748 -38.4071114
OS 51.47717924 -38.4117342
OS 51.47163188 -38.41913068
OS 51.46608452 -38.4302254
OS 51.4596126 -38.44316924
OS 51.45406524 -38.45981132
OS 51.450367 -38.47830252
OS 51.44851788 -38.4995674
OS 51.36808116 -38.49124636
OS 51.36808116 -38.4903218
OS 51.36900572 -38.48754812
OS 51.36900572 -38.48292532
OS 51.36993028 -38.4764534
OS 51.3717794 -38.46905692
OS 51.37362852 -38.46073588
OS 51.3764022 -38.45056572
OS 51.37917588 -38.44039556
OS 51.38657236 -38.41820612
OS 51.39766708 -38.39601668
OS 51.404139 -38.38492196
OS 51.41246004 -38.37382724
OS 51.42078108 -38.36365708
OS 51.43002668 -38.35441148
OS 51.43095124 -38.35348692
OS 51.43280036 -38.35256236
OS 51.43557404 -38.34978868
OS 51.44019684 -38.347015
OS 51.4457442 -38.34331676
OS 51.45221612 -38.33961852
OS 51.4596126 -38.33499572
OS 51.4688582 -38.33037292
OS 51.47902836 -38.32575012
OS 51.49012308 -38.32112732
OS 51.50214236 -38.31742908
OS 51.5150862 -38.31373084
OS 51.5289546 -38.31095716
OS 51.54374756 -38.30818348
OS 51.55946508 -38.30725892
OS 51.57610716 -38.30633436
OS 51.58535276 -38.30633436
OS 51.59182468 -38.30725892
OE
OB 52.08184148 -38.30725892 I
OS 52.09386076 -38.30910804
OS 52.10865372 -38.31188172
OS 52.1252958 -38.31650452
OS 52.14193788 -38.32205188
OS 52.15857996 -38.32944836
OS 52.15950452 -38.32944836
OS 52.16042908 -38.33037292
OS 52.16597644 -38.3331466
OS 52.17429748 -38.33869396
OS 52.18354308 -38.34516588
OS 52.1946378 -38.35441148
OS 52.20573252 -38.36458164
OS 52.21682724 -38.37660092
OS 52.22607284 -38.39046932
OS 52.2269974 -38.39231844
OS 52.22977108 -38.39694124
OS 52.23346932 -38.40526228
OS 52.23809212 -38.41543244
OS 52.24271492 -38.42745172
OS 52.24641316 -38.44132012
OS 52.24918684 -38.45703764
OS 52.2501114 -38.47275516
OS 52.2501114 -38.47460428
OS 52.2501114 -38.48015164
OS 52.24918684 -38.48754812
OS 52.24733772 -38.49771828
OS 52.24456404 -38.50973756
OS 52.23994124 -38.5226814
OS 52.23439388 -38.53562524
OS 52.2269974 -38.54856908
OS 52.22607284 -38.5504182
OS 52.22329916 -38.55411644
OS 52.2177518 -38.56058836
OS 52.21035532 -38.56798484
OS 52.20110972 -38.57630588
OS 52.190015 -38.58555148
OS 52.17707116 -38.59387252
OS 52.16135364 -38.60219356
OS 52.1622782 -38.60219356
OS 52.16412732 -38.60311812
OS 52.166901 -38.60404268
OS 52.17059924 -38.60496724
OS 52.1807694 -38.60866548
OS 52.19371324 -38.61421284
OS 52.2085062 -38.62160932
OS 52.22329916 -38.63085492
OS 52.23716756 -38.6428742
OS 52.2501114 -38.6567426
OS 52.25103596 -38.65859172
OS 52.2547342 -38.66413908
OS 52.26028156 -38.67338468
OS 52.26582892 -38.68540396
OS 52.27137628 -38.70019692
OS 52.27692364 -38.71776356
OS 52.28062188 -38.73810388
OS 52.28154644 -38.76029332
OS 52.28154644 -38.76121788
OS 52.28154644 -38.76399156
OS 52.28154644 -38.76861436
OS 52.28062188 -38.77416172
OS 52.27969732 -38.7815582
OS 52.2778482 -38.78987924
OS 52.27599908 -38.79912484
OS 52.27414996 -38.809295
OS 52.26675348 -38.83148444
OS 52.26120612 -38.84350372
OS 52.25565876 -38.85459844
OS 52.24826228 -38.86661772
OS 52.23994124 -38.878637
OS 52.23069564 -38.89065628
OS 52.21960092 -38.901751
OS 52.21867636 -38.90267556
OS 52.21682724 -38.90452468
OS 52.213129 -38.90729836
OS 52.2085062 -38.9109966
OS 52.20295884 -38.9156194
OS 52.19556236 -38.9202422
OS 52.18724132 -38.92578956
OS 52.17707116 -38.93041236
OS 52.166901 -38.93595972
OS 52.15488172 -38.94150708
OS 52.14286244 -38.94612988
OS 52.12899404 -38.95075268
OS 52.11420108 -38.95445092
OS 52.09848356 -38.9572246
OS 52.08276604 -38.95907372
OS 52.0651994 -38.95999828
OS 52.05687836 -38.95999828
OS 52.051331 -38.95907372
OS 52.04393452 -38.95814916
OS 52.03561348 -38.9572246
OS 52.02636788 -38.95537548
OS 52.01619772 -38.95352636
OS 51.99400828 -38.947979
OS 51.97089428 -38.9387334
OS 51.958875 -38.93318604
OS 51.94778028 -38.92671412
OS 51.93668556 -38.91839308
OS 51.92559084 -38.91007204
OS 51.92466628 -38.90914748
OS 51.92281716 -38.90729836
OS 51.92004348 -38.90452468
OS 51.9172698 -38.90082644
OS 51.912647 -38.89620364
OS 51.9080242 -38.88973172
OS 51.90247684 -38.8832598
OS 51.89692948 -38.87493876
OS 51.89138212 -38.86569316
OS 51.88583476 -38.85644756
OS 51.8756646 -38.83425812
OS 51.86734356 -38.80837044
OS 51.86456988 -38.79450204
OS 51.86272076 -38.77970908
OS 51.94130836 -38.76953892
OS 51.94130836 -38.77046348
OS 51.94223292 -38.7723126
OS 51.94315748 -38.77601084
OS 51.94408204 -38.78063364
OS 51.9450066 -38.786181
OS 51.94685572 -38.79265292
OS 51.95147852 -38.80652132
OS 51.95795044 -38.8231634
OS 51.96627148 -38.83888092
OS 51.97551708 -38.85367388
OS 51.9866118 -38.86661772
OS 51.98846092 -38.86754228
OS 51.99215916 -38.87124052
OS 51.99955564 -38.87586332
OS 52.00880124 -38.88048612
OS 52.01989596 -38.88603348
OS 52.03376436 -38.89065628
OS 52.04948188 -38.89435452
OS 52.06612396 -38.89527908
OS 52.07167132 -38.89527908
OS 52.07536956 -38.89435452
OS 52.08553972 -38.89342996
OS 52.09848356 -38.89065628
OS 52.11327652 -38.88603348
OS 52.12899404 -38.87956156
OS 52.14471156 -38.87031596
OS 52.15950452 -38.85737212
OS 52.16135364 -38.855523
OS 52.16597644 -38.84997564
OS 52.1715238 -38.8416546
OS 52.17892028 -38.83055988
OS 52.18631676 -38.81669148
OS 52.19186412 -38.80097396
OS 52.19648692 -38.78248276
OS 52.19833604 -38.76214244
OS 52.19833604 -38.76121788
OS 52.19833604 -38.75936876
OS 52.19833604 -38.75659508
OS 52.19741148 -38.75289684
OS 52.19648692 -38.74272668
OS 52.19371324 -38.7307074
OS 52.190015 -38.71591444
OS 52.18354308 -38.70112148
OS 52.17429748 -38.68632852
OS 52.1622782 -38.67246012
OS 52.16042908 -38.670611
OS 52.15580628 -38.66691276
OS 52.1484098 -38.6613654
OS 52.13823964 -38.65489348
OS 52.1252958 -38.64842156
OS 52.10957828 -38.6428742
OS 52.09201164 -38.63917596
OS 52.07259588 -38.63732684
OS 52.06427484 -38.63732684
OS 52.05780292 -38.6382514
OS 52.04948188 -38.63917596
OS 52.04023628 -38.64102508
OS 52.02914156 -38.6428742
OS 52.01712228 -38.64564788
OS 52.02636788 -38.57630588
OS 52.03099068 -38.57630588
OS 52.03468892 -38.57723044
OS 52.0467082 -38.57723044
OS 52.05687836 -38.57538132
OS 52.06889764 -38.5735322
OS 52.08276604 -38.57075852
OS 52.09848356 -38.56613572
OS 52.11327652 -38.5596638
OS 52.12899404 -38.55134276
OS 52.1299186 -38.55134276
OS 52.13084316 -38.5504182
OS 52.13546596 -38.54671996
OS 52.14193788 -38.54024804
OS 52.14933436 -38.531927
OS 52.15673084 -38.51990772
OS 52.16320276 -38.50603932
OS 52.16782556 -38.4903218
OS 52.16967468 -38.4810762
OS 52.16967468 -38.47090604
OS 52.16967468 -38.46998148
OS 52.16967468 -38.46905692
OS 52.16967468 -38.46350956
OS 52.16782556 -38.45611308
OS 52.16597644 -38.44594292
OS 52.1622782 -38.4348482
OS 52.1576554 -38.42282892
OS 52.15025892 -38.41080964
OS 52.14008876 -38.39971492
OS 52.1391642 -38.39879036
OS 52.1345414 -38.39509212
OS 52.12806948 -38.39046932
OS 52.11974844 -38.38492196
OS 52.10865372 -38.38029916
OS 52.09570988 -38.37567636
OS 52.08091692 -38.37197812
OS 52.06427484 -38.37105356
OS 52.05687836 -38.37105356
OS 52.04855732 -38.37290268
OS 52.0374626 -38.3747518
OS 52.02544332 -38.37845004
OS 52.01342404 -38.38307284
OS 52.0004802 -38.39046932
OS 51.98846092 -38.39971492
OS 51.98753636 -38.40063948
OS 51.98383812 -38.40526228
OS 51.97829076 -38.4117342
OS 51.97181884 -38.4209798
OS 51.96534692 -38.43299908
OS 51.958875 -38.44779204
OS 51.95332764 -38.46535868
OS 51.9496294 -38.485699
OS 51.8710418 -38.4718306
OS 51.8710418 -38.47090604
OS 51.87196636 -38.46813236
OS 51.87289092 -38.46443412
OS 51.87381548 -38.45888676
OS 51.8756646 -38.45241484
OS 51.87843828 -38.44501836
OS 51.88398564 -38.42745172
OS 51.89323124 -38.4071114
OS 51.90432596 -38.38677108
OS 51.91819436 -38.36735532
OS 51.935761 -38.34978868
OS 51.93668556 -38.34886412
OS 51.93853468 -38.34793956
OS 51.94130836 -38.34609044
OS 51.9450066 -38.34331676
OS 51.9496294 -38.33961852
OS 51.95610132 -38.33592028
OS 51.96257324 -38.33222204
OS 51.97089428 -38.32759924
OS 51.98938548 -38.32020276
OS 52.01065036 -38.31280628
OS 52.03561348 -38.30818348
OS 52.04855732 -38.30633436
OS 52.07167132 -38.30633436
OS 52.08184148 -38.30725892
OE
OB 56.14158444 -38.38492196 H
OS 55.95852156 -38.38492196
OS 55.95852156 -38.61328828
OS 56.13048972 -38.61328828
OS 56.13696164 -38.61236372
OS 56.14343356 -38.61236372
OS 56.15083004 -38.61143916
OS 56.16839668 -38.60959004
OS 56.18781244 -38.6058918
OS 56.2072282 -38.60034444
OS 56.22479484 -38.59294796
OS 56.23311588 -38.58832516
OS 56.2395878 -38.5827778
OS 56.24143692 -38.58092868
OS 56.24513516 -38.57723044
OS 56.25068252 -38.56983396
OS 56.25715444 -38.56058836
OS 56.26362636 -38.54856908
OS 56.26917372 -38.53377612
OS 56.27287196 -38.51713404
OS 56.27472108 -38.49771828
OS 56.27472108 -38.49679372
OS 56.27472108 -38.49586916
OS 56.27472108 -38.49124636
OS 56.27379652 -38.48292532
OS 56.2719474 -38.47367972
OS 56.27009828 -38.46350956
OS 56.26640004 -38.45149028
OS 56.26085268 -38.44039556
OS 56.25438076 -38.42930084
OS 56.2534562 -38.42837628
OS 56.25068252 -38.42467804
OS 56.24605972 -38.42005524
OS 56.24051236 -38.41358332
OS 56.23219132 -38.4071114
OS 56.22294572 -38.40156404
OS 56.21277556 -38.39601668
OS 56.20075628 -38.39139388
OS 56.19983172 -38.39139388
OS 56.19613348 -38.39046932
OS 56.19058612 -38.38954476
OS 56.18318964 -38.38769564
OS 56.17209492 -38.38677108
OS 56.15822652 -38.38584652
OS 56.14158444 -38.38492196
OE
OB 49.87491676 -38.43669732 H
OS 49.67336268 -38.72331092
OS 49.87491676 -38.72331092
OS 49.87491676 -38.43669732
OE
OB 54.06132444 -38.37105356 H
OS 54.05392796 -38.37105356
OS 54.04560692 -38.37290268
OS 54.0345122 -38.3747518
OS 54.02249292 -38.37845004
OS 54.00954908 -38.38307284
OS 53.9975298 -38.39046932
OS 53.98551052 -38.40063948
OS 53.98458596 -38.40156404
OS 53.98088772 -38.40526228
OS 53.97626492 -38.4117342
OS 53.97164212 -38.42005524
OS 53.96609476 -38.4302254
OS 53.96147196 -38.44224468
OS 53.95777372 -38.45518852
OS 53.95684916 -38.46998148
OS 53.95684916 -38.47090604
OS 53.95684916 -38.4718306
OS 53.95777372 -38.47737796
OS 53.95869828 -38.485699
OS 53.9605474 -38.49586916
OS 53.96424564 -38.50788844
OS 53.96886844 -38.51990772
OS 53.97626492 -38.53285156
OS 53.98551052 -38.54394628
OS 53.98643508 -38.54487084
OS 53.99105788 -38.54856908
OS 53.9975298 -38.55319188
OS 54.00585084 -38.55781468
OS 54.01694556 -38.56336204
OS 54.0298894 -38.56798484
OS 54.04468236 -38.57168308
OS 54.06132444 -38.57260764
OS 54.06317356 -38.57260764
OS 54.06872092 -38.57168308
OS 54.07704196 -38.57075852
OS 54.08813668 -38.5689094
OS 54.10015596 -38.56521116
OS 54.11217524 -38.56058836
OS 54.12511908 -38.55319188
OS 54.1362138 -38.54394628
OS 54.13713836 -38.54302172
OS 54.1408366 -38.53839892
OS 54.1454594 -38.53285156
OS 54.15100676 -38.52453052
OS 54.15655412 -38.51436036
OS 54.16117692 -38.50234108
OS 54.16487516 -38.48847268
OS 54.16579972 -38.47367972
OS 54.16579972 -38.47275516
OS 54.16579972 -38.4718306
OS 54.16579972 -38.46628324
OS 54.1639506 -38.4579622
OS 54.16210148 -38.44779204
OS 54.15840324 -38.43669732
OS 54.15285588 -38.42467804
OS 54.1454594 -38.41265876
OS 54.13528924 -38.40063948
OS 54.13436468 -38.39971492
OS 54.12974188 -38.39601668
OS 54.12326996 -38.39139388
OS 54.11494892 -38.38584652
OS 54.1038542 -38.38029916
OS 54.09183492 -38.37567636
OS 54.07704196 -38.37197812
OS 54.06132444 -38.37105356
OE
OB 54.05855076 -38.63640228 H
OS 54.0530034 -38.63640228
OS 54.04930516 -38.63732684
OS 54.039135 -38.6382514
OS 54.02619116 -38.64102508
OS 54.0113982 -38.64564788
OS 53.99660524 -38.6521198
OS 53.98088772 -38.6613654
OS 53.96701932 -38.67338468
OS 53.9651702 -38.6752338
OS 53.96147196 -38.6798566
OS 53.9559246 -38.68817764
OS 53.94945268 -38.6983478
OS 53.9420562 -38.7122162
OS 53.93650884 -38.72793372
OS 53.9328106 -38.74550036
OS 53.93096148 -38.76491612
OS 53.93096148 -38.76676524
OS 53.93096148 -38.77046348
OS 53.93188604 -38.7769354
OS 53.9328106 -38.78525644
OS 53.93465972 -38.7954266
OS 53.9374334 -38.80652132
OS 53.94113164 -38.81761604
OS 53.94575444 -38.82963532
OS 53.946679 -38.83055988
OS 53.94852812 -38.83518268
OS 53.95222636 -38.84073004
OS 53.95777372 -38.84720196
OS 53.96424564 -38.855523
OS 53.97256668 -38.86384404
OS 53.98181228 -38.87124052
OS 53.992907 -38.878637
OS 53.99475612 -38.87956156
OS 53.99845436 -38.88141068
OS 54.00492628 -38.88418436
OS 54.01324732 -38.88695804
OS 54.02341748 -38.88973172
OS 54.03543676 -38.8925054
OS 54.0483806 -38.89435452
OS 54.06132444 -38.89527908
OS 54.0668718 -38.89527908
OS 54.07057004 -38.89435452
OS 54.08166476 -38.89342996
OS 54.0946086 -38.89065628
OS 54.10940156 -38.88603348
OS 54.12511908 -38.88048612
OS 54.13991204 -38.87124052
OS 54.154705 -38.85922124
OS 54.15655412 -38.85737212
OS 54.16025236 -38.85274932
OS 54.16672428 -38.84442828
OS 54.1731962 -38.83425812
OS 54.17966812 -38.82131428
OS 54.18614004 -38.80559676
OS 54.18983828 -38.78710556
OS 54.1916874 -38.7676898
OS 54.1916874 -38.76676524
OS 54.1916874 -38.76491612
OS 54.1916874 -38.76214244
OS 54.19076284 -38.7584442
OS 54.18983828 -38.74827404
OS 54.1870646 -38.73440564
OS 54.1824418 -38.72053724
OS 54.17596988 -38.70481972
OS 54.16672428 -38.6891022
OS 54.15378044 -38.67430924
OS 54.15193132 -38.67246012
OS 54.14730852 -38.66876188
OS 54.13898748 -38.66228996
OS 54.12789276 -38.65489348
OS 54.11402436 -38.64842156
OS 54.09738228 -38.64194964
OS 54.07889108 -38.6382514
OS 54.05855076 -38.63640228
OE
OB 54.80559524 -38.37105356 H
OS 54.80004788 -38.37105356
OS 54.79634964 -38.37197812
OS 54.78617948 -38.37382724
OS 54.7741602 -38.37660092
OS 54.7602918 -38.38214828
OS 54.74549884 -38.39046932
OS 54.73810236 -38.39601668
OS 54.73070588 -38.40156404
OS 54.72423396 -38.40896052
OS 54.71776204 -38.41728156
OS 54.71776204 -38.41820612
OS 54.71591292 -38.42005524
OS 54.7140638 -38.42375348
OS 54.71129012 -38.42837628
OS 54.70851644 -38.43577276
OS 54.7048182 -38.4440938
OS 54.70204452 -38.45426396
OS 54.69834628 -38.46628324
OS 54.69464804 -38.48015164
OS 54.6909498 -38.49586916
OS 54.68725156 -38.5134358
OS 54.68447788 -38.53285156
OS 54.6817042 -38.555041
OS 54.67985508 -38.57907956
OS 54.67893052 -38.60496724
OS 54.67800596 -38.6336286
OS 54.67800596 -38.63547772
OS 54.67800596 -38.64010052
OS 54.67800596 -38.64842156
OS 54.67893052 -38.65951628
OS 54.67893052 -38.67153556
OS 54.67985508 -38.68632852
OS 54.68077964 -38.70204604
OS 54.68262876 -38.71868812
OS 54.68725156 -38.75474596
OS 54.69002524 -38.7723126
OS 54.69372348 -38.78895468
OS 54.69742172 -38.8046722
OS 54.70296908 -38.81946516
OS 54.70851644 -38.832409
OS 54.71498836 -38.84350372
OS 54.71498836 -38.84442828
OS 54.71683748 -38.84535284
OS 54.72146028 -38.85182476
OS 54.72978132 -38.8601458
OS 54.73995148 -38.8693914
OS 54.75381988 -38.878637
OS 54.7695374 -38.88695804
OS 54.78710404 -38.89342996
OS 54.79634964 -38.89435452
OS 54.8065198 -38.89527908
OS 54.81206716 -38.89527908
OS 54.8157654 -38.89435452
OS 54.825011 -38.8925054
OS 54.83795484 -38.88880716
OS 54.85182324 -38.88233524
OS 54.86754076 -38.87308964
OS 54.87493724 -38.86754228
OS 54.88233372 -38.8601458
OS 54.8897302 -38.85274932
OS 54.89712668 -38.84350372
OS 54.89712668 -38.84257916
OS 54.8989758 -38.84073004
OS 54.90082492 -38.83795636
OS 54.90267404 -38.83333356
OS 54.90637228 -38.82686164
OS 54.90914596 -38.8185406
OS 54.9128442 -38.809295
OS 54.91654244 -38.79820028
OS 54.91931612 -38.78433188
OS 54.92301436 -38.76953892
OS 54.9267126 -38.75197228
OS 54.92948628 -38.73348108
OS 54.9313354 -38.71129164
OS 54.93318452 -38.68817764
OS 54.93503364 -38.66228996
OS 54.93503364 -38.6336286
OS 54.93503364 -38.63270404
OS 54.93503364 -38.63177948
OS 54.93503364 -38.62715668
OS 54.93503364 -38.61883564
OS 54.93410908 -38.60774092
OS 54.93410908 -38.59572164
OS 54.93318452 -38.58092868
OS 54.93225996 -38.56521116
OS 54.93041084 -38.54764452
OS 54.92578804 -38.51251124
OS 54.92301436 -38.4949446
OS 54.91931612 -38.47830252
OS 54.91561788 -38.462585
OS 54.91007052 -38.44779204
OS 54.90452316 -38.4348482
OS 54.89805124 -38.42375348
OS 54.89805124 -38.42282892
OS 54.89620212 -38.42190436
OS 54.894353 -38.41913068
OS 54.89157932 -38.41543244
OS 54.88325828 -38.4071114
OS 54.87308812 -38.39694124
OS 54.85921972 -38.38769564
OS 54.8435022 -38.3793746
OS 54.83518116 -38.37567636
OS 54.82593556 -38.37290268
OS 54.8157654 -38.37197812
OS 54.80559524 -38.37105356
OE
OB 51.07499564 -38.37105356 H
OS 51.06944828 -38.37105356
OS 51.06575004 -38.37197812
OS 51.05557988 -38.37382724
OS 51.0435606 -38.37660092
OS 51.0296922 -38.38214828
OS 51.01489924 -38.39046932
OS 51.00750276 -38.39601668
OS 51.00010628 -38.40156404
OS 50.99363436 -38.40896052
OS 50.98716244 -38.41728156
OS 50.98716244 -38.41820612
OS 50.98531332 -38.42005524
OS 50.9834642 -38.42375348
OS 50.98069052 -38.42837628
OS 50.97791684 -38.43577276
OS 50.9742186 -38.4440938
OS 50.97144492 -38.45426396
OS 50.96774668 -38.46628324
OS 50.96404844 -38.48015164
OS 50.9603502 -38.49586916
OS 50.95665196 -38.5134358
OS 50.95387828 -38.53285156
OS 50.9511046 -38.555041
OS 50.94925548 -38.57907956
OS 50.94833092 -38.60496724
OS 50.94740636 -38.6336286
OS 50.94740636 -38.63547772
OS 50.94740636 -38.64010052
OS 50.94740636 -38.64842156
OS 50.94833092 -38.65951628
OS 50.94833092 -38.67153556
OS 50.94925548 -38.68632852
OS 50.95018004 -38.70204604
OS 50.95202916 -38.71868812
OS 50.95665196 -38.75474596
OS 50.95942564 -38.7723126
OS 50.96312388 -38.78895468
OS 50.96682212 -38.8046722
OS 50.97236948 -38.81946516
OS 50.97791684 -38.832409
OS 50.98438876 -38.84350372
OS 50.98438876 -38.84442828
OS 50.98623788 -38.84535284
OS 50.99086068 -38.85182476
OS 50.99918172 -38.8601458
OS 51.00935188 -38.8693914
OS 51.02322028 -38.878637
OS 51.0389378 -38.88695804
OS 51.05650444 -38.89342996
OS 51.06575004 -38.89435452
OS 51.0759202 -38.89527908
OS 51.08146756 -38.89527908
OS 51.0851658 -38.89435452
OS 51.0944114 -38.8925054
OS 51.10735524 -38.88880716
OS 51.12122364 -38.88233524
OS 51.13694116 -38.87308964
OS 51.14433764 -38.86754228
OS 51.15173412 -38.8601458
OS 51.1591306 -38.85274932
OS 51.16652708 -38.84350372
OS 51.16652708 -38.84257916
OS 51.1683762 -38.84073004
OS 51.17022532 -38.83795636
OS 51.17207444 -38.83333356
OS 51.17577268 -38.82686164
OS 51.17854636 -38.8185406
OS 51.1822446 -38.809295
OS 51.18594284 -38.79820028
OS 51.18871652 -38.78433188
OS 51.19241476 -38.76953892
OS 51.196113 -38.75197228
OS 51.19888668 -38.73348108
OS 51.2007358 -38.71129164
OS 51.20258492 -38.68817764
OS 51.20443404 -38.66228996
OS 51.20443404 -38.6336286
OS 51.20443404 -38.63270404
OS 51.20443404 -38.63177948
OS 51.20443404 -38.62715668
OS 51.20443404 -38.61883564
OS 51.20350948 -38.60774092
OS 51.20350948 -38.59572164
OS 51.20258492 -38.58092868
OS 51.20166036 -38.56521116
OS 51.19981124 -38.54764452
OS 51.19518844 -38.51251124
OS 51.19241476 -38.4949446
OS 51.18871652 -38.47830252
OS 51.18501828 -38.462585
OS 51.17947092 -38.44779204
OS 51.17392356 -38.4348482
OS 51.16745164 -38.42375348
OS 51.16745164 -38.42282892
OS 51.16560252 -38.42190436
OS 51.1637534 -38.41913068
OS 51.16097972 -38.41543244
OS 51.15265868 -38.4071114
OS 51.14248852 -38.39694124
OS 51.12862012 -38.38769564
OS 51.1129026 -38.3793746
OS 51.10458156 -38.37567636
OS 51.09533596 -38.37290268
OS 51.0851658 -38.37197812
OS 51.07499564 -38.37105356
OE
SE
P -2.99999908 16.00000102 6 P 0 0 ;0=4,1=1
P -2.99999908 17.99999956 6 P 0 0 ;0=4,1=1
P -2.99999908 20.00000064 6 P 0 0 ;0=4,1=1
P -2.99999908 21.99999918 6 P 0 0 ;0=4,1=1
P -2.99999908 24.00000026 6 P 0 0 ;0=4,1=1
P -2.99999908 25.9999988 6 P 0 0 ;0=4,1=1
P -2.99999908 27.99999988 6 P 0 0 ;0=4,1=1
P -2.99999908 30.00000096 6 P 0 0 ;0=4,1=1
P -2.99999908 31.9999995 6 P 0 0 ;0=4,1=1
P -2.99999908 34.00000058 6 P 0 0 ;0=4,1=1
P -2.99999908 35.99999912 6 P 0 0 ;0=4,1=1
P -2.99999908 38.0000002 6 P 0 0 ;0=4,1=1
P -2.99999908 39.99999874 6 P 0 0 ;0=4,1=1
P 0.50000154 -3.99999962 6 P 0 0 ;0=4,1=1
P 2.50000008 -3.99999962 6 P 0 0 ;0=4,1=1
P 4.50000116 -3.99999962 6 P 0 0 ;0=4,1=1
P 6.4999997 -3.99999962 6 P 0 0 ;0=4,1=1
P 8.50000078 -3.99999962 6 P 0 0 ;0=4,1=1
P 10.49999932 -3.99999962 6 P 0 0 ;0=4,1=1
P 12.5000004 -3.99999962 6 P 0 0 ;0=4,1=1
P 12.74500118 40.26499948 6 P 0 0 ;0=4,1=1
P 12.74500118 41.21500012 6 P 0 0 ;0=4,1=1
P 12.74500118 44.63999962 6 P 0 0 ;0=4,1=1
P 12.75500116 42.16500076 6 P 0 0 ;0=4,1=1
P 12.98999942 18.0150008 6 P 0 0 ;0=4,1=1
P 14.50000148 -3.99999962 6 P 0 0 ;0=4,1=1
P 15.88470534 21.56499878 6 P 0 0 ;0=4,1=1
P 16.30970576 23.03999964 6 P 0 0 ;0=4,1=1
P 16.50000002 -3.99999962 6 P 0 0 ;0=4,1=1
P 17.57500168 13.89000016 6 P 0 0 ;0=4,1=1
P 17.915001 15.69625258 6 P 0 0 ;0=4,1=1
P 18.8149992 15.10000028 6 P 0 0 ;0=4,1=1
P 18.8149992 15.98270108 6 P 0 0 ;0=4,1=1
P 18.8149992 16.85250122 6 P 0 0 ;0=4,1=1
P 19.01500134 7.39000046 6 P 0 0 ;0=4,1=1
P 19.01500134 8.5900006 6 P 0 0 ;0=4,1=1
P 19.01500134 9.7899982 6 P 0 0 ;0=4,1=1
P 19.01500134 11.09000068 6 P 0 0 ;0=4,1=1
P 19.01500134 12.39000062 6 P 0 0 ;0=4,1=1
P 21.11499968 6.76500044 6 P 0 0 ;0=4,1=1
P 21.11499968 7.78999966 6 P 0 0 ;0=4,1=1
P 21.11499968 8.9899998 6 P 0 0 ;0=4,1=1
P 21.11499968 10.28999974 6 P 0 0 ;0=4,1=1
P 21.11499968 11.38590052 6 P 0 0 ;0=4,1=1
P 22.05919388 12.29000082 6 P 0 0 ;0=4,1=1
P 22.45970616 20.01499934 6 P 0 0 ;0=4,1=1
P 23.29999912 38.90000094 6 P 0 0 ;0=4,1=1
P 23.33999904 44.0138312 6 P 0 0 ;0=4,1=1
P 23.4097068 20.04000056 6 P 0 0 ;0=4,1=1
P 24.35970744 20.04000056 6 P 0 0 ;0=4,1=1
P 24.49999926 -3.50000062 6 P 0 0 ;0=4,1=1
P 25.7999992 38.90000094 6 P 0 0 ;0=4,1=1
P 26.50000034 -3.50000062 6 P 0 0 ;0=4,1=1
P 28.50000142 -3.50000062 6 P 0 0 ;0=4,1=1
P 30.49999996 -3.50000062 6 P 0 0 ;0=4,1=1
P 32.50000104 -3.50000062 6 P 0 0 ;0=4,1=1
P 32.80000044 38.90000094 6 P 0 0 ;0=4,1=1
P 35.30000052 44.0000009 6 P 0 0 ;0=4,1=1
P 38.4999992 -3.50000062 6 P 0 0 ;0=4,1=1
P 39.60000208 38.91499964 6 P 0 0 ;0=4,1=1
P 40.50000028 -3.50000062 6 P 0 0 ;0=4,1=1
P 40.67999992 42.76499956 6 P 0 0 ;0=4,1=1
P 42.2249981 38.91499964 6 P 0 0 ;0=4,1=1
P 44.4999999 0.499999 6 P 0 0 ;0=4,1=1
P 44.4999999 2.50000008 6 P 0 0 ;0=4,1=1
P 44.4999999 4.49999862 6 P 0 0 ;0=4,1=1
P 44.4999999 6.4999997 6 P 0 0 ;0=4,1=1
P 44.4999999 8.49999824 6 P 0 0 ;0=4,1=1
P 44.4999999 10.49999932 6 P 0 0 ;0=4,1=1
P 44.4999999 12.49999786 6 P 0 0 ;0=4,1=1
P 44.4999999 14.49999894 6 P 0 0 ;0=4,1=1
P 44.4999999 16.50000002 6 P 0 0 ;0=4,1=1
P 44.4999999 18.49999856 6 P 0 0 ;0=4,1=1
P 44.4999999 20.49999964 6 P 0 0 ;0=4,1=1
P 44.4999999 22.49999818 6 P 0 0 ;0=4,1=1
P 44.4999999 24.49999926 6 P 0 0 ;0=4,1=1
P 44.4999999 26.4999978 6 P 0 0 ;0=4,1=1
P 44.4999999 28.49999888 6 P 0 0 ;0=4,1=1
P 44.4999999 30.49999996 6 P 0 0 ;0=4,1=1
P 44.4999999 32.4999985 6 P 0 0 ;0=4,1=1
P 44.4999999 34.49999958 6 P 0 0 ;0=4,1=1
P 44.4999999 36.49999812 6 P 0 0 ;0=4,1=1
P 44.4999999 38.4999992 6 P 0 0 ;0=4,1=1
P 44.4999999 40.49999774 6 P 0 0 ;0=4,1=1

### steps/pcb/layers/l03-inner_layer/features
UNITS=MM
#Layer_Physical_Order=3
#Layer_Color=65280
#
#Feature symbol names
#
$0 r99.9998
$1 r2090.0009
$2 r1562.00094
$3 r1799.99894
$4 r599.9988

#
#Feature attribute names
#
@0 .geometry
@1 .pad_usage
@2 .nomenclature
@3 .string
@4 .string_angle

#
#Feature attribute text strings
#
&0 Pad_Simple_X2090.0009Y2090.0009H1090.0004C2106.0004
&1 Pad_Simple_X1562.0009Y1562.0009H961.9996C1977.9996
&2 Pad_Simple_X1799.9989Y1799.9989H1200.0001C2216.0001
&3 VIA_RoundD599.9988H299.9994C1315.9994

#
#Layer features
#
L -9.5600012 -24.45999934 40.4400004 -24.45999934 0 P 0
L -9.5600012 -35.9599992 -9.5600012 -24.45999934 0 P 0
L -9.5600012 -35.9599992 28.439999 -35.9599992 0 P 0
L -9.5600012 -39.45999982 -9.5600012 -35.9599992 0 P 0
L -9.5600012 -39.45999982 28.439999 -39.45999982 0 P 0
L -9.5600012 -42.96000044 -9.5600012 -39.45999982 0 P 0
L -9.5600012 -42.96000044 28.439999 -42.96000044 0 P 0
L -10.0600002 -23.96000034 62.93999858 -23.96000034 0 P 0
L -10.0600002 -43.45999944 -10.0600002 -23.96000034 0 P 0
L -10.0600002 -43.45999944 62.93999858 -43.45999944 0 P 0
L 28.439999 -35.96000174 45.44000056 -35.9599992 0 P 0
L 28.439999 -39.45999982 28.439999 -35.9599992 0 P 0
L 28.439999 -39.46000236 45.44000056 -39.45999982 0 P 0
L 28.439999 -42.96000044 28.439999 -39.45999982 0 P 0
L 28.439999 -42.96000298 45.44000056 -42.96000044 0 P 0
L 40.4400004 -24.45999934 62.43999958 -24.45999934 0 P 0
L 40.4400004 -35.9599992 40.4400004 -24.45999934 0 P 0
L 45.44000056 -35.9599992 62.43999958 -35.9599992 0 P 0
L 45.44000056 -39.45999982 62.43999958 -39.45999982 0 P 0
L 45.44000056 -42.96000044 45.44000056 -35.9599992 0 P 0
L 45.44000056 -42.96000044 62.43999958 -42.96000044 0 P 0
L 62.43999958 -35.9599992 62.43999958 -24.45999934 0 P 0
L 62.43999958 -42.96000044 62.43999958 -35.9599992 0 P 0
L 62.93999858 -43.45999944 62.93999858 -23.96000034 0 P 0
P 0 40.64 1 P 0 0 ;0=0,1=0
P 37.8500005 12.71999996 3 P 0 0 ;0=2,1=0
P 37.8500005 12.71999996 2 P 0 0 ;0=1,1=0
P 40.67999992 20.33999996 1 P 0 0 ;0=0,1=0
S P 0
OB 43.2467766 45.28782662 I
OS 43.5750081 45.19987658
OS 43.8889648 45.06983112
OS 44.18321872 44.89994068
OS 44.45280162 44.69308308
OS 44.693078 44.45280924
OS 44.89994068 44.18322126
OS 45.06983112 43.8889648
OS 45.19986896 43.57502842
OS 45.28782408 43.24677914
OS 45.33217502 42.90990402
OS 45.33217756 42.7399958
OS 45.33217502 -2.06000096
OS 45.33217502 -2.22990918
OS 45.28782662 -2.56677922
OS 45.19987658 -2.89501072
OS 45.06983112 -3.20896742
OS 44.89994068 -3.50322134
OS 44.69308308 -3.77280424
OS 44.45280924 -4.01308062
OS 44.18322126 -4.2199433
OS 43.8889648 -4.38983374
OS 43.57502842 -4.51987158
OS 43.24677914 -4.6078267
OS 42.90989132 -4.6521751
OS 42.7399958 -4.65217764
OS -2.06000096 -4.65218272
OS -2.22990918 -4.65218272
OS -2.56678938 -4.60783178
OS -2.89502088 -4.51988428
OS -3.20895472 -4.38984644
OS -3.50322388 -4.21994838
OS -3.77279916 -4.0130984
OS -4.0130984 -3.77279916
OS -4.21994584 -3.50322642
OS -4.38984136 -3.2089598
OS -4.51988174 -2.89502088
OS -4.60782924 -2.56679192
OS -4.65218018 -2.22991172
OS -4.65217764 -2.06000604
OS -4.65218526 42.73999834
OS -4.65218526 42.90990656
OS -4.60783432 43.24678422
OS -4.51988682 43.57501318
OS -4.38984644 43.88895464
OS -4.21995092 44.18321872
OS -4.01310094 44.452794
OS -3.77280932 44.69308562
OS -3.50323404 44.89993814
OS -3.20894964 45.06984128
OS -2.89502342 45.19987658
OS -2.56679192 45.28782408
OS -2.22992188 45.33217248
OS -2.07798416 45.33216486
OS -2.07795622 45.33216994
OS 42.74000088 45.33217502
OS 42.90990656 45.33217502
OS 43.2467766 45.28782662
OE
OB 14.42216826 44.87499788 H
OS 14.11783054 44.87499788
OS 13.8193399 44.81562538
OS 13.53816952 44.69915876
OS 13.28511948 44.53007858
OS 13.06992052 44.31487962
OS 12.90084034 44.06182958
OS 12.8147318 43.85394836
OS 12.677267 43.85394836
OS 12.59115846 44.06182958
OS 12.42207828 44.31487962
OS 12.20687932 44.53007858
OS 11.95382928 44.69915876
OS 11.6726589 44.81562538
OS 11.37416826 44.87499788
OS 11.06983054 44.87499788
OS 10.7713399 44.81562538
OS 10.49016952 44.69915876
OS 10.23711948 44.53007858
OS 10.02192052 44.31487962
OS 9.85284034 44.06182958
OS 9.73637372 43.7806592
OS 9.67700122 43.48216856
OS 9.67700122 43.17783084
OS 9.73637372 42.8793402
OS 9.85284034 42.59816982
OS 10.02192052 42.34511978
OS 10.23711948 42.12992082
OS 10.49016952 41.96084064
OS 10.7713399 41.84437402
OS 11.06983054 41.78500152
OS 11.37416826 41.78500152
OS 11.6726589 41.84437402
OS 11.95382928 41.96084064
OS 12.20687932 42.12992082
OS 12.42207828 42.34511978
OS 12.59115846 42.59816982
OS 12.677267 42.80605104
OS 12.8147318 42.80605104
OS 12.90084034 42.59816982
OS 13.06992052 42.34511978
OS 13.28511948 42.12992082
OS 13.53816952 41.96084064
OS 13.8193399 41.84437402
OS 14.11783054 41.78500152
OS 14.42216826 41.78500152
OS 14.7206589 41.84437402
OS 15.00182928 41.96084064
OS 15.25487932 42.12992082
OS 15.47007828 42.34511978
OS 15.63915846 42.59816982
OS 15.75562508 42.8793402
OS 15.81499758 43.17783084
OS 15.81499758 43.48216856
OS 15.75562508 43.7806592
OS 15.63915846 44.06182958
OS 15.47007828 44.31487962
OS 15.25487932 44.53007858
OS 15.00182928 44.69915876
OS 14.7206589 44.81562538
OS 14.42216826 44.87499788
OE
OB 8.3379056 44.57499848 H
OS 8.0100932 44.57499848
OS 7.69344664 44.49015486
OS 7.40955084 44.32624866
OS 7.17775044 44.09444826
OS 7.01384424 43.81055246
OS 6.92900062 43.4939059
OS 6.92900062 43.1660935
OS 7.01384424 42.84944694
OS 7.17775044 42.56555114
OS 7.40955084 42.33375074
OS 7.69344664 42.16984454
OS 8.0100932 42.08500092
OS 8.3379056 42.08500092
OS 8.65455216 42.16984454
OS 8.93844796 42.33375074
OS 9.17024836 42.56555114
OS 9.33415456 42.84944694
OS 9.41899818 43.1660935
OS 9.41899818 43.4939059
OS 9.33415456 43.81055246
OS 9.17024836 44.09444826
OS 8.93844796 44.32624866
OS 8.65455216 44.49015486
OS 8.3379056 44.57499848
OE
OB 5.2899056 44.57499848 H
OS 4.9620932 44.57499848
OS 4.64544664 44.49015486
OS 4.36155084 44.32624866
OS 4.12975044 44.09444826
OS 3.96584424 43.81055246
OS 3.88100062 43.4939059
OS 3.88100062 43.1660935
OS 3.96584424 42.84944694
OS 4.12975044 42.56555114
OS 4.36155084 42.33375074
OS 4.64544664 42.16984454
OS 4.9620932 42.08500092
OS 5.2899056 42.08500092
OS 5.60655216 42.16984454
OS 5.89044796 42.33375074
OS 6.12224836 42.56555114
OS 6.28615456 42.84944694
OS 6.37099818 43.1660935
OS 6.37099818 43.4939059
OS 6.28615456 43.81055246
OS 6.12224836 44.09444826
OS 5.89044796 44.32624866
OS 5.60655216 44.49015486
OS 5.2899056 44.57499848
OE
OB 2.2419056 44.57499848 H
OS 1.9140932 44.57499848
OS 1.59744664 44.49015486
OS 1.31355084 44.32624866
OS 1.08175044 44.09444826
OS 0.91784424 43.81055246
OS 0.83300062 43.4939059
OS 0.83300062 43.1660935
OS 0.91784424 42.84944694
OS 1.08175044 42.56555114
OS 1.31355084 42.33375074
OS 1.59744664 42.16984454
OS 1.9140932 42.08500092
OS 2.2419056 42.08500092
OS 2.55855216 42.16984454
OS 2.84244796 42.33375074
OS 3.07424836 42.56555114
OS 3.23815456 42.84944694
OS 3.32299818 43.1660935
OS 3.32299818 43.4939059
OS 3.23815456 43.81055246
OS 3.07424836 44.09444826
OS 2.84244796 44.32624866
OS 2.55855216 44.49015486
OS 2.2419056 44.57499848
OE
OB 0.17101566 41.93899918 H
OS 0.12699492 41.93899918
OS 0.12699492 40.76701016
OS 1.29899918 40.76701016
OS 1.29899918 40.81101566
OS 1.2104751 41.141396
OS 1.0394569 41.43760318
OS 0.79760318 41.6794569
OS 0.501396 41.8504751
OS 0.17101566 41.93899918
OE
OB -0.12700508 41.93899918 H
OS -0.17101566 41.93899918
OS -0.501396 41.8504751
OS -0.79760318 41.6794569
OS -1.0394569 41.43760318
OS -1.2104751 41.141396
OS -1.29899918 40.81101566
OS -1.29899918 40.76701016
OS -0.12700508 40.76701016
OS -0.12700508 41.93899918
OE
OB 1.29899918 40.51301016 H
OS 0.12699492 40.51301016
OS 0.12699492 39.34100082
OS 0.17101566 39.34100082
OS 0.501396 39.4295249
OS 0.79760318 39.6005431
OS 1.0394569 39.84239682
OS 1.2104751 40.138604
OS 1.29899918 40.46898434
OS 1.29899918 40.51301016
OE
OB -0.12700508 40.51301016 H
OS -1.29899918 40.51301016
OS -1.29899918 40.46898434
OS -1.2104751 40.138604
OS -1.0394569 39.84239682
OS -0.79760318 39.6005431
OS -0.501396 39.4295249
OS -0.17101566 39.34100082
OS -0.12700508 39.34100082
OS -0.12700508 40.51301016
OE
OB 20.46429994 44.98999892 H
OS 20.01570038 44.98999892
OS 19.57262278 44.9198238
OS 19.14597898 44.78119822
OS 18.74627442 44.57753848
OS 18.38334906 44.31385854
OS 18.06614116 43.99665064
OS 17.80246122 43.63372528
OS 17.59880148 43.23402072
OS 17.4601759 42.80737692
OS 17.39000078 42.36429932
OS 17.39000078 41.91569976
OS 17.4601759 41.47262216
OS 17.59880148 41.04597836
OS 17.80246122 40.6462738
OS 18.06614116 40.28334844
OS 18.38334906 39.96614054
OS 18.74627442 39.7024606
OS 19.14597898 39.49880086
OS 19.57262278 39.36017528
OS 20.01570038 39.29000016
OS 20.46429994 39.29000016
OS 20.90737754 39.36017528
OS 21.33402134 39.49880086
OS 21.7337259 39.7024606
OS 22.09665126 39.96614054
OS 22.41385916 40.28334844
OS 22.6775391 40.6462738
OS 22.88119884 41.04597836
OS 23.01982442 41.47262216
OS 23.08999954 41.91569976
OS 23.08999954 42.36429932
OS 23.01982442 42.80737692
OS 22.88119884 43.23402072
OS 22.6775391 43.63372528
OS 22.41385916 43.99665064
OS 22.09665126 44.31385854
OS 21.7337259 44.57753848
OS 21.33402134 44.78119822
OS 20.90737754 44.9198238
OS 20.46429994 44.98999892
OE
OB 40.79216886 42.18499818 H
OS 40.48783114 42.18499818
OS 40.1893405 42.12562568
OS 39.90817012 42.00915906
OS 39.65512008 41.84007888
OS 39.43992112 41.62487992
OS 39.27084094 41.37182988
OS 39.15437432 41.0906595
OS 39.09500182 40.79216886
OS 39.09500182 40.48783114
OS 39.15437432 40.1893405
OS 39.27084094 39.90817012
OS 39.43992112 39.65512008
OS 39.65512008 39.43992112
OS 39.90817012 39.27084094
OS 40.1893405 39.15437432
OS 40.48783114 39.09500182
OS 40.79216886 39.09500182
OS 41.0906595 39.15437432
OS 41.37182988 39.27084094
OS 41.62487992 39.43992112
OS 41.84007888 39.65512008
OS 42.00915906 39.90817012
OS 42.12562568 40.1893405
OS 42.18499818 40.48783114
OS 42.18499818 40.79216886
OS 42.12562568 41.0906595
OS 42.00915906 41.37182988
OS 41.84007888 41.62487992
OS 41.62487992 41.84007888
OS 41.37182988 42.00915906
OS 41.0906595 42.12562568
OS 40.79216886 42.18499818
OE
OB 36.4019084 42.14999952 H
OS 35.99809412 42.14999952
OS 35.60203954 42.07121888
OS 35.2289618 41.91668528
OS 34.89320428 41.69233978
OS 34.60766256 41.40679806
OS 34.38331706 41.07104054
OS 34.22878346 40.6979628
OS 34.15000282 40.30190822
OS 34.15000282 39.89809394
OS 34.22878346 39.50203936
OS 34.38331706 39.12896162
OS 34.60766256 38.7932041
OS 34.89320428 38.50766238
OS 35.2289618 38.28331688
OS 35.60203954 38.12878328
OS 35.99809412 38.05000264
OS 36.4019084 38.05000264
OS 36.79796298 38.12878328
OS 37.17104072 38.28331688
OS 37.50679824 38.50766238
OS 37.79233996 38.7932041
OS 38.01668546 39.12896162
OS 38.17121906 39.50203936
OS 38.2499997 39.89809394
OS 38.2499997 40.30190822
OS 38.17121906 40.6979628
OS 38.01668546 41.07104054
OS 37.79233996 41.40679806
OS 37.50679824 41.69233978
OS 37.17104072 41.91668528
OS 36.79796298 42.07121888
OS 36.4019084 42.14999952
OE
OB 4.60190596 40.64999744 H
OS 4.19809168 40.64999744
OS 3.8020371 40.5712168
OS 3.42895936 40.4166832
OS 3.09320184 40.1923377
OS 2.80766012 39.90679598
OS 2.58331462 39.57103846
OS 2.42878102 39.19796072
OS 2.35000038 38.80190614
OS 2.35000038 38.39809186
OS 2.42878102 38.00203728
OS 2.58331462 37.62895954
OS 2.80766012 37.29320202
OS 3.09320184 37.0076603
OS 3.42895936 36.7833148
OS 3.8020371 36.6287812
OS 4.19809168 36.55000056
OS 4.60190596 36.55000056
OS 4.99796054 36.6287812
OS 5.37103828 36.7833148
OS 5.7067958 37.0076603
OS 5.99233752 37.29320202
OS 6.21668302 37.62895954
OS 6.37121662 38.00203728
OS 6.44999726 38.39809186
OS 6.44999726 38.80190614
OS 6.37121662 39.19796072
OS 6.21668302 39.57103846
OS 5.99233752 39.90679598
OS 5.7067958 40.1923377
OS 5.37103828 40.4166832
OS 4.99796054 40.5712168
OS 4.60190596 40.64999744
OE
OB 4.9748186 34.13999776 H
OS 4.6851824 34.13999776
OS 4.40541664 34.06503474
OS 4.15458656 33.92021664
OS 3.94978382 33.7154139
OS 3.80496572 33.46458382
OS 3.7300027 33.18481806
OS 3.7300027 32.89518186
OS 3.80496572 32.6154161
OS 3.94978382 32.36458602
OS 4.15458656 32.15978328
OS 4.40541664 32.01496518
OS 4.6851824 31.94000216
OS 4.9748186 31.94000216
OS 5.25458436 32.01496518
OS 5.50541444 32.15978328
OS 5.71021718 32.36458602
OS 5.85503528 32.6154161
OS 5.9299983 32.89518186
OS 5.9299983 33.18481806
OS 5.85503528 33.46458382
OS 5.71021718 33.7154139
OS 5.50541444 33.92021664
OS 5.25458436 34.06503474
OS 4.9748186 34.13999776
OE
OB 38.03431306 34.43999716 H
OS 37.66568794 34.43999716
OS 37.30962312 34.34458968
OS 36.99038322 34.16027712
OS 36.72972334 33.89961724
OS 36.54541078 33.58037734
OS 36.4500033 33.22431252
OS 36.4500033 32.8556874
OS 36.54541078 32.49962258
OS 36.72972334 32.18038268
OS 36.99038322 31.9197228
OS 37.30962312 31.73541024
OS 37.66568794 31.64000276
OS 38.03431306 31.64000276
OS 38.39037788 31.73541024
OS 38.70961778 31.9197228
OS 38.97027766 32.18038268
OS 39.15459022 32.49962258
OS 39.2499977 32.8556874
OS 39.2499977 33.22431252
OS 39.15459022 33.58037734
OS 38.97027766 33.89961724
OS 38.70961778 34.16027712
OS 38.39037788 34.34458968
OS 38.03431306 34.43999716
OE
OB 38.03431306 24.27999716 H
OS 37.66568794 24.27999716
OS 37.30962312 24.18458968
OS 36.99038322 24.00027712
OS 36.72972334 23.73961724
OS 36.54541078 23.42037734
OS 36.4500033 23.06431252
OS 36.4500033 22.6956874
OS 36.54541078 22.33962258
OS 36.72972334 22.02038268
OS 36.99038322 21.7597228
OS 37.30962312 21.57541024
OS 37.66568794 21.48000276
OS 38.03431306 21.48000276
OS 38.39037788 21.57541024
OS 38.70961778 21.7597228
OS 38.97027766 22.02038268
OS 39.15459022 22.33962258
OS 39.2499977 22.6956874
OS 39.2499977 23.06431252
OS 39.15459022 23.42037734
OS 38.97027766 23.73961724
OS 38.70961778 24.00027712
OS 38.39037788 24.18458968
OS 38.03431306 24.27999716
OE
OB 40.85101558 21.63899914 H
OS 40.80699484 21.63899914
OS 40.80699484 20.46699996
OS 41.9789991 20.46699996
OS 41.9789991 20.51101562
OS 41.89047502 20.84139596
OS 41.71945682 21.13760314
OS 41.4776031 21.37945686
OS 41.18139592 21.55047506
OS 40.85101558 21.63899914
OE
OB 40.55299484 21.63899914 H
OS 40.50898426 21.63899914
OS 40.17860392 21.55047506
OS 39.88239674 21.37945686
OS 39.64054302 21.13760314
OS 39.46952482 20.84139596
OS 39.38100074 20.51101562
OS 39.38100074 20.46699996
OS 40.55299484 20.46699996
OS 40.55299484 21.63899914
OE
OB 41.9789991 20.21299996 H
OS 40.80699484 20.21299996
OS 40.80699484 19.04100078
OS 40.85101558 19.04100078
OS 41.18139592 19.12952486
OS 41.4776031 19.30054306
OS 41.71945682 19.54239678
OS 41.89047502 19.83860396
OS 41.9789991 20.1689843
OS 41.9789991 20.21299996
OE
OB 40.55299484 20.21299996 H
OS 39.38100074 20.21299996
OS 39.38100074 20.1689843
OS 39.46952482 19.83860396
OS 39.64054302 19.54239678
OS 39.88239674 19.30054306
OS 40.17860392 19.12952486
OS 40.50898426 19.04100078
OS 40.55299484 19.04100078
OS 40.55299484 20.21299996
OE
OB 4.9748186 18.89999776 H
OS 4.6851824 18.89999776
OS 4.40541664 18.82503474
OS 4.15458656 18.68021664
OS 3.94978382 18.4754139
OS 3.80496572 18.22458382
OS 3.7300027 17.94481806
OS 3.7300027 17.65518186
OS 3.80496572 17.3754161
OS 3.94978382 17.12458602
OS 4.15458656 16.91978328
OS 4.40541664 16.77496518
OS 4.6851824 16.70000216
OS 4.9748186 16.70000216
OS 5.25458436 16.77496518
OS 5.50541444 16.91978328
OS 5.71021718 17.12458602
OS 5.85503528 17.3754161
OS 5.9299983 17.65518186
OS 5.9299983 17.94481806
OS 5.85503528 18.22458382
OS 5.71021718 18.4754139
OS 5.50541444 18.68021664
OS 5.25458436 18.82503474
OS 4.9748186 18.89999776
OE
OB 38.03431306 19.19999716 H
OS 37.66568794 19.19999716
OS 37.30962312 19.10458968
OS 36.99038322 18.92027712
OS 36.72972334 18.65961724
OS 36.54541078 18.34037734
OS 36.4500033 17.98431252
OS 36.4500033 17.6156874
OS 36.54541078 17.25962258
OS 36.72972334 16.94038268
OS 36.99038322 16.6797228
OS 37.30962312 16.49541024
OS 37.66568794 16.40000276
OS 38.03431306 16.40000276
OS 38.39037788 16.49541024
OS 38.70961778 16.6797228
OS 38.97027766 16.94038268
OS 39.15459022 17.25962258
OS 39.2499977 17.6156874
OS 39.2499977 17.98431252
OS 39.15459022 18.34037734
OS 38.97027766 18.65961724
OS 38.70961778 18.92027712
OS 38.39037788 19.10458968
OS 38.03431306 19.19999716
OE
OB 38.00192806 13.87399816 H
OS 37.97699034 13.87399816
OS 37.97699034 12.8469898
OS 39.0039987 12.8469898
OS 39.0039987 12.87192752
OS 38.92535522 13.16542706
OS 38.77342766 13.42857106
OS 38.5585716 13.64342712
OS 38.2954276 13.79535468
OS 38.00192806 13.87399816
OE
OB 37.72299034 13.87399816 H
OS 37.69807294 13.87399816
OS 37.4045734 13.79535468
OS 37.1414294 13.64342712
OS 36.92657334 13.42857106
OS 36.77464578 13.16542706
OS 36.6960023 12.87192752
OS 36.6960023 12.8469898
OS 37.72299034 12.8469898
OS 37.72299034 13.87399816
OE
OB 4.9748186 13.81999776 H
OS 4.6851824 13.81999776
OS 4.40541664 13.74503474
OS 4.15458656 13.60021664
OS 3.94978382 13.3954139
OS 3.80496572 13.14458382
OS 3.7300027 12.86481806
OS 3.7300027 12.57518186
OS 3.80496572 12.2954161
OS 3.94978382 12.04458602
OS 4.15458656 11.83978328
OS 4.40541664 11.69496518
OS 4.6851824 11.62000216
OS 4.9748186 11.62000216
OS 5.25458436 11.69496518
OS 5.50541444 11.83978328
OS 5.71021718 12.04458602
OS 5.85503528 12.2954161
OS 5.9299983 12.57518186
OS 5.9299983 12.86481806
OS 5.85503528 13.14458382
OS 5.71021718 13.3954139
OS 5.50541444 13.60021664
OS 5.25458436 13.74503474
OS 4.9748186 13.81999776
OE
OB 39.0039987 12.5929898 H
OS 37.97699034 12.5929898
OS 37.97699034 11.56600176
OS 38.00192806 11.56600176
OS 38.2954276 11.64464524
OS 38.5585716 11.7965728
OS 38.77342766 12.01142886
OS 38.92535522 12.27457286
OS 39.0039987 12.5680724
OS 39.0039987 12.5929898
OE
OB 37.72299034 12.5929898 H
OS 36.6960023 12.5929898
OS 36.6960023 12.5680724
OS 36.77464578 12.27457286
OS 36.92657334 12.01142886
OS 37.1414294 11.7965728
OS 37.4045734 11.64464524
OS 37.69807294 11.56600176
OS 37.72299034 11.56600176
OS 37.72299034 12.5929898
OE
OB 37.9948186 8.73999776 H
OS 37.7051824 8.73999776
OS 37.42541664 8.66503474
OS 37.17458656 8.52021664
OS 36.96978382 8.3154139
OS 36.82496572 8.06458382
OS 36.7500027 7.78481806
OS 36.7500027 7.49518186
OS 36.82496572 7.2154161
OS 36.96978382 6.96458602
OS 37.17458656 6.75978328
OS 37.42541664 6.61496518
OS 37.7051824 6.54000216
OS 37.9948186 6.54000216
OS 38.27458436 6.61496518
OS 38.52541444 6.75978328
OS 38.73021718 6.96458602
OS 38.87503528 7.2154161
OS 38.9499983 7.49518186
OS 38.9499983 7.78481806
OS 38.87503528 8.06458382
OS 38.73021718 8.3154139
OS 38.52541444 8.52021664
OS 38.27458436 8.66503474
OS 37.9948186 8.73999776
OE
OB 4.9748186 8.73999776 H
OS 4.6851824 8.73999776
OS 4.40541664 8.66503474
OS 4.15458656 8.52021664
OS 3.94978382 8.3154139
OS 3.80496572 8.06458382
OS 3.7300027 7.78481806
OS 3.7300027 7.49518186
OS 3.80496572 7.2154161
OS 3.94978382 6.96458602
OS 4.15458656 6.75978328
OS 4.40541664 6.61496518
OS 4.6851824 6.54000216
OS 4.9748186 6.54000216
OS 5.25458436 6.61496518
OS 5.50541444 6.75978328
OS 5.71021718 6.96458602
OS 5.85503528 7.2154161
OS 5.9299983 7.49518186
OS 5.9299983 7.78481806
OS 5.85503528 8.06458382
OS 5.71021718 8.3154139
OS 5.50541444 8.52021664
OS 5.25458436 8.66503474
OS 4.9748186 8.73999776
OE
OB 4.60190596 4.04999952 H
OS 4.19809168 4.04999952
OS 3.8020371 3.97121888
OS 3.42895936 3.81668528
OS 3.09320184 3.59233978
OS 2.80766012 3.30679806
OS 2.58331462 2.97104054
OS 2.42878102 2.5979628
OS 2.35000038 2.20190822
OS 2.35000038 1.79809394
OS 2.42878102 1.40203936
OS 2.58331462 1.02896162
OS 2.80766012 0.6932041
OS 3.09320184 0.40766238
OS 3.42895936 0.18331688
OS 3.8020371 0.02878328
OS 4.19809168 -0.04999736
OS 4.60190596 -0.04999736
OS 4.99796054 0.02878328
OS 5.37103828 0.18331688
OS 5.7067958 0.40766238
OS 5.99233752 0.6932041
OS 6.21668302 1.02896162
OS 6.37121662 1.40203936
OS 6.44999726 1.79809394
OS 6.44999726 2.20190822
OS 6.37121662 2.5979628
OS 6.21668302 2.97104054
OS 5.99233752 3.30679806
OS 5.7067958 3.59233978
OS 5.37103828 3.81668528
OS 4.99796054 3.97121888
OS 4.60190596 4.04999952
OE
OB 40.8039062 1.24499878 H
OS 40.4760938 1.24499878
OS 40.15944724 1.16015516
OS 39.87555144 0.99624896
OS 39.64375104 0.76444856
OS 39.47984484 0.48055276
OS 39.39500122 0.1639062
OS 39.39500122 -0.1639062
OS 39.47984484 -0.48055276
OS 39.64375104 -0.76444856
OS 39.87555144 -0.99624896
OS 40.15944724 -1.16015516
OS 40.4760938 -1.24499878
OS 40.8039062 -1.24499878
OS 41.12055276 -1.16015516
OS 41.40444856 -0.99624896
OS 41.63624896 -0.76444856
OS 41.80015516 -0.48055276
OS 41.88499878 -0.1639062
OS 41.88499878 0.1639062
OS 41.80015516 0.48055276
OS 41.63624896 0.76444856
OS 41.40444856 0.99624896
OS 41.12055276 1.16015516
OS 40.8039062 1.24499878
OE
OB 0.1639062 1.24499878 H
OS -0.1639062 1.24499878
OS -0.48055276 1.16015516
OS -0.76444856 0.99624896
OS -0.99624896 0.76444856
OS -1.16015516 0.48055276
OS -1.24499878 0.1639062
OS -1.24499878 -0.1639062
OS -1.16015516 -0.48055276
OS -0.99624896 -0.76444856
OS -0.76444856 -0.99624896
OS -0.48055276 -1.16015516
OS -0.1639062 -1.24499878
OS 0.1639062 -1.24499878
OS 0.48055276 -1.16015516
OS 0.76444856 -0.99624896
OS 0.99624896 -0.76444856
OS 1.16015516 -0.48055276
OS 1.24499878 -0.1639062
OS 1.24499878 0.1639062
OS 1.16015516 0.48055276
OS 0.99624896 0.76444856
OS 0.76444856 0.99624896
OS 0.48055276 1.16015516
OS 0.1639062 1.24499878
OE
OB 35.70190726 1.0499979 H
OS 35.29809298 1.0499979
OS 34.9020384 0.97121726
OS 34.52896066 0.81668366
OS 34.19320314 0.59233816
OS 33.90766142 0.30679644
OS 33.68331592 -0.02896108
OS 33.52878232 -0.40203882
OS 33.45000168 -0.7980934
OS 33.45000168 -1.20190768
OS 33.52878232 -1.59796226
OS 33.68331592 -1.97104
OS 33.90766142 -2.30679752
OS 34.19320314 -2.59233924
OS 34.52896066 -2.81668474
OS 34.9020384 -2.97121834
OS 35.29809298 -3.04999898
OS 35.70190726 -3.04999898
OS 36.09796184 -2.97121834
OS 36.47103958 -2.81668474
OS 36.8067971 -2.59233924
OS 37.09233882 -2.30679752
OS 37.31668432 -1.97104
OS 37.47121792 -1.59796226
OS 37.54999856 -1.20190768
OS 37.54999856 -0.7980934
OS 37.47121792 -0.40203882
OS 37.31668432 -0.02896108
OS 37.09233882 0.30679644
OS 36.8067971 0.59233816
OS 36.47103958 0.81668366
OS 36.09796184 0.97121726
OS 35.70190726 1.0499979
OE
OB 20.66429954 1.58999936 H
OS 20.21569998 1.58999936
OS 19.77262238 1.51982424
OS 19.34597858 1.38119866
OS 18.94627402 1.17753892
OS 18.58334866 0.91385898
OS 18.26614076 0.59665108
OS 18.00246082 0.23372572
OS 17.79880108 -0.16597884
OS 17.6601755 -0.59262264
OS 17.59000038 -1.03570024
OS 17.59000038 -1.4842998
OS 17.6601755 -1.9273774
OS 17.79880108 -2.3540212
OS 18.00246082 -2.75372576
OS 18.26614076 -3.11665112
OS 18.58334866 -3.43385902
OS 18.94627402 -3.69753896
OS 19.34597858 -3.9011987
OS 19.77262238 -4.03982428
OS 20.21569998 -4.1099994
OS 20.66429954 -4.1099994
OS 21.10737714 -4.03982428
OS 21.53402094 -3.9011987
OS 21.9337255 -3.69753896
OS 22.29665086 -3.43385902
OS 22.61385876 -3.11665112
OS 22.8775387 -2.75372576
OS 23.08119844 -2.3540212
OS 23.21982402 -1.9273774
OS 23.28999914 -1.4842998
OS 23.28999914 -1.03570024
OS 23.21982402 -0.59262264
OS 23.08119844 -0.16597884
OS 22.8775387 0.23372572
OS 22.61385876 0.59665108
OS 22.29665086 0.91385898
OS 21.9337255 1.17753892
OS 21.53402094 1.38119866
OS 21.10737714 1.51982424
OS 20.66429954 1.58999936
OE
SE
S P 0
OB -2.97936666 -38.48662356 I
OS -2.97197018 -38.48754812
OS -2.96272458 -38.48939724
OS -2.95255442 -38.49124636
OS -2.94053514 -38.49402004
OS -2.92944042 -38.49679372
OS -2.91649658 -38.50141652
OS -2.9044773 -38.50603932
OS -2.89153346 -38.51251124
OS -2.87858962 -38.51990772
OS -2.86564578 -38.52822876
OS -2.8536265 -38.53839892
OS -2.84253178 -38.54949364
OS -2.84160722 -38.5504182
OS -2.8397581 -38.55226732
OS -2.83698442 -38.55596556
OS -2.83328618 -38.56151292
OS -2.82866338 -38.56798484
OS -2.82404058 -38.57538132
OS -2.81849322 -38.58462692
OS -2.81294586 -38.59572164
OS -2.8073985 -38.60774092
OS -2.80185114 -38.62068476
OS -2.79722834 -38.63547772
OS -2.79260554 -38.65119524
OS -2.7889073 -38.66876188
OS -2.78613362 -38.68725308
OS -2.7842845 -38.70666884
OS -2.78335994 -38.72793372
OS -2.78335994 -38.72885828
OS -2.78335994 -38.73255652
OS -2.78335994 -38.73902844
OS -2.7842845 -38.74827404
OS -3.1309945 -38.74827404
OS -3.1309945 -38.7491986
OS -3.1309945 -38.75197228
OS -3.13006994 -38.75567052
OS -3.13006994 -38.76121788
OS -3.12914538 -38.7676898
OS -3.12729626 -38.77508628
OS -3.12452258 -38.79172836
OS -3.11897522 -38.81021956
OS -3.11157874 -38.83055988
OS -3.10140858 -38.84905108
OS -3.08846474 -38.86569316
OS -3.08754018 -38.86569316
OS -3.08661562 -38.86754228
OS -3.08106826 -38.87216508
OS -3.07274722 -38.878637
OS -3.0616525 -38.88510892
OS -3.04685954 -38.8925054
OS -3.03021746 -38.89897732
OS -3.01172626 -38.90360012
OS -3.0015561 -38.90452468
OS -2.99046138 -38.90544924
OS -2.9830649 -38.90544924
OS -2.97474386 -38.90452468
OS -2.9645737 -38.90267556
OS -2.95347898 -38.89990188
OS -2.94053514 -38.89620364
OS -2.92851586 -38.89065628
OS -2.91649658 -38.8832598
OS -2.91557202 -38.88233524
OS -2.91094922 -38.878637
OS -2.90540186 -38.87308964
OS -2.89892994 -38.86569316
OS -2.89153346 -38.855523
OS -2.88321242 -38.84257916
OS -2.87489138 -38.8277862
OS -2.8674949 -38.81021956
OS -2.78613362 -38.82038972
OS -2.78613362 -38.82131428
OS -2.78705818 -38.8231634
OS -2.78798274 -38.82686164
OS -2.78983186 -38.832409
OS -2.79260554 -38.83795636
OS -2.79537922 -38.84535284
OS -2.8027757 -38.86107036
OS -2.8120213 -38.878637
OS -2.82496514 -38.8971282
OS -2.8397581 -38.91469484
OS -2.8582493 -38.93133692
OS -2.85917386 -38.93133692
OS -2.86102298 -38.93318604
OS -2.86379666 -38.93503516
OS -2.8674949 -38.93780884
OS -2.87304226 -38.94058252
OS -2.87858962 -38.9433562
OS -2.8859861 -38.94705444
OS -2.89430714 -38.95075268
OS -2.90355274 -38.95445092
OS -2.91279834 -38.95814916
OS -2.93591234 -38.96369652
OS -2.96180002 -38.96831932
OS -2.99046138 -38.97016844
OS -3.00063154 -38.97016844
OS -3.00710346 -38.96924388
OS -3.0154245 -38.96831932
OS -3.02559466 -38.9664702
OS -3.03668938 -38.96462108
OS -3.04870866 -38.96277196
OS -3.07459634 -38.95537548
OS -3.08846474 -38.94982812
OS -3.10140858 -38.94428076
OS -3.11527698 -38.93688428
OS -3.12822082 -38.92856324
OS -3.1402401 -38.91931764
OS -3.15225938 -38.90822292
OS -3.15318394 -38.90729836
OS -3.15503306 -38.90544924
OS -3.15780674 -38.901751
OS -3.16150498 -38.89620364
OS -3.16612778 -38.88973172
OS -3.17075058 -38.88233524
OS -3.17629794 -38.87308964
OS -3.1818453 -38.86291948
OS -3.18739266 -38.8509002
OS -3.19294002 -38.83795636
OS -3.19756282 -38.8231634
OS -3.20218562 -38.80744588
OS -3.20588386 -38.7908038
OS -3.20865754 -38.7723126
OS -3.21050666 -38.75289684
OS -3.21143122 -38.73255652
OS -3.21143122 -38.73163196
OS -3.21143122 -38.72700916
OS -3.21143122 -38.7214618
OS -3.21050666 -38.71314076
OS -3.2095821 -38.7029706
OS -3.20865754 -38.69187588
OS -3.20680842 -38.67893204
OS -3.20403474 -38.6659882
OS -3.19663826 -38.63640228
OS -3.19201546 -38.62160932
OS -3.1864681 -38.6058918
OS -3.17907162 -38.59109884
OS -3.17075058 -38.57723044
OS -3.16150498 -38.56336204
OS -3.15133482 -38.5504182
OS -3.15041026 -38.54949364
OS -3.14856114 -38.54764452
OS -3.1448629 -38.54487084
OS -3.1402401 -38.54024804
OS -3.13469274 -38.53562524
OS -3.12729626 -38.53007788
OS -3.11897522 -38.52360596
OS -3.10880506 -38.5180586
OS -3.0986349 -38.51158668
OS -3.08661562 -38.50603932
OS -3.07367178 -38.50049196
OS -3.05980338 -38.49586916
OS -3.04501042 -38.49124636
OS -3.0292929 -38.48847268
OS -3.01265082 -38.48662356
OS -2.99508418 -38.485699
OS -2.98583858 -38.485699
OS -2.97936666 -38.48662356
OE
OB -2.5022937 -38.48662356 I
OS -2.49212354 -38.48847268
OS -2.48010426 -38.49217092
OS -2.46716042 -38.49679372
OS -2.45236746 -38.50326564
OS -2.43664994 -38.51158668
OS -2.4653113 -38.58370236
OS -2.46623586 -38.5827778
OS -2.4699341 -38.58092868
OS -2.47548146 -38.578155
OS -2.48287794 -38.57538132
OS -2.49119898 -38.57260764
OS -2.50136914 -38.56983396
OS -2.5115393 -38.56798484
OS -2.52170946 -38.56706028
OS -2.52633226 -38.56706028
OS -2.53095506 -38.56798484
OS -2.53742698 -38.5689094
OS -2.5438989 -38.57075852
OS -2.55221994 -38.5735322
OS -2.56054098 -38.57723044
OS -2.56793746 -38.5827778
OS -2.56886202 -38.58370236
OS -2.5716357 -38.58555148
OS -2.57440938 -38.58924972
OS -2.57903218 -38.59387252
OS -2.58365498 -38.60034444
OS -2.58827778 -38.60774092
OS -2.59290058 -38.61606196
OS -2.59659882 -38.62623212
OS -2.59752338 -38.62808124
OS -2.59844794 -38.6336286
OS -2.60029706 -38.64194964
OS -2.60307074 -38.65304436
OS -2.60584442 -38.66691276
OS -2.60769354 -38.68263028
OS -2.6086181 -38.69927236
OS -2.60954266 -38.71776356
OS -2.60954266 -38.95999828
OS -2.68813026 -38.95999828
OS -2.68813026 -38.49586916
OS -2.61693914 -38.49586916
OS -2.61693914 -38.56613572
OS -2.61601458 -38.56521116
OS -2.61231634 -38.55873924
OS -2.60769354 -38.5504182
OS -2.60029706 -38.54024804
OS -2.59290058 -38.53007788
OS -2.58457954 -38.51898316
OS -2.5762585 -38.50973756
OS -2.56793746 -38.50234108
OS -2.5670129 -38.50141652
OS -2.56423922 -38.4995674
OS -2.55869186 -38.49679372
OS -2.5531445 -38.49402004
OS -2.54574802 -38.49124636
OS -2.53650242 -38.48847268
OS -2.52725682 -38.48662356
OS -2.51708666 -38.485699
OS -2.51061474 -38.485699
OS -2.5022937 -38.48662356
OE
OB -3.4499677 -38.48662356 I
OS -3.43979754 -38.48754812
OS -3.42777826 -38.48939724
OS -3.41483442 -38.49217092
OS -3.40096602 -38.49586916
OS -3.38802218 -38.50141652
OS -3.38617306 -38.50234108
OS -3.38247482 -38.5041902
OS -3.3760029 -38.50696388
OS -3.36860642 -38.51158668
OS -3.35936082 -38.51713404
OS -3.35103978 -38.52453052
OS -3.34271874 -38.531927
OS -3.33532226 -38.5411726
OS -3.3343977 -38.54209716
OS -3.33254858 -38.5457954
OS -3.3297749 -38.5504182
OS -3.3251521 -38.55689012
OS -3.32145386 -38.56613572
OS -3.31775562 -38.57538132
OS -3.31313282 -38.58647604
OS -3.31035914 -38.59849532
OS -3.31035914 -38.59941988
OS -3.30943458 -38.60311812
OS -3.30851002 -38.60866548
OS -3.30758546 -38.61606196
OS -3.30758546 -38.62715668
OS -3.3066609 -38.64010052
OS -3.30573634 -38.65581804
OS -3.30573634 -38.6752338
OS -3.30573634 -38.95999828
OS -3.38432394 -38.95999828
OS -3.38432394 -38.67893204
OS -3.38432394 -38.67800748
OS -3.38432394 -38.67708292
OS -3.38432394 -38.670611
OS -3.38432394 -38.66228996
OS -3.3852485 -38.6521198
OS -3.38617306 -38.64010052
OS -3.38802218 -38.62808124
OS -3.39079586 -38.61698652
OS -3.39356954 -38.60681636
OS -3.39356954 -38.6058918
OS -3.39541866 -38.60311812
OS -3.39819234 -38.59849532
OS -3.40096602 -38.59294796
OS -3.40558882 -38.5874006
OS -3.41113618 -38.58092868
OS -3.41853266 -38.57445676
OS -3.4268537 -38.5689094
OS -3.42777826 -38.56798484
OS -3.43055194 -38.56613572
OS -3.4360993 -38.5642866
OS -3.44257122 -38.56151292
OS -3.4499677 -38.55873924
OS -3.4592133 -38.55596556
OS -3.47030802 -38.555041
OS -3.48140274 -38.55411644
OS -3.48602554 -38.55411644
OS -3.48972378 -38.555041
OS -3.49896938 -38.55596556
OS -3.51098866 -38.55781468
OS -3.5239325 -38.56243748
OS -3.53872546 -38.56798484
OS -3.55351842 -38.57538132
OS -3.56738682 -38.58647604
OS -3.56923594 -38.58832516
OS -3.57293418 -38.59294796
OS -3.57570786 -38.5966462
OS -3.57848154 -38.601269
OS -3.58217978 -38.60681636
OS -3.58495346 -38.61328828
OS -3.5886517 -38.62068476
OS -3.59234994 -38.62993036
OS -3.59512362 -38.64010052
OS -3.5978973 -38.65119524
OS -3.59974642 -38.66321452
OS -3.60159554 -38.67615836
OS -3.60344466 -38.69187588
OS -3.60344466 -38.7075934
OS -3.60344466 -38.95999828
OS -3.68203226 -38.95999828
OS -3.68203226 -38.49586916
OS -3.6117657 -38.49586916
OS -3.6117657 -38.56243748
OS -3.61084114 -38.56151292
OS -3.60899202 -38.55873924
OS -3.60621834 -38.555041
OS -3.6025201 -38.5504182
OS -3.59697274 -38.54487084
OS -3.59050082 -38.53839892
OS -3.58310434 -38.53100244
OS -3.57385874 -38.52360596
OS -3.56461314 -38.51713404
OS -3.55351842 -38.50973756
OS -3.54149914 -38.50326564
OS -3.5285553 -38.49771828
OS -3.51376234 -38.49309548
OS -3.49896938 -38.48939724
OS -3.4823273 -38.48662356
OS -3.46476066 -38.485699
OS -3.45736418 -38.485699
OS -3.4499677 -38.48662356
OE
OB -0.0660781 -38.48662356 I
OS -0.05590794 -38.48847268
OS -0.04388866 -38.49217092
OS -0.03094482 -38.49679372
OS -0.01615186 -38.50326564
OS -0.00043434 -38.51158668
OS -0.0290957 -38.58370236
OS -0.03002026 -38.5827778
OS -0.0337185 -38.58092868
OS -0.03926586 -38.578155
OS -0.04666234 -38.57538132
OS -0.05498338 -38.57260764
OS -0.06515354 -38.56983396
OS -0.0753237 -38.56798484
OS -0.08549386 -38.56706028
OS -0.09011666 -38.56706028
OS -0.09473946 -38.56798484
OS -0.10121138 -38.5689094
OS -0.1076833 -38.57075852
OS -0.11600434 -38.5735322
OS -0.12432538 -38.57723044
OS -0.13172186 -38.5827778
OS -0.13264642 -38.58370236
OS -0.1354201 -38.58555148
OS -0.13819378 -38.58924972
OS -0.14281658 -38.59387252
OS -0.14743938 -38.60034444
OS -0.15206218 -38.60774092
OS -0.15668498 -38.61606196
OS -0.16038322 -38.62623212
OS -0.16130778 -38.62808124
OS -0.16223234 -38.6336286
OS -0.16408146 -38.64194964
OS -0.16685514 -38.65304436
OS -0.16962882 -38.66691276
OS -0.17147794 -38.68263028
OS -0.1724025 -38.69927236
OS -0.17332706 -38.71776356
OS -0.17332706 -38.95999828
OS -0.25191466 -38.95999828
OS -0.25191466 -38.49586916
OS -0.18072354 -38.49586916
OS -0.18072354 -38.56613572
OS -0.17979898 -38.56521116
OS -0.17610074 -38.55873924
OS -0.17147794 -38.5504182
OS -0.16408146 -38.54024804
OS -0.15668498 -38.53007788
OS -0.14836394 -38.51898316
OS -0.1400429 -38.50973756
OS -0.13172186 -38.50234108
OS -0.1307973 -38.50141652
OS -0.12802362 -38.4995674
OS -0.12247626 -38.49679372
OS -0.1169289 -38.49402004
OS -0.10953242 -38.49124636
OS -0.10028682 -38.48847268
OS -0.09104122 -38.48662356
OS -0.08087106 -38.485699
OS -0.07439914 -38.485699
OS -0.0660781 -38.48662356
OE
OB -1.94201034 -39.1375138 I
OS -2.46253762 -39.1375138
OS -2.46253762 -39.08111564
OS -1.94201034 -39.08111564
OS -1.94201034 -39.1375138
OE
OB -1.81534562 -38.95999828 I
OS -1.89393322 -38.95999828
OS -1.89393322 -38.32020276
OS -1.81534562 -38.32020276
OS -1.81534562 -38.95999828
OE
OB -0.99248722 -38.96739476 I
OS -0.99248722 -38.96831932
OS -0.99341178 -38.971093
OS -0.9952609 -38.97479124
OS -0.99711002 -38.97941404
OS -0.9998837 -38.98588596
OS -1.00265738 -38.99328244
OS -1.0091293 -39.00899996
OS -1.01560122 -39.0265666
OS -1.0229977 -39.04413324
OS -1.03039418 -39.05985076
OS -1.03409242 -39.06632268
OS -1.0368661 -39.0727946
OS -1.03779066 -39.07464372
OS -1.04056434 -39.07926652
OS -1.04518714 -39.08573844
OS -1.0507345 -39.09405948
OS -1.05813098 -39.10330508
OS -1.06645202 -39.11255068
OS -1.07477306 -39.12179628
OS -1.08494322 -39.12919276
OS -1.08586778 -39.13011732
OS -1.08956602 -39.13196644
OS -1.09511338 -39.13474012
OS -1.10343442 -39.13843836
OS -1.11268002 -39.1421366
OS -1.12377474 -39.14491028
OS -1.13579402 -39.1467594
OS -1.14966242 -39.14768396
OS -1.15336066 -39.14768396
OS -1.15798346 -39.1467594
OS -1.16445538 -39.1467594
OS -1.17185186 -39.14491028
OS -1.1801729 -39.14306116
OS -1.1894185 -39.14121204
OS -1.19958866 -39.1375138
OS -1.2079097 -39.06447356
OS -1.20698514 -39.06447356
OS -1.2032869 -39.06539812
OS -1.1986641 -39.06632268
OS -1.19311674 -39.0681718
OS -1.17832378 -39.07094548
OS -1.16353082 -39.07187004
OS -1.15890802 -39.07187004
OS -1.15428522 -39.07094548
OS -1.14873786 -39.07094548
OS -1.13486946 -39.0681718
OS -1.12839754 -39.06539812
OS -1.12192562 -39.06262444
OS -1.12100106 -39.06262444
OS -1.11915194 -39.06077532
OS -1.11637826 -39.0589262
OS -1.11268002 -39.05615252
OS -1.10435898 -39.04875604
OS -1.0969625 -39.03858588
OS -1.0969625 -39.03766132
OS -1.09511338 -39.0358122
OS -1.09326426 -39.03211396
OS -1.09141514 -39.0265666
OS -1.0877169 -39.01917012
OS -1.08401866 -39.0080754
OS -1.0784713 -38.99513156
OS -1.07292394 -38.97941404
OS -1.07292394 -38.97848948
OS -1.07107482 -38.97479124
OS -1.0692257 -38.96831932
OS -1.06552746 -38.95999828
OS -1.24119386 -38.49586916
OS -1.15798346 -38.49586916
OS -1.06090466 -38.76491612
OS -1.06090466 -38.76584068
OS -1.0599801 -38.76676524
OS -1.05905554 -38.76953892
OS -1.05813098 -38.77416172
OS -1.05628186 -38.77878452
OS -1.05443274 -38.78433188
OS -1.04980994 -38.79727572
OS -1.04426258 -38.81299324
OS -1.03871522 -38.83148444
OS -1.03316786 -38.8509002
OS -1.0276205 -38.87216508
OS -1.0276205 -38.87124052
OS -1.02669594 -38.8693914
OS -1.02577138 -38.86661772
OS -1.02484682 -38.86291948
OS -1.02392226 -38.85829668
OS -1.02207314 -38.85274932
OS -1.0183749 -38.83888092
OS -1.0137521 -38.8231634
OS -1.00728018 -38.8046722
OS -1.00173282 -38.786181
OS -0.99433634 -38.76676524
OS -0.89448386 -38.49586916
OS -0.81589626 -38.49586916
OS -0.99248722 -38.96739476
OE
OB -0.54315106 -38.48662356 I
OS -0.53575458 -38.48754812
OS -0.52650898 -38.48939724
OS -0.51633882 -38.49124636
OS -0.50431954 -38.49402004
OS -0.49322482 -38.49679372
OS -0.48028098 -38.50141652
OS -0.4682617 -38.50603932
OS -0.45531786 -38.51251124
OS -0.44237402 -38.51990772
OS -0.42943018 -38.52822876
OS -0.4174109 -38.53839892
OS -0.40631618 -38.54949364
OS -0.40539162 -38.5504182
OS -0.4035425 -38.55226732
OS -0.40076882 -38.55596556
OS -0.39707058 -38.56151292
OS -0.39244778 -38.56798484
OS -0.38782498 -38.57538132
OS -0.38227762 -38.58462692
OS -0.37673026 -38.59572164
OS -0.3711829 -38.60774092
OS -0.36563554 -38.62068476
OS -0.36101274 -38.63547772
OS -0.35638994 -38.65119524
OS -0.3526917 -38.66876188
OS -0.34991802 -38.68725308
OS -0.3480689 -38.70666884
OS -0.34714434 -38.72793372
OS -0.34714434 -38.72885828
OS -0.34714434 -38.73255652
OS -0.34714434 -38.73902844
OS -0.3480689 -38.74827404
OS -0.6947789 -38.74827404
OS -0.6947789 -38.7491986
OS -0.6947789 -38.75197228
OS -0.69385434 -38.75567052
OS -0.69385434 -38.76121788
OS -0.69292978 -38.7676898
OS -0.69108066 -38.77508628
OS -0.68830698 -38.79172836
OS -0.68275962 -38.81021956
OS -0.67536314 -38.83055988
OS -0.66519298 -38.84905108
OS -0.65224914 -38.86569316
OS -0.65132458 -38.86569316
OS -0.65040002 -38.86754228
OS -0.64485266 -38.87216508
OS -0.63653162 -38.878637
OS -0.6254369 -38.88510892
OS -0.61064394 -38.8925054
OS -0.59400186 -38.89897732
OS -0.57551066 -38.90360012
OS -0.5653405 -38.90452468
OS -0.55424578 -38.90544924
OS -0.5468493 -38.90544924
OS -0.53852826 -38.90452468
OS -0.5283581 -38.90267556
OS -0.51726338 -38.89990188
OS -0.50431954 -38.89620364
OS -0.49230026 -38.89065628
OS -0.48028098 -38.8832598
OS -0.47935642 -38.88233524
OS -0.47473362 -38.878637
OS -0.46918626 -38.87308964
OS -0.46271434 -38.86569316
OS -0.45531786 -38.855523
OS -0.44699682 -38.84257916
OS -0.43867578 -38.8277862
OS -0.4312793 -38.81021956
OS -0.34991802 -38.82038972
OS -0.34991802 -38.82131428
OS -0.35084258 -38.8231634
OS -0.35176714 -38.82686164
OS -0.35361626 -38.832409
OS -0.35638994 -38.83795636
OS -0.35916362 -38.84535284
OS -0.3665601 -38.86107036
OS -0.3758057 -38.878637
OS -0.38874954 -38.8971282
OS -0.4035425 -38.91469484
OS -0.4220337 -38.93133692
OS -0.42295826 -38.93133692
OS -0.42480738 -38.93318604
OS -0.42758106 -38.93503516
OS -0.4312793 -38.93780884
OS -0.43682666 -38.94058252
OS -0.44237402 -38.9433562
OS -0.4497705 -38.94705444
OS -0.45809154 -38.95075268
OS -0.46733714 -38.95445092
OS -0.47658274 -38.95814916
OS -0.49969674 -38.96369652
OS -0.52558442 -38.96831932
OS -0.55424578 -38.97016844
OS -0.56441594 -38.97016844
OS -0.57088786 -38.96924388
OS -0.5792089 -38.96831932
OS -0.58937906 -38.9664702
OS -0.60047378 -38.96462108
OS -0.61249306 -38.96277196
OS -0.63838074 -38.95537548
OS -0.65224914 -38.94982812
OS -0.66519298 -38.94428076
OS -0.67906138 -38.93688428
OS -0.69200522 -38.92856324
OS -0.7040245 -38.91931764
OS -0.71604378 -38.90822292
OS -0.71696834 -38.90729836
OS -0.71881746 -38.90544924
OS -0.72159114 -38.901751
OS -0.72528938 -38.89620364
OS -0.72991218 -38.88973172
OS -0.73453498 -38.88233524
OS -0.74008234 -38.87308964
OS -0.7456297 -38.86291948
OS -0.75117706 -38.8509002
OS -0.75672442 -38.83795636
OS -0.76134722 -38.8231634
OS -0.76597002 -38.80744588
OS -0.76966826 -38.7908038
OS -0.77244194 -38.7723126
OS -0.77429106 -38.75289684
OS -0.77521562 -38.73255652
OS -0.77521562 -38.73163196
OS -0.77521562 -38.72700916
OS -0.77521562 -38.7214618
OS -0.77429106 -38.71314076
OS -0.7733665 -38.7029706
OS -0.77244194 -38.69187588
OS -0.77059282 -38.67893204
OS -0.76781914 -38.6659882
OS -0.76042266 -38.63640228
OS -0.75579986 -38.62160932
OS -0.7502525 -38.6058918
OS -0.74285602 -38.59109884
OS -0.73453498 -38.57723044
OS -0.72528938 -38.56336204
OS -0.71511922 -38.5504182
OS -0.71419466 -38.54949364
OS -0.71234554 -38.54764452
OS -0.7086473 -38.54487084
OS -0.7040245 -38.54024804
OS -0.69847714 -38.53562524
OS -0.69108066 -38.53007788
OS -0.68275962 -38.52360596
OS -0.67258946 -38.5180586
OS -0.6624193 -38.51158668
OS -0.65040002 -38.50603932
OS -0.63745618 -38.50049196
OS -0.62358778 -38.49586916
OS -0.60879482 -38.49124636
OS -0.5930773 -38.48847268
OS -0.57643522 -38.48662356
OS -0.55886858 -38.485699
OS -0.54962298 -38.485699
OS -0.54315106 -38.48662356
OE
OB -1.47695666 -38.48662356 I
OS -1.46308826 -38.48754812
OS -1.44737074 -38.48939724
OS -1.43165322 -38.49217092
OS -1.4159357 -38.49586916
OS -1.40114274 -38.50049196
OS -1.39929362 -38.50141652
OS -1.39467082 -38.50326564
OS -1.3881989 -38.50603932
OS -1.37987786 -38.50973756
OS -1.37063226 -38.51528492
OS -1.36138666 -38.52083228
OS -1.35306562 -38.52822876
OS -1.34566914 -38.53562524
OS -1.34474458 -38.5365498
OS -1.34289546 -38.53932348
OS -1.34012178 -38.54394628
OS -1.33642354 -38.54949364
OS -1.33180074 -38.55781468
OS -1.3281025 -38.56613572
OS -1.32440426 -38.57630588
OS -1.32163058 -38.58832516
OS -1.32163058 -38.58924972
OS -1.32070602 -38.5920234
OS -1.31978146 -38.59757076
OS -1.3188569 -38.60496724
OS -1.3188569 -38.6151374
OS -1.31793234 -38.62715668
OS -1.31700778 -38.6428742
OS -1.31700778 -38.66044084
OS -1.31700778 -38.76584068
OS -1.31700778 -38.76676524
OS -1.31700778 -38.77046348
OS -1.31700778 -38.77601084
OS -1.31700778 -38.78340732
OS -1.31700778 -38.79172836
OS -1.31700778 -38.80189852
OS -1.31608322 -38.82408796
OS -1.31608322 -38.84720196
OS -1.31515866 -38.87031596
OS -1.3142341 -38.88048612
OS -1.3142341 -38.88973172
OS -1.31330954 -38.89805276
OS -1.31238498 -38.90452468
OS -1.31238498 -38.90544924
OS -1.31146042 -38.90914748
OS -1.31053586 -38.91469484
OS -1.30776218 -38.92209132
OS -1.30591306 -38.93041236
OS -1.30221482 -38.93965796
OS -1.29759202 -38.94982812
OS -1.29296922 -38.95999828
OS -1.37525506 -38.95999828
OS -1.37617962 -38.95907372
OS -1.37710418 -38.95537548
OS -1.3789533 -38.95075268
OS -1.38172698 -38.9433562
OS -1.38450066 -38.93503516
OS -1.38634978 -38.924865
OS -1.3881989 -38.91377028
OS -1.39004802 -38.901751
OS -1.39097258 -38.901751
OS -1.39189714 -38.90360012
OS -1.3974445 -38.90822292
OS -1.40576554 -38.91469484
OS -1.41686026 -38.92301588
OS -1.43072866 -38.93133692
OS -1.44459706 -38.94058252
OS -1.45939002 -38.94890356
OS -1.47510754 -38.95537548
OS -1.47695666 -38.95630004
OS -1.48250402 -38.9572246
OS -1.49082506 -38.95999828
OS -1.50099522 -38.96277196
OS -1.51393906 -38.96554564
OS -1.52873202 -38.96739476
OS -1.5453741 -38.96924388
OS -1.56201618 -38.97016844
OS -1.56941266 -38.97016844
OS -1.57496002 -38.96924388
OS -1.58143194 -38.96924388
OS -1.58882842 -38.96831932
OS -1.6054705 -38.96554564
OS -1.6239617 -38.96092284
OS -1.64430202 -38.95445092
OS -1.66279322 -38.94520532
OS -1.6794353 -38.93318604
OS -1.68128442 -38.93133692
OS -1.68590722 -38.92671412
OS -1.69237914 -38.91839308
OS -1.69977562 -38.90729836
OS -1.7071721 -38.89342996
OS -1.71364402 -38.87771244
OS -1.71826682 -38.85829668
OS -1.71919138 -38.84905108
OS -1.72011594 -38.83795636
OS -1.72011594 -38.83610724
OS -1.72011594 -38.832409
OS -1.71919138 -38.82593708
OS -1.71826682 -38.81761604
OS -1.7164177 -38.80744588
OS -1.71364402 -38.79727572
OS -1.70994578 -38.786181
OS -1.70532298 -38.77601084
OS -1.70439842 -38.77508628
OS -1.7025493 -38.77138804
OS -1.69885106 -38.76584068
OS -1.69422826 -38.75936876
OS -1.6886809 -38.75197228
OS -1.68128442 -38.7445758
OS -1.67388794 -38.73717932
OS -1.66464234 -38.7307074
OS -1.66371778 -38.72978284
OS -1.66001954 -38.72793372
OS -1.65539674 -38.72423548
OS -1.64800026 -38.72053724
OS -1.63967922 -38.716839
OS -1.62950906 -38.7122162
OS -1.6193389 -38.70851796
OS -1.60731962 -38.70481972
OS -1.60639506 -38.70481972
OS -1.60269682 -38.70389516
OS -1.59714946 -38.70204604
OS -1.58975298 -38.70112148
OS -1.58050738 -38.69927236
OS -1.5684881 -38.69742324
OS -1.5546197 -38.69464956
OS -1.53797762 -38.69280044
OS -1.53705306 -38.69280044
OS -1.53335482 -38.69187588
OS -1.52873202 -38.69187588
OS -1.5222601 -38.69095132
OS -1.51486362 -38.69002676
OS -1.50561802 -38.68817764
OS -1.49544786 -38.68725308
OS -1.48435314 -38.68540396
OS -1.4621637 -38.68078116
OS -1.43812514 -38.67615836
OS -1.41686026 -38.670611
OS -1.4066901 -38.66783732
OS -1.3974445 -38.66506364
OS -1.3974445 -38.66413908
OS -1.3974445 -38.66228996
OS -1.39651994 -38.6567426
OS -1.39651994 -38.65027068
OS -1.39651994 -38.64657244
OS -1.39651994 -38.64472332
OS -1.39651994 -38.64379876
OS -1.39651994 -38.6428742
OS -1.39651994 -38.63732684
OS -1.3974445 -38.62808124
OS -1.39929362 -38.61791108
OS -1.4020673 -38.60681636
OS -1.4066901 -38.59572164
OS -1.41223746 -38.58555148
OS -1.41963394 -38.57723044
OS -1.4205585 -38.57630588
OS -1.4251813 -38.57260764
OS -1.43257778 -38.5689094
OS -1.44182338 -38.56336204
OS -1.45476722 -38.55873924
OS -1.46956018 -38.55411644
OS -1.48805138 -38.55134276
OS -1.50931626 -38.5504182
OS -1.51856186 -38.5504182
OS -1.52780746 -38.55134276
OS -1.5407513 -38.55319188
OS -1.55369514 -38.555041
OS -1.56756354 -38.55873924
OS -1.58050738 -38.56336204
OS -1.5916021 -38.56983396
OS -1.59252666 -38.57075852
OS -1.5962249 -38.5735322
OS -1.6008477 -38.578155
OS -1.60639506 -38.58555148
OS -1.61194242 -38.59479708
OS -1.61841434 -38.60681636
OS -1.6239617 -38.62160932
OS -1.62950906 -38.6382514
OS -1.70624754 -38.62808124
OS -1.70624754 -38.62715668
OS -1.70532298 -38.62623212
OS -1.70532298 -38.62345844
OS -1.70439842 -38.6197602
OS -1.70162474 -38.61143916
OS -1.6979265 -38.59941988
OS -1.6933037 -38.5874006
OS -1.68775634 -38.57445676
OS -1.68035986 -38.56151292
OS -1.67203882 -38.54949364
OS -1.67111426 -38.54856908
OS -1.66741602 -38.54487084
OS -1.66186866 -38.53932348
OS -1.65447218 -38.531927
OS -1.64430202 -38.52453052
OS -1.63228274 -38.51713404
OS -1.61841434 -38.508813
OS -1.60269682 -38.50234108
OS -1.60177226 -38.50234108
OS -1.6008477 -38.50141652
OS -1.59807402 -38.50049196
OS -1.59437578 -38.4995674
OS -1.58513018 -38.49679372
OS -1.57218634 -38.49402004
OS -1.55739338 -38.49124636
OS -1.53890218 -38.48847268
OS -1.51948642 -38.48662356
OS -1.49729698 -38.485699
OS -1.48712682 -38.485699
OS -1.47695666 -38.48662356
OE
OB 0.11698478 -38.42745172 I
OS 0.0957199 -38.54671996
OS 0.04671822 -38.54671996
OS 0.02730246 -38.42745172
OS 0.02730246 -38.32020276
OS 0.11698478 -38.32020276
OS 0.11698478 -38.42745172
OE
OB -5.4655085 -38.31835364 I
OS -5.45348922 -38.32020276
OS -5.43962082 -38.32297644
OS -5.42482786 -38.32667468
OS -5.40911034 -38.33129748
OS -5.39431738 -38.33869396
OS -5.39339282 -38.33869396
OS -5.39246826 -38.33961852
OS -5.38784546 -38.3423922
OS -5.38044898 -38.347015
OS -5.37120338 -38.35348692
OS -5.36103322 -38.36273252
OS -5.3499385 -38.37290268
OS -5.33976834 -38.38492196
OS -5.32959818 -38.39879036
OS -5.32867362 -38.40063948
OS -5.32497538 -38.40526228
OS -5.32127714 -38.41358332
OS -5.31480522 -38.4256026
OS -5.30925786 -38.439471
OS -5.30186138 -38.45518852
OS -5.29538946 -38.47367972
OS -5.2898421 -38.49402004
OS -5.2898421 -38.4949446
OS -5.28891754 -38.49679372
OS -5.28799298 -38.4995674
OS -5.28706842 -38.5041902
OS -5.28614386 -38.50973756
OS -5.2852193 -38.51620948
OS -5.28337018 -38.52453052
OS -5.28244562 -38.53377612
OS -5.2805965 -38.54394628
OS -5.27967194 -38.555041
OS -5.27874738 -38.56798484
OS -5.27689826 -38.58092868
OS -5.2759737 -38.59572164
OS -5.2759737 -38.6105146
OS -5.27504914 -38.62715668
OS -5.27504914 -38.64472332
OS -5.27504914 -38.64564788
OS -5.27504914 -38.64934612
OS -5.27504914 -38.65581804
OS -5.27504914 -38.66321452
OS -5.2759737 -38.67338468
OS -5.2759737 -38.6844794
OS -5.27689826 -38.69649868
OS -5.27782282 -38.70944252
OS -5.2805965 -38.73902844
OS -5.2852193 -38.76953892
OS -5.29076666 -38.79912484
OS -5.2944649 -38.81299324
OS -5.2990877 -38.82686164
OS -5.2990877 -38.8277862
OS -5.30001226 -38.82963532
OS -5.30186138 -38.83333356
OS -5.3037105 -38.83795636
OS -5.30555962 -38.84442828
OS -5.30925786 -38.8509002
OS -5.31665434 -38.86661772
OS -5.32589994 -38.8832598
OS -5.33791922 -38.901751
OS -5.35178762 -38.91839308
OS -5.3684297 -38.9341106
OS -5.36935426 -38.9341106
OS -5.37027882 -38.93595972
OS -5.3730525 -38.93780884
OS -5.37675074 -38.93965796
OS -5.38137354 -38.94243164
OS -5.38599634 -38.94612988
OS -5.39986474 -38.9526018
OS -5.41650682 -38.95907372
OS -5.43592258 -38.96554564
OS -5.45903658 -38.96924388
OS -5.4839997 -38.971093
OS -5.4932453 -38.971093
OS -5.49971722 -38.97016844
OS -5.5071137 -38.96924388
OS -5.5163593 -38.96739476
OS -5.52652946 -38.96554564
OS -5.53762418 -38.96277196
OS -5.5487189 -38.95907372
OS -5.56073818 -38.95537548
OS -5.57275746 -38.94982812
OS -5.58477674 -38.9433562
OS -5.59679602 -38.93595972
OS -5.6088153 -38.92671412
OS -5.61991002 -38.91654396
OS -5.63008018 -38.90544924
OS -5.63100474 -38.90452468
OS -5.63285386 -38.901751
OS -5.63562754 -38.8971282
OS -5.64025034 -38.88973172
OS -5.64487314 -38.88141068
OS -5.64949594 -38.87031596
OS -5.65596786 -38.85737212
OS -5.66151522 -38.84257916
OS -5.66706258 -38.82593708
OS -5.67260994 -38.80652132
OS -5.6781573 -38.78525644
OS -5.6827801 -38.76121788
OS -5.6874029 -38.7353302
OS -5.69017658 -38.7075934
OS -5.6920257 -38.67708292
OS -5.69295026 -38.64472332
OS -5.69295026 -38.64379876
OS -5.69295026 -38.64010052
OS -5.69295026 -38.6336286
OS -5.69295026 -38.62623212
OS -5.6920257 -38.61606196
OS -5.6920257 -38.60496724
OS -5.69110114 -38.59294796
OS -5.69017658 -38.57907956
OS -5.6874029 -38.5504182
OS -5.6827801 -38.51990772
OS -5.67723274 -38.48939724
OS -5.6735345 -38.47552884
OS -5.66983626 -38.46166044
OS -5.66983626 -38.46073588
OS -5.6689117 -38.45888676
OS -5.66706258 -38.45518852
OS -5.66521346 -38.45056572
OS -5.66336434 -38.4440938
OS -5.6596661 -38.43762188
OS -5.65226962 -38.42190436
OS -5.64302402 -38.40526228
OS -5.63100474 -38.38769564
OS -5.61713634 -38.370129
OS -5.60049426 -38.35533604
OS -5.5995697 -38.35533604
OS -5.59864514 -38.35348692
OS -5.59587146 -38.3516378
OS -5.59217322 -38.34978868
OS -5.58755042 -38.34609044
OS -5.58200306 -38.34331676
OS -5.56813466 -38.33592028
OS -5.55149258 -38.32944836
OS -5.53207682 -38.32297644
OS -5.50896282 -38.3192782
OS -5.4839997 -38.31742908
OS -5.47567866 -38.31742908
OS -5.4655085 -38.31835364
OE
OB -5.79280274 -38.95999828 I
OS -5.87139034 -38.95999828
OS -5.87139034 -38.32020276
OS -5.79280274 -38.32020276
OS -5.79280274 -38.95999828
OE
OB -5.97031826 -38.42745172 I
OS -5.99158314 -38.54671996
OS -6.04058482 -38.54671996
OS -6.06000058 -38.42745172
OS -6.06000058 -38.32020276
OS -5.97031826 -38.32020276
OS -5.97031826 -38.42745172
OE
OB -4.9754917 -38.31835364 I
OS -4.96347242 -38.32020276
OS -4.94867946 -38.32297644
OS -4.93203738 -38.32759924
OS -4.9153953 -38.3331466
OS -4.89875322 -38.34054308
OS -4.89782866 -38.34054308
OS -4.8969041 -38.34146764
OS -4.89135674 -38.34424132
OS -4.8830357 -38.34978868
OS -4.8737901 -38.3562606
OS -4.86269538 -38.3655062
OS -4.85160066 -38.37567636
OS -4.84050594 -38.38769564
OS -4.83126034 -38.40156404
OS -4.83033578 -38.40341316
OS -4.8275621 -38.40803596
OS -4.82386386 -38.416357
OS -4.81924106 -38.42652716
OS -4.81461826 -38.43854644
OS -4.81092002 -38.45241484
OS -4.80814634 -38.46813236
OS -4.80722178 -38.48384988
OS -4.80722178 -38.485699
OS -4.80722178 -38.49124636
OS -4.80814634 -38.49864284
OS -4.80999546 -38.508813
OS -4.81276914 -38.52083228
OS -4.81739194 -38.53377612
OS -4.8229393 -38.54671996
OS -4.83033578 -38.5596638
OS -4.83126034 -38.56151292
OS -4.83403402 -38.56521116
OS -4.83958138 -38.57168308
OS -4.84697786 -38.57907956
OS -4.85622346 -38.5874006
OS -4.86731818 -38.5966462
OS -4.88026202 -38.60496724
OS -4.89597954 -38.61328828
OS -4.89505498 -38.61328828
OS -4.89320586 -38.61421284
OS -4.89043218 -38.6151374
OS -4.88673394 -38.61606196
OS -4.87656378 -38.6197602
OS -4.86361994 -38.62530756
OS -4.84882698 -38.63270404
OS -4.83403402 -38.64194964
OS -4.82016562 -38.65396892
OS -4.80722178 -38.66783732
OS -4.80629722 -38.66968644
OS -4.80259898 -38.6752338
OS -4.79705162 -38.6844794
OS -4.79150426 -38.69649868
OS -4.7859569 -38.71129164
OS -4.78040954 -38.72885828
OS -4.7767113 -38.7491986
OS -4.77578674 -38.77138804
OS -4.77578674 -38.7723126
OS -4.77578674 -38.77508628
OS -4.77578674 -38.77970908
OS -4.7767113 -38.78525644
OS -4.77763586 -38.79265292
OS -4.77948498 -38.80097396
OS -4.7813341 -38.81021956
OS -4.78318322 -38.82038972
OS -4.7905797 -38.84257916
OS -4.79612706 -38.85459844
OS -4.80167442 -38.86569316
OS -4.8090709 -38.87771244
OS -4.81739194 -38.88973172
OS -4.82663754 -38.901751
OS -4.83773226 -38.91284572
OS -4.83865682 -38.91377028
OS -4.84050594 -38.9156194
OS -4.84420418 -38.91839308
OS -4.84882698 -38.92209132
OS -4.85437434 -38.92671412
OS -4.86177082 -38.93133692
OS -4.87009186 -38.93688428
OS -4.88026202 -38.94150708
OS -4.89043218 -38.94705444
OS -4.90245146 -38.9526018
OS -4.91447074 -38.9572246
OS -4.92833914 -38.9618474
OS -4.9431321 -38.96554564
OS -4.95884962 -38.96831932
OS -4.97456714 -38.97016844
OS -4.99213378 -38.971093
OS -5.00045482 -38.971093
OS -5.00600218 -38.97016844
OS -5.01339866 -38.96924388
OS -5.0217197 -38.96831932
OS -5.0309653 -38.9664702
OS -5.04113546 -38.96462108
OS -5.0633249 -38.95907372
OS -5.0864389 -38.94982812
OS -5.09845818 -38.94428076
OS -5.1095529 -38.93780884
OS -5.12064762 -38.9294878
OS -5.13174234 -38.92116676
OS -5.1326669 -38.9202422
OS -5.13451602 -38.91839308
OS -5.1372897 -38.9156194
OS -5.14006338 -38.91192116
OS -5.14468618 -38.90729836
OS -5.14930898 -38.90082644
OS -5.15485634 -38.89435452
OS -5.1604037 -38.88603348
OS -5.16595106 -38.87678788
OS -5.17149842 -38.86754228
OS -5.18166858 -38.84535284
OS -5.18998962 -38.81946516
OS -5.1927633 -38.80559676
OS -5.19461242 -38.7908038
OS -5.11602482 -38.78063364
OS -5.11602482 -38.7815582
OS -5.11510026 -38.78340732
OS -5.1141757 -38.78710556
OS -5.11325114 -38.79172836
OS -5.11232658 -38.79727572
OS -5.11047746 -38.80374764
OS -5.10585466 -38.81761604
OS -5.09938274 -38.83425812
OS -5.0910617 -38.84997564
OS -5.0818161 -38.8647686
OS -5.07072138 -38.87771244
OS -5.06887226 -38.878637
OS -5.06517402 -38.88233524
OS -5.05777754 -38.88695804
OS -5.04853194 -38.89158084
OS -5.03743722 -38.8971282
OS -5.02356882 -38.901751
OS -5.0078513 -38.90544924
OS -4.99120922 -38.9063738
OS -4.98566186 -38.9063738
OS -4.98196362 -38.90544924
OS -4.97179346 -38.90452468
OS -4.95884962 -38.901751
OS -4.94405666 -38.8971282
OS -4.92833914 -38.89065628
OS -4.91262162 -38.88141068
OS -4.89782866 -38.86846684
OS -4.89597954 -38.86661772
OS -4.89135674 -38.86107036
OS -4.88580938 -38.85274932
OS -4.8784129 -38.8416546
OS -4.87101642 -38.8277862
OS -4.86546906 -38.81206868
OS -4.86084626 -38.79357748
OS -4.85899714 -38.77323716
OS -4.85899714 -38.7723126
OS -4.85899714 -38.77046348
OS -4.85899714 -38.7676898
OS -4.8599217 -38.76399156
OS -4.86084626 -38.7538214
OS -4.86361994 -38.74180212
OS -4.86731818 -38.72700916
OS -4.8737901 -38.7122162
OS -4.8830357 -38.69742324
OS -4.89505498 -38.68355484
OS -4.8969041 -38.68170572
OS -4.9015269 -38.67800748
OS -4.90892338 -38.67246012
OS -4.91909354 -38.6659882
OS -4.93203738 -38.65951628
OS -4.9477549 -38.65396892
OS -4.96532154 -38.65027068
OS -4.9847373 -38.64842156
OS -4.99305834 -38.64842156
OS -4.99953026 -38.64934612
OS -5.0078513 -38.65027068
OS -5.0170969 -38.6521198
OS -5.02819162 -38.65396892
OS -5.0402109 -38.6567426
OS -5.0309653 -38.5874006
OS -5.0263425 -38.5874006
OS -5.02264426 -38.58832516
OS -5.01062498 -38.58832516
OS -5.00045482 -38.58647604
OS -4.98843554 -38.58462692
OS -4.97456714 -38.58185324
OS -4.95884962 -38.57723044
OS -4.94405666 -38.57075852
OS -4.92833914 -38.56243748
OS -4.92741458 -38.56243748
OS -4.92649002 -38.56151292
OS -4.92186722 -38.55781468
OS -4.9153953 -38.55134276
OS -4.90799882 -38.54302172
OS -4.90060234 -38.53100244
OS -4.89413042 -38.51713404
OS -4.88950762 -38.50141652
OS -4.8876585 -38.49217092
OS -4.8876585 -38.48200076
OS -4.8876585 -38.4810762
OS -4.8876585 -38.48015164
OS -4.8876585 -38.47460428
OS -4.88950762 -38.4672078
OS -4.89135674 -38.45703764
OS -4.89505498 -38.44594292
OS -4.89967778 -38.43392364
OS -4.90707426 -38.42190436
OS -4.91724442 -38.41080964
OS -4.91816898 -38.40988508
OS -4.92279178 -38.40618684
OS -4.9292637 -38.40156404
OS -4.93758474 -38.39601668
OS -4.94867946 -38.39139388
OS -4.9616233 -38.38677108
OS -4.97641626 -38.38307284
OS -4.99305834 -38.38214828
OS -5.00045482 -38.38214828
OS -5.00877586 -38.3839974
OS -5.01987058 -38.38584652
OS -5.03188986 -38.38954476
OS -5.04390914 -38.39416756
OS -5.05685298 -38.40156404
OS -5.06887226 -38.41080964
OS -5.06979682 -38.4117342
OS -5.07349506 -38.416357
OS -5.07904242 -38.42282892
OS -5.08551434 -38.43207452
OS -5.09198626 -38.4440938
OS -5.09845818 -38.45888676
OS -5.10400554 -38.4764534
OS -5.10770378 -38.49679372
OS -5.18629138 -38.48292532
OS -5.18629138 -38.48200076
OS -5.18536682 -38.47922708
OS -5.18444226 -38.47552884
OS -5.1835177 -38.46998148
OS -5.18166858 -38.46350956
OS -5.1788949 -38.45611308
OS -5.17334754 -38.43854644
OS -5.16410194 -38.41820612
OS -5.15300722 -38.3978658
OS -5.13913882 -38.37845004
OS -5.12157218 -38.3608834
OS -5.12064762 -38.35995884
OS -5.1187985 -38.35903428
OS -5.11602482 -38.35718516
OS -5.11232658 -38.35441148
OS -5.10770378 -38.35071324
OS -5.10123186 -38.347015
OS -5.09475994 -38.34331676
OS -5.0864389 -38.33869396
OS -5.0679477 -38.33129748
OS -5.04668282 -38.323901
OS -5.0217197 -38.3192782
OS -5.00877586 -38.31742908
OS -4.98566186 -38.31742908
OS -4.9754917 -38.31835364
OE
OB -4.29963834 -38.40988508 I
OS -4.37822594 -38.40988508
OS -4.37822594 -38.32020276
OS -4.29963834 -38.32020276
OS -4.29963834 -38.40988508
OE
OB -4.29963834 -38.95999828 I
OS -4.37822594 -38.95999828
OS -4.37822594 -38.49586916
OS -4.29963834 -38.49586916
OS -4.29963834 -38.95999828
OE
OB -4.46421002 -38.7676898 I
OS -4.7073693 -38.7676898
OS -4.7073693 -38.6891022
OS -4.46421002 -38.6891022
OS -4.46421002 -38.7676898
OE
OB -3.94738098 -38.48662356 I
OS -3.93721082 -38.48754812
OS -3.92519154 -38.48939724
OS -3.9122477 -38.49217092
OS -3.8983793 -38.49586916
OS -3.88543546 -38.50141652
OS -3.88358634 -38.50234108
OS -3.8798881 -38.5041902
OS -3.87341618 -38.50696388
OS -3.8660197 -38.51158668
OS -3.8567741 -38.51713404
OS -3.84845306 -38.52453052
OS -3.84013202 -38.531927
OS -3.83273554 -38.5411726
OS -3.83181098 -38.54209716
OS -3.82996186 -38.5457954
OS -3.82718818 -38.5504182
OS -3.82256538 -38.55689012
OS -3.81886714 -38.56613572
OS -3.8151689 -38.57538132
OS -3.8105461 -38.58647604
OS -3.80777242 -38.59849532
OS -3.80777242 -38.59941988
OS -3.80684786 -38.60311812
OS -3.8059233 -38.60866548
OS -3.80499874 -38.61606196
OS -3.80499874 -38.62715668
OS -3.80407418 -38.64010052
OS -3.80314962 -38.65581804
OS -3.80314962 -38.6752338
OS -3.80314962 -38.95999828
OS -3.88173722 -38.95999828
OS -3.88173722 -38.67893204
OS -3.88173722 -38.67800748
OS -3.88173722 -38.67708292
OS -3.88173722 -38.670611
OS -3.88173722 -38.66228996
OS -3.88266178 -38.6521198
OS -3.88358634 -38.64010052
OS -3.88543546 -38.62808124
OS -3.88820914 -38.61698652
OS -3.89098282 -38.60681636
OS -3.89098282 -38.6058918
OS -3.89283194 -38.60311812
OS -3.89560562 -38.59849532
OS -3.8983793 -38.59294796
OS -3.9030021 -38.5874006
OS -3.90854946 -38.58092868
OS -3.91594594 -38.57445676
OS -3.92426698 -38.5689094
OS -3.92519154 -38.56798484
OS -3.92796522 -38.56613572
OS -3.93351258 -38.5642866
OS -3.9399845 -38.56151292
OS -3.94738098 -38.55873924
OS -3.95662658 -38.55596556
OS -3.9677213 -38.555041
OS -3.97881602 -38.55411644
OS -3.98343882 -38.55411644
OS -3.98713706 -38.555041
OS -3.99638266 -38.55596556
OS -4.00840194 -38.55781468
OS -4.02134578 -38.56243748
OS -4.03613874 -38.56798484
OS -4.0509317 -38.57538132
OS -4.0648001 -38.58647604
OS -4.06664922 -38.58832516
OS -4.07034746 -38.59294796
OS -4.07312114 -38.5966462
OS -4.07589482 -38.601269
OS -4.07959306 -38.60681636
OS -4.08236674 -38.61328828
OS -4.08606498 -38.62068476
OS -4.08976322 -38.62993036
OS -4.0925369 -38.64010052
OS -4.09531058 -38.65119524
OS -4.0971597 -38.66321452
OS -4.09900882 -38.67615836
OS -4.10085794 -38.69187588
OS -4.10085794 -38.7075934
OS -4.10085794 -38.95999828
OS -4.17944554 -38.95999828
OS -4.17944554 -38.49586916
OS -4.10917898 -38.49586916
OS -4.10917898 -38.56243748
OS -4.10825442 -38.56151292
OS -4.1064053 -38.55873924
OS -4.10363162 -38.555041
OS -4.09993338 -38.5504182
OS -4.09438602 -38.54487084
OS -4.0879141 -38.53839892
OS -4.08051762 -38.53100244
OS -4.07127202 -38.52360596
OS -4.06202642 -38.51713404
OS -4.0509317 -38.50973756
OS -4.03891242 -38.50326564
OS -4.02596858 -38.49771828
OS -4.01117562 -38.49309548
OS -3.99638266 -38.48939724
OS -3.97974058 -38.48662356
OS -3.96217394 -38.485699
OS -3.95477746 -38.485699
OS -3.94738098 -38.48662356
OE
OB -0.55794402 -38.5504182 H
OS -0.56349138 -38.5504182
OS -0.56718962 -38.55134276
OS -0.57735978 -38.55226732
OS -0.58937906 -38.555041
OS -0.60417202 -38.5596638
OS -0.61988954 -38.56613572
OS -0.6346825 -38.57538132
OS -0.64947546 -38.5874006
OS -0.65132458 -38.58924972
OS -0.65502282 -38.59387252
OS -0.66149474 -38.60219356
OS -0.66796666 -38.61328828
OS -0.67536314 -38.62623212
OS -0.68183506 -38.6428742
OS -0.68738242 -38.66228996
OS -0.6901561 -38.68355484
OS -0.43035474 -38.68355484
OS -0.43035474 -38.68263028
OS -0.43035474 -38.68078116
OS -0.4312793 -38.67800748
OS -0.4312793 -38.67430924
OS -0.43312842 -38.66321452
OS -0.4359021 -38.65119524
OS -0.4405249 -38.63640228
OS -0.4451477 -38.62253388
OS -0.45254418 -38.60866548
OS -0.46086522 -38.5966462
OS -0.46086522 -38.59572164
OS -0.46271434 -38.59479708
OS -0.46733714 -38.58924972
OS -0.47565818 -38.58185324
OS -0.4867529 -38.5735322
OS -0.5006213 -38.56521116
OS -0.51726338 -38.55781468
OS -0.53667914 -38.55226732
OS -0.5468493 -38.55134276
OS -0.55794402 -38.5504182
OE
OB -5.48492426 -38.38214828 H
OS -5.49047162 -38.38214828
OS -5.49416986 -38.38307284
OS -5.50434002 -38.38492196
OS -5.5163593 -38.38769564
OS -5.5302277 -38.393243
OS -5.54502066 -38.40156404
OS -5.55241714 -38.4071114
OS -5.55981362 -38.41265876
OS -5.56628554 -38.42005524
OS -5.57275746 -38.42837628
OS -5.57275746 -38.42930084
OS -5.57460658 -38.43114996
OS -5.5764557 -38.4348482
OS -5.57922938 -38.439471
OS -5.58200306 -38.44686748
OS -5.5857013 -38.45518852
OS -5.58847498 -38.46535868
OS -5.59217322 -38.47737796
OS -5.59587146 -38.49124636
OS -5.5995697 -38.50696388
OS -5.60326794 -38.52453052
OS -5.60604162 -38.54394628
OS -5.6088153 -38.56613572
OS -5.61066442 -38.59017428
OS -5.61158898 -38.61606196
OS -5.61251354 -38.64472332
OS -5.61251354 -38.64657244
OS -5.61251354 -38.65119524
OS -5.61251354 -38.65951628
OS -5.61158898 -38.670611
OS -5.61158898 -38.68263028
OS -5.61066442 -38.69742324
OS -5.60973986 -38.71314076
OS -5.60789074 -38.72978284
OS -5.60326794 -38.76584068
OS -5.60049426 -38.78340732
OS -5.59679602 -38.8000494
OS -5.59309778 -38.81576692
OS -5.58755042 -38.83055988
OS -5.58200306 -38.84350372
OS -5.57553114 -38.85459844
OS -5.57553114 -38.855523
OS -5.57368202 -38.85644756
OS -5.56905922 -38.86291948
OS -5.56073818 -38.87124052
OS -5.55056802 -38.88048612
OS -5.53669962 -38.88973172
OS -5.5209821 -38.89805276
OS -5.50341546 -38.90452468
OS -5.49416986 -38.90544924
OS -5.4839997 -38.9063738
OS -5.47845234 -38.9063738
OS -5.4747541 -38.90544924
OS -5.4655085 -38.90360012
OS -5.45256466 -38.89990188
OS -5.43869626 -38.89342996
OS -5.42297874 -38.88418436
OS -5.41558226 -38.878637
OS -5.40818578 -38.87124052
OS -5.4007893 -38.86384404
OS -5.39339282 -38.85459844
OS -5.39339282 -38.85367388
OS -5.3915437 -38.85182476
OS -5.38969458 -38.84905108
OS -5.38784546 -38.84442828
OS -5.38414722 -38.83795636
OS -5.38137354 -38.82963532
OS -5.3776753 -38.82038972
OS -5.37397706 -38.809295
OS -5.37120338 -38.7954266
OS -5.36750514 -38.78063364
OS -5.3638069 -38.763067
OS -5.36103322 -38.7445758
OS -5.3591841 -38.72238636
OS -5.35733498 -38.69927236
OS -5.35548586 -38.67338468
OS -5.35548586 -38.64472332
OS -5.35548586 -38.64379876
OS -5.35548586 -38.6428742
OS -5.35548586 -38.6382514
OS -5.35548586 -38.62993036
OS -5.35641042 -38.61883564
OS -5.35641042 -38.60681636
OS -5.35733498 -38.5920234
OS -5.35825954 -38.57630588
OS -5.36010866 -38.55873924
OS -5.36473146 -38.52360596
OS -5.36750514 -38.50603932
OS -5.37120338 -38.48939724
OS -5.37490162 -38.47367972
OS -5.38044898 -38.45888676
OS -5.38599634 -38.44594292
OS -5.39246826 -38.4348482
OS -5.39246826 -38.43392364
OS -5.39431738 -38.43299908
OS -5.3961665 -38.4302254
OS -5.39894018 -38.42652716
OS -5.40726122 -38.41820612
OS -5.41743138 -38.40803596
OS -5.43129978 -38.39879036
OS -5.4470173 -38.39046932
OS -5.45533834 -38.38677108
OS -5.46458394 -38.3839974
OS -5.4747541 -38.38307284
OS -5.48492426 -38.38214828
OE
OB -2.99415962 -38.5504182 H
OS -2.99970698 -38.5504182
OS -3.00340522 -38.55134276
OS -3.01357538 -38.55226732
OS -3.02559466 -38.555041
OS -3.04038762 -38.5596638
OS -3.05610514 -38.56613572
OS -3.0708981 -38.57538132
OS -3.08569106 -38.5874006
OS -3.08754018 -38.58924972
OS -3.09123842 -38.59387252
OS -3.09771034 -38.60219356
OS -3.10418226 -38.61328828
OS -3.11157874 -38.62623212
OS -3.11805066 -38.6428742
OS -3.12359802 -38.66228996
OS -3.1263717 -38.68355484
OS -2.86657034 -38.68355484
OS -2.86657034 -38.68263028
OS -2.86657034 -38.68078116
OS -2.8674949 -38.67800748
OS -2.8674949 -38.67430924
OS -2.86934402 -38.66321452
OS -2.8721177 -38.65119524
OS -2.8767405 -38.63640228
OS -2.8813633 -38.62253388
OS -2.88875978 -38.60866548
OS -2.89708082 -38.5966462
OS -2.89708082 -38.59572164
OS -2.89892994 -38.59479708
OS -2.90355274 -38.58924972
OS -2.91187378 -38.58185324
OS -2.9229685 -38.5735322
OS -2.9368369 -38.56521116
OS -2.95347898 -38.55781468
OS -2.97289474 -38.55226732
OS -2.9830649 -38.55134276
OS -2.99415962 -38.5504182
OE
OB -1.39651994 -38.72700916 H
OS -1.3974445 -38.72700916
OS -1.39836906 -38.72793372
OS -1.40114274 -38.72885828
OS -1.40484098 -38.72978284
OS -1.40946378 -38.73163196
OS -1.41501114 -38.73348108
OS -1.42148306 -38.7353302
OS -1.42887954 -38.73717932
OS -1.43720058 -38.739953
OS -1.44737074 -38.74180212
OS -1.4575409 -38.7445758
OS -1.46956018 -38.74734948
OS -1.48250402 -38.75012316
OS -1.49544786 -38.75289684
OS -1.51024082 -38.75474596
OS -1.52595834 -38.75751964
OS -1.52780746 -38.75751964
OS -1.53335482 -38.7584442
OS -1.54260042 -38.76029332
OS -1.55277058 -38.76214244
OS -1.5638653 -38.76399156
OS -1.57496002 -38.76676524
OS -1.58513018 -38.76953892
OS -1.59437578 -38.77323716
OS -1.59530034 -38.77323716
OS -1.59807402 -38.77508628
OS -1.60177226 -38.7769354
OS -1.6054705 -38.77970908
OS -1.61656522 -38.78710556
OS -1.62581082 -38.79820028
OS -1.62581082 -38.79912484
OS -1.62765994 -38.80097396
OS -1.6285845 -38.8046722
OS -1.63043362 -38.809295
OS -1.63228274 -38.81484236
OS -1.63413186 -38.82038972
OS -1.63505642 -38.8277862
OS -1.63598098 -38.83518268
OS -1.63598098 -38.83610724
OS -1.63598098 -38.84073004
OS -1.63505642 -38.8462774
OS -1.6332073 -38.85367388
OS -1.63043362 -38.86199492
OS -1.62581082 -38.87031596
OS -1.62026346 -38.87956156
OS -1.61286698 -38.8878826
OS -1.61194242 -38.88880716
OS -1.60824418 -38.89065628
OS -1.60269682 -38.89435452
OS -1.59530034 -38.89805276
OS -1.58513018 -38.901751
OS -1.5731109 -38.90544924
OS -1.5592425 -38.90729836
OS -1.54260042 -38.90822292
OS -1.53520394 -38.90822292
OS -1.52595834 -38.90729836
OS -1.51578818 -38.90544924
OS -1.50284434 -38.90360012
OS -1.4899005 -38.89990188
OS -1.4760321 -38.89527908
OS -1.4621637 -38.88880716
OS -1.46031458 -38.8878826
OS -1.45661634 -38.88510892
OS -1.45014442 -38.88048612
OS -1.44274794 -38.8740142
OS -1.4344269 -38.86661772
OS -1.4251813 -38.85737212
OS -1.41778482 -38.8462774
OS -1.41038834 -38.83425812
OS -1.40946378 -38.83333356
OS -1.40853922 -38.82963532
OS -1.4066901 -38.8231634
OS -1.40391642 -38.81484236
OS -1.40114274 -38.80374764
OS -1.39929362 -38.7908038
OS -1.39836906 -38.77508628
OS -1.3974445 -38.75659508
OS -1.39651994 -38.72700916
OE
SE
S P 0
OB -4.66714078 -36.5016923 I
OS -4.65465922 -36.5016923
OS -4.62553558 -36.50307914
OS -4.5950251 -36.50723966
OS -4.56174094 -36.51140018
OS -4.53123046 -36.51833438
OS -4.51597522 -36.5224949
OS -4.50349366 -36.52665542
OS -4.50210682 -36.52665542
OS -4.50071998 -36.52804226
OS -4.49239894 -36.53220278
OS -4.47991738 -36.53775014
OS -4.46466214 -36.54745802
OS -4.44802006 -36.55993958
OS -4.42999114 -36.57658166
OS -4.41334906 -36.59599742
OS -4.39670698 -36.61818686
OS -4.39670698 -36.6195737
OS -4.39532014 -36.62096054
OS -4.38977278 -36.62928158
OS -4.38422542 -36.64314998
OS -4.37590438 -36.6611789
OS -4.36897018 -36.6819815
OS -4.36203598 -36.70694462
OS -4.35787546 -36.73329458
OS -4.35648862 -36.76241822
OS -4.35648862 -36.76380506
OS -4.35648862 -36.76657874
OS -4.35648862 -36.7721261
OS -4.35787546 -36.7790603
OS -4.35787546 -36.78876818
OS -4.3592623 -36.79847606
OS -4.36480966 -36.82205234
OS -4.3731307 -36.84978914
OS -4.38422542 -36.87891278
OS -4.4008675 -36.90803642
OS -4.41196222 -36.92190482
OS -4.42305694 -36.93577322
OS -4.42444378 -36.93716006
OS -4.42583062 -36.9385469
OS -4.42999114 -36.94270742
OS -4.4355385 -36.94686794
OS -4.4424727 -36.9524153
OS -4.45079374 -36.95796266
OS -4.46188846 -36.96489686
OS -4.47298318 -36.9732179
OS -4.48685158 -36.9801521
OS -4.50210682 -36.9870863
OS -4.5187489 -36.99540734
OS -4.53677782 -37.00234154
OS -4.55758042 -37.0078889
OS -4.57838302 -37.0148231
OS -4.6019593 -37.01898362
OS -4.62692242 -37.02314414
OS -4.62414874 -37.02453098
OS -4.61860138 -37.02730466
OS -4.61028034 -37.03285202
OS -4.59918562 -37.03839938
OS -4.5742225 -37.05365462
OS -4.56174094 -37.0633625
OS -4.55064622 -37.07168354
OS -4.54787254 -37.07445722
OS -4.54093834 -37.08139142
OS -4.52984362 -37.09248614
OS -4.51597522 -37.10635454
OS -4.50071998 -37.1257703
OS -4.48269106 -37.1465729
OS -4.46466214 -37.17153602
OS -4.44524638 -37.19927282
OS -4.28021242 -37.45999874
OS -4.43831218 -37.45999874
OS -4.56451462 -37.26029378
OS -4.56451462 -37.25890694
OS -4.5672883 -37.25613326
OS -4.57006198 -37.25197274
OS -4.5742225 -37.24642538
OS -4.58393038 -37.23117014
OS -4.59641194 -37.21175438
OS -4.61166718 -37.19095178
OS -4.62692242 -37.16876234
OS -4.64217766 -37.14795974
OS -4.65604606 -37.12854398
OS -4.6574329 -37.12715714
OS -4.66159342 -37.12160978
OS -4.66852762 -37.11328874
OS -4.6782355 -37.10358086
OS -4.6990381 -37.08277826
OS -4.71013282 -37.07307038
OS -4.72122754 -37.06474934
OS -4.72261438 -37.0633625
OS -4.72538806 -37.06197566
OS -4.73093542 -37.05920198
OS -4.73925646 -37.05504146
OS -4.7475775 -37.05088094
OS -4.75728538 -37.04672042
OS -4.77947482 -37.03978622
OS -4.78086166 -37.03978622
OS -4.78363534 -37.03839938
OS -4.7891827 -37.03839938
OS -4.7961169 -37.03701254
OS -4.80582478 -37.0356257
OS -4.8169195 -37.0356257
OS -4.83217474 -37.03423886
OS -4.99582186 -37.03423886
OS -4.99582186 -37.45999874
OS -5.12341114 -37.45999874
OS -5.12341114 -36.50030546
OS -4.6782355 -36.50030546
OS -4.66714078 -36.5016923
OE
OB -1.0100437 -37.45999874 I
OS -1.13208562 -37.45999874
OS -1.13208562 -36.65701838
OS -1.4122273 -37.45999874
OS -1.52594818 -37.45999874
OS -1.80331618 -36.64314998
OS -1.80331618 -37.45999874
OS -1.9253581 -37.45999874
OS -1.9253581 -36.50030546
OS -1.73536102 -36.50030546
OS -1.50791926 -37.1812439
OS -1.50791926 -37.18263074
OS -1.50653242 -37.18540442
OS -1.50514558 -37.18956494
OS -1.5023719 -37.19649914
OS -1.49682454 -37.21314122
OS -1.48989034 -37.23394382
OS -1.48295614 -37.2575201
OS -1.4746351 -37.28109638
OS -1.4677009 -37.30328582
OS -1.46215354 -37.32270158
OS -1.4607667 -37.3199279
OS -1.45937986 -37.3129937
OS -1.45521934 -37.30051214
OS -1.44967198 -37.28387006
OS -1.44273778 -37.26168062
OS -1.4330299 -37.23533066
OS -1.42332202 -37.20482018
OS -1.41084046 -37.16876234
OS -1.18062502 -36.50030546
OS -1.0100437 -36.50030546
OS -1.0100437 -37.45999874
OE
OB -2.02382374 -37.45999874 I
OS -2.1680551 -37.45999874
OS -2.28038914 -37.16876234
OS -2.68257274 -37.16876234
OS -2.78658574 -37.45999874
OS -2.92110922 -37.45999874
OS -2.55498346 -36.50030546
OS -2.41629946 -36.50030546
OS -2.02382374 -37.45999874
OE
OB -3.02928274 -37.45999874 I
OS -3.16103254 -37.45999874
OS -3.66306862 -36.70694462
OS -3.66306862 -37.45999874
OS -3.78511054 -37.45999874
OS -3.78511054 -36.50030546
OS -3.65474758 -36.50030546
OS -3.15132466 -37.25474642
OS -3.15132466 -36.50030546
OS -3.02928274 -36.50030546
OS -3.02928274 -37.45999874
OE
OB -5.3231161 -36.61402634 I
OS -5.89033366 -36.61402634
OS -5.89033366 -36.90664958
OS -5.35917394 -36.90664958
OS -5.35917394 -37.02037046
OS -5.89033366 -37.02037046
OS -5.89033366 -37.34627786
OS -5.30092666 -37.34627786
OS -5.30092666 -37.45999874
OS -6.01792294 -37.45999874
OS -6.01792294 -36.50030546
OS -5.3231161 -36.50030546
OS -5.3231161 -36.61402634
OE
OB -0.10721086 -36.61402634 I
OS -0.67442842 -36.61402634
OS -0.67442842 -36.90664958
OS -0.1432687 -36.90664958
OS -0.1432687 -37.02037046
OS -0.67442842 -37.02037046
OS -0.67442842 -37.34627786
OS -0.08502142 -37.34627786
OS -0.08502142 -37.45999874
OS -0.8020177 -37.45999874
OS -0.8020177 -36.50030546
OS -0.10721086 -36.50030546
OS -0.10721086 -36.61402634
OE
OB -8.43241138 -37.34627786 I
OS -7.95949894 -37.34627786
OS -7.95949894 -37.45999874
OS -8.56000066 -37.45999874
OS -8.56000066 -36.50030546
OS -8.43241138 -36.50030546
OS -8.43241138 -37.34627786
OE
OB -6.51718534 -37.05365462 I
OS -6.51718534 -37.45999874
OS -6.64477462 -37.45999874
OS -6.64477462 -37.05365462
OS -7.0150609 -36.50030546
OS -6.86112166 -36.50030546
OS -6.67251142 -36.79154186
OS -6.67251142 -36.7929287
OS -6.66973774 -36.79570238
OS -6.66696406 -36.7998629
OS -6.66419038 -36.80541026
OS -6.65864302 -36.81234446
OS -6.65309566 -36.8206655
OS -6.6406141 -36.8414681
OS -6.62535886 -36.86643122
OS -6.60871678 -36.89416802
OS -6.59068786 -36.92329166
OS -6.57404578 -36.95380214
OS -6.57404578 -36.9524153
OS -6.57265894 -36.94964162
OS -6.56988526 -36.9454811
OS -6.56572474 -36.93993374
OS -6.56156422 -36.93299954
OS -6.55601686 -36.9246785
OS -6.5435353 -36.9038759
OS -6.52828006 -36.87891278
OS -6.51025114 -36.84978914
OS -6.48944854 -36.81789182
OS -6.4672591 -36.78322082
OS -6.28280938 -36.50030546
OS -6.1344175 -36.50030546
OS -6.51718534 -37.05365462
OE
OB -7.01644774 -37.45999874 I
OS -7.1606791 -37.45999874
OS -7.27301314 -37.16876234
OS -7.67519674 -37.16876234
OS -7.77920974 -37.45999874
OS -7.91373322 -37.45999874
OS -7.54760746 -36.50030546
OS -7.40892346 -36.50030546
OS -7.01644774 -37.45999874
OE
OB -7.48103914 -36.60015794 H
OS -7.48103914 -36.60154478
OS -7.48242598 -36.60431846
OS -7.48242598 -36.60986582
OS -7.48519966 -36.61541318
OS -7.4865865 -36.62512106
OS -7.48936018 -36.63482894
OS -7.49490754 -36.65840522
OS -7.50184174 -36.68614202
OS -7.51154962 -36.7166525
OS -7.5212575 -36.74993666
OS -7.53373906 -36.78460766
OS -7.63775206 -37.06474934
OS -7.3132315 -37.06474934
OS -7.41308398 -36.80124974
OS -7.41308398 -36.7998629
OS -7.41447082 -36.79570238
OS -7.4172445 -36.78876818
OS -7.42001818 -36.78044714
OS -7.4241787 -36.77073926
OS -7.42833922 -36.7582577
OS -7.43249974 -36.7443893
OS -7.4380471 -36.7305209
OS -7.44914182 -36.69862358
OS -7.46023654 -36.66533942
OS -7.47133126 -36.63205526
OS -7.48103914 -36.60015794
OE
OB -4.69349074 -36.60709214 H
OS -4.99582186 -36.60709214
OS -4.99582186 -36.9246785
OS -4.71013282 -36.9246785
OS -4.69349074 -36.92329166
OS -4.67407498 -36.92190482
OS -4.65188554 -36.92051798
OS -4.6296961 -36.9177443
OS -4.60750666 -36.91358378
OS -4.5880909 -36.90803642
OS -4.58531722 -36.90664958
OS -4.57976986 -36.9038759
OS -4.57144882 -36.89971538
OS -4.5603541 -36.89416802
OS -4.54787254 -36.88584698
OS -4.53539098 -36.8761391
OS -4.52290942 -36.86365754
OS -4.51320154 -36.84978914
OS -4.5118147 -36.8484023
OS -4.50904102 -36.84285494
OS -4.5048805 -36.8345339
OS -4.49933314 -36.82343918
OS -4.49517262 -36.81095762
OS -4.4910121 -36.79708922
OS -4.48823842 -36.78044714
OS -4.48685158 -36.76380506
OS -4.48685158 -36.76241822
OS -4.48685158 -36.76103138
OS -4.48823842 -36.75271034
OS -4.48962526 -36.74022878
OS -4.49239894 -36.7235867
OS -4.49933314 -36.70694462
OS -4.50765418 -36.68752886
OS -4.52013574 -36.66949994
OS -4.53677782 -36.65147102
OS -4.5395515 -36.65008418
OS -4.5464857 -36.64453682
OS -4.55758042 -36.63760262
OS -4.57560934 -36.62928158
OS -4.59641194 -36.62096054
OS -4.62414874 -36.61402634
OS -4.65604606 -36.60847898
OS -4.69349074 -36.60709214
OE
OB -2.48841514 -36.60015794 H
OS -2.48841514 -36.60154478
OS -2.48980198 -36.60431846
OS -2.48980198 -36.60986582
OS -2.49257566 -36.61541318
OS -2.4939625 -36.62512106
OS -2.49673618 -36.63482894
OS -2.50228354 -36.65840522
OS -2.50921774 -36.68614202
OS -2.51892562 -36.7166525
OS -2.5286335 -36.74993666
OS -2.54111506 -36.78460766
OS -2.64512806 -37.06474934
OS -2.3206075 -37.06474934
OS -2.42045998 -36.80124974
OS -2.42045998 -36.7998629
OS -2.42184682 -36.79570238
OS -2.4246205 -36.78876818
OS -2.42739418 -36.78044714
OS -2.4315547 -36.77073926
OS -2.43571522 -36.7582577
OS -2.43987574 -36.7443893
OS -2.4454231 -36.7305209
OS -2.45651782 -36.69862358
OS -2.46761254 -36.66533942
OS -2.47870726 -36.63205526
OS -2.48841514 -36.60015794
OE
SE
S P 0
OB 35.73690338 -37.45999874 I
OS 35.61486146 -37.45999874
OS 35.61486146 -36.65701838
OS 35.33471978 -37.45999874
OS 35.2209989 -37.45999874
OS 34.9436309 -36.64314998
OS 34.9436309 -37.45999874
OS 34.82158898 -37.45999874
OS 34.82158898 -36.50030546
OS 35.01158606 -36.50030546
OS 35.23902782 -37.1812439
OS 35.23902782 -37.18263074
OS 35.24041466 -37.18540442
OS 35.2418015 -37.18956494
OS 35.24457518 -37.19649914
OS 35.25012254 -37.21314122
OS 35.25705674 -37.23394382
OS 35.26399094 -37.2575201
OS 35.27231198 -37.28109638
OS 35.27924618 -37.30328582
OS 35.28479354 -37.32270158
OS 35.28618038 -37.3199279
OS 35.28756722 -37.3129937
OS 35.29172774 -37.30051214
OS 35.2972751 -37.28387006
OS 35.3042093 -37.26168062
OS 35.31391718 -37.23533066
OS 35.32362506 -37.20482018
OS 35.33610662 -37.16876234
OS 35.56632206 -36.50030546
OS 35.73690338 -36.50030546
OS 35.73690338 -37.45999874
OE
OB 34.61356298 -37.05504146 I
OS 34.61356298 -37.0564283
OS 34.61356298 -37.06197566
OS 34.61356298 -37.06890986
OS 34.61356298 -37.07861774
OS 34.61217614 -37.0910993
OS 34.61217614 -37.1049677
OS 34.6107893 -37.12160978
OS 34.60940246 -37.13825186
OS 34.60524194 -37.17569654
OS 34.59969458 -37.21452806
OS 34.59137354 -37.25197274
OS 34.58582618 -37.27000166
OS 34.58027882 -37.28664374
OS 34.58027882 -37.28803058
OS 34.57889198 -37.29080426
OS 34.5761183 -37.29496478
OS 34.57334462 -37.30051214
OS 34.56502358 -37.31576738
OS 34.55254202 -37.33518314
OS 34.53589994 -37.35737258
OS 34.51648418 -37.37956202
OS 34.49152106 -37.4031383
OS 34.46101058 -37.4239409
OS 34.45962374 -37.4239409
OS 34.45685006 -37.42671458
OS 34.45268954 -37.42810142
OS 34.44575534 -37.43226194
OS 34.4374343 -37.43642246
OS 34.42633958 -37.44058298
OS 34.41524486 -37.4447435
OS 34.40137646 -37.45029086
OS 34.38612122 -37.45583822
OS 34.36947914 -37.45999874
OS 34.35145022 -37.46415926
OS 34.33064762 -37.46831978
OS 34.30984502 -37.47109346
OS 34.28765558 -37.47386714
OS 34.23772934 -37.47664082
OS 34.22524778 -37.47664082
OS 34.2155399 -37.47525398
OS 34.20444518 -37.47525398
OS 34.19057678 -37.47386714
OS 34.17532154 -37.4724803
OS 34.1600663 -37.47109346
OS 34.1253953 -37.4655461
OS 34.08795062 -37.45722506
OS 34.05189278 -37.44613034
OS 34.01722178 -37.4308751
OS 34.01583494 -37.4308751
OS 34.01306126 -37.42810142
OS 34.00890074 -37.42532774
OS 34.00335338 -37.42255406
OS 33.98809814 -37.41145934
OS 33.97006922 -37.3962041
OS 33.94926662 -37.37678834
OS 33.92985086 -37.3545989
OS 33.9104351 -37.3268621
OS 33.89517986 -37.29635162
OS 33.89517986 -37.29496478
OS 33.89379302 -37.2921911
OS 33.89240618 -37.28664374
OS 33.8896325 -37.27970954
OS 33.88685882 -37.2713885
OS 33.88408514 -37.26029378
OS 33.87992462 -37.24781222
OS 33.87715094 -37.23255698
OS 33.87437726 -37.2159149
OS 33.87021674 -37.19788598
OS 33.86744306 -37.17847022
OS 33.86466938 -37.15766762
OS 33.8618957 -37.13409134
OS 33.86050886 -37.10912822
OS 33.85912202 -37.08277826
OS 33.85912202 -37.05504146
OS 33.85912202 -36.50030546
OS 33.9867113 -36.50030546
OS 33.9867113 -37.05504146
OS 33.9867113 -37.0564283
OS 33.9867113 -37.06058882
OS 33.9867113 -37.06752302
OS 33.9867113 -37.07584406
OS 33.98809814 -37.08555194
OS 33.98809814 -37.0980335
OS 33.98948498 -37.12438346
OS 33.99225866 -37.15489394
OS 33.99641918 -37.18540442
OS 34.00196654 -37.21452806
OS 34.00474022 -37.22700962
OS 34.00890074 -37.23949118
OS 34.01028758 -37.24226486
OS 34.01306126 -37.24919906
OS 34.01999546 -37.25890694
OS 34.0283165 -37.27277534
OS 34.03802438 -37.28664374
OS 34.05189278 -37.30189898
OS 34.06853486 -37.31715422
OS 34.08795062 -37.32963578
OS 34.0907243 -37.33102262
OS 34.0976585 -37.33518314
OS 34.11014006 -37.33934366
OS 34.12678214 -37.34489102
OS 34.1461979 -37.35182522
OS 34.17116102 -37.35598574
OS 34.19751098 -37.36014626
OS 34.22663462 -37.3615331
OS 34.24050302 -37.3615331
OS 34.24882406 -37.36014626
OS 34.26130562 -37.36014626
OS 34.27378718 -37.35875942
OS 34.30429766 -37.35321206
OS 34.33758182 -37.34627786
OS 34.36947914 -37.33518314
OS 34.39998962 -37.3199279
OS 34.41385802 -37.31022002
OS 34.42633958 -37.2991253
OS 34.42772642 -37.29773846
OS 34.42911326 -37.29635162
OS 34.43188694 -37.2921911
OS 34.43604746 -37.28664374
OS 34.44020798 -37.2783227
OS 34.44575534 -37.27000166
OS 34.4513027 -37.2575201
OS 34.45685006 -37.24503854
OS 34.46239742 -37.2297833
OS 34.46655794 -37.21175438
OS 34.4721053 -37.19095178
OS 34.47626582 -37.16876234
OS 34.48042634 -37.14379922
OS 34.48320002 -37.11744926
OS 34.4859737 -37.08693878
OS 34.4859737 -37.05504146
OS 34.4859737 -36.50030546
OS 34.61356298 -36.50030546
OS 34.61356298 -37.05504146
OE
OB 33.64416182 -37.45999874 I
OS 33.51241202 -37.45999874
OS 33.01037594 -36.70694462
OS 33.01037594 -37.45999874
OS 32.88833402 -37.45999874
OS 32.88833402 -36.50030546
OS 33.01869698 -36.50030546
OS 33.5221199 -37.25474642
OS 33.5221199 -36.50030546
OS 33.64416182 -36.50030546
OS 33.64416182 -37.45999874
OE
OB 38.19022334 -36.5016923 I
OS 38.2027049 -36.5016923
OS 38.23182854 -36.50307914
OS 38.26233902 -36.50723966
OS 38.29562318 -36.51140018
OS 38.32613366 -36.51833438
OS 38.3413889 -36.5224949
OS 38.35387046 -36.52665542
OS 38.3552573 -36.52665542
OS 38.35664414 -36.52804226
OS 38.36496518 -36.53220278
OS 38.37744674 -36.53775014
OS 38.39270198 -36.54745802
OS 38.40934406 -36.55993958
OS 38.42737298 -36.57658166
OS 38.44401506 -36.59599742
OS 38.46065714 -36.61818686
OS 38.46065714 -36.6195737
OS 38.46204398 -36.62096054
OS 38.46759134 -36.62928158
OS 38.4731387 -36.64314998
OS 38.48145974 -36.6611789
OS 38.48839394 -36.6819815
OS 38.49532814 -36.70694462
OS 38.49948866 -36.73329458
OS 38.5008755 -36.76241822
OS 38.5008755 -36.76380506
OS 38.5008755 -36.76657874
OS 38.5008755 -36.7721261
OS 38.49948866 -36.7790603
OS 38.49948866 -36.78876818
OS 38.49810182 -36.79847606
OS 38.49255446 -36.82205234
OS 38.48423342 -36.84978914
OS 38.4731387 -36.87891278
OS 38.45649662 -36.90803642
OS 38.4454019 -36.92190482
OS 38.43430718 -36.93577322
OS 38.43292034 -36.93716006
OS 38.4315335 -36.9385469
OS 38.42737298 -36.94270742
OS 38.42182562 -36.94686794
OS 38.41489142 -36.9524153
OS 38.40657038 -36.95796266
OS 38.39547566 -36.96489686
OS 38.38438094 -36.9732179
OS 38.37051254 -36.9801521
OS 38.3552573 -36.9870863
OS 38.33861522 -36.99540734
OS 38.3205863 -37.00234154
OS 38.2997837 -37.0078889
OS 38.2789811 -37.0148231
OS 38.25540482 -37.01898362
OS 38.2304417 -37.02314414
OS 38.23321538 -37.02453098
OS 38.23876274 -37.02730466
OS 38.24708378 -37.03285202
OS 38.2581785 -37.03839938
OS 38.28314162 -37.05365462
OS 38.29562318 -37.0633625
OS 38.3067179 -37.07168354
OS 38.30949158 -37.07445722
OS 38.31642578 -37.08139142
OS 38.3275205 -37.09248614
OS 38.3413889 -37.10635454
OS 38.35664414 -37.1257703
OS 38.37467306 -37.1465729
OS 38.39270198 -37.17153602
OS 38.41211774 -37.19927282
OS 38.5771517 -37.45999874
OS 38.41905194 -37.45999874
OS 38.2928495 -37.26029378
OS 38.2928495 -37.25890694
OS 38.29007582 -37.25613326
OS 38.28730214 -37.25197274
OS 38.28314162 -37.24642538
OS 38.27343374 -37.23117014
OS 38.26095218 -37.21175438
OS 38.24569694 -37.19095178
OS 38.2304417 -37.16876234
OS 38.21518646 -37.14795974
OS 38.20131806 -37.12854398
OS 38.19993122 -37.12715714
OS 38.1957707 -37.12160978
OS 38.1888365 -37.11328874
OS 38.17912862 -37.10358086
OS 38.15832602 -37.08277826
OS 38.1472313 -37.07307038
OS 38.13613658 -37.06474934
OS 38.13474974 -37.0633625
OS 38.13197606 -37.06197566
OS 38.1264287 -37.05920198
OS 38.11810766 -37.05504146
OS 38.10978662 -37.05088094
OS 38.10007874 -37.04672042
OS 38.0778893 -37.03978622
OS 38.07650246 -37.03978622
OS 38.07372878 -37.03839938
OS 38.06818142 -37.03839938
OS 38.06124722 -37.03701254
OS 38.05153934 -37.0356257
OS 38.04044462 -37.0356257
OS 38.02518938 -37.03423886
OS 37.86154226 -37.03423886
OS 37.86154226 -37.45999874
OS 37.73395298 -37.45999874
OS 37.73395298 -36.50030546
OS 38.17912862 -36.50030546
OS 38.19022334 -36.5016923
OE
OB 37.53424802 -36.61402634 I
OS 36.96703046 -36.61402634
OS 36.96703046 -36.90664958
OS 37.49819018 -36.90664958
OS 37.49819018 -37.02037046
OS 36.96703046 -37.02037046
OS 36.96703046 -37.34627786
OS 37.55643746 -37.34627786
OS 37.55643746 -37.45999874
OS 36.83944118 -37.45999874
OS 36.83944118 -36.50030546
OS 37.53424802 -36.50030546
OS 37.53424802 -36.61402634
OE
OB 36.32492354 -36.5016923 I
OS 36.33601826 -36.5016923
OS 36.36098138 -36.50446598
OS 36.38871818 -36.50723966
OS 36.41784182 -36.51278702
OS 36.44696546 -36.51972122
OS 36.47331542 -36.5294291
OS 36.47470226 -36.5294291
OS 36.4760891 -36.53081594
OS 36.48441014 -36.53497646
OS 36.4968917 -36.54191066
OS 36.5107601 -36.55161854
OS 36.52740218 -36.5641001
OS 36.5454311 -36.57935534
OS 36.56207318 -36.5987711
OS 36.57732842 -36.6195737
OS 36.57871526 -36.62234738
OS 36.58287578 -36.63066842
OS 36.58980998 -36.64176314
OS 36.59674418 -36.65840522
OS 36.60367838 -36.67782098
OS 36.61061258 -36.69862358
OS 36.6147731 -36.72219986
OS 36.61615994 -36.74577614
OS 36.61615994 -36.74854982
OS 36.61615994 -36.75548402
OS 36.6147731 -36.76796558
OS 36.61199942 -36.78322082
OS 36.6078389 -36.80124974
OS 36.6009047 -36.8206655
OS 36.59258366 -36.84008126
OS 36.58148894 -36.86088386
OS 36.5801021 -36.86365754
OS 36.57594158 -36.8692049
OS 36.56762054 -36.88029962
OS 36.55652582 -36.89139434
OS 36.54265742 -36.90526274
OS 36.52601534 -36.92051798
OS 36.50521274 -36.93438638
OS 36.48163646 -36.94825478
OS 36.4830233 -36.94825478
OS 36.48579698 -36.94964162
OS 36.4899575 -36.95102846
OS 36.49550486 -36.95380214
OS 36.51214694 -36.9593495
OS 36.5315627 -36.96905738
OS 36.5523653 -36.98153894
OS 36.57594158 -36.99679418
OS 36.59674418 -37.0148231
OS 36.61615994 -37.03701254
OS 36.61754678 -37.03978622
OS 36.62309414 -37.04810726
OS 36.63141518 -37.06058882
OS 36.63973622 -37.0772309
OS 36.64805726 -37.09942034
OS 36.6563783 -37.12299662
OS 36.66192566 -37.15073342
OS 36.6633125 -37.1812439
OS 36.6633125 -37.18263074
OS 36.6633125 -37.18401758
OS 36.6633125 -37.19233862
OS 36.66192566 -37.20620702
OS 36.65915198 -37.2228491
OS 36.6563783 -37.24226486
OS 36.65083094 -37.26306746
OS 36.64389674 -37.2852569
OS 36.63418886 -37.30744634
OS 36.63280202 -37.31022002
OS 36.6286415 -37.31715422
OS 36.62309414 -37.3268621
OS 36.6147731 -37.3407305
OS 36.60367838 -37.3545989
OS 36.59258366 -37.36985414
OS 36.57871526 -37.38510938
OS 36.56346002 -37.39759094
OS 36.56207318 -37.39897778
OS 36.55652582 -37.4031383
OS 36.54681794 -37.40868566
OS 36.53433638 -37.41423302
OS 36.51908114 -37.42255406
OS 36.50105222 -37.4308751
OS 36.48163646 -37.4378093
OS 36.45806018 -37.4447435
OS 36.4552865 -37.4447435
OS 36.44696546 -37.44751718
OS 36.43309706 -37.44890402
OS 36.41506814 -37.4516777
OS 36.3928787 -37.45445138
OS 36.36652874 -37.45722506
OS 36.3374051 -37.4586119
OS 36.30412094 -37.45999874
OS 35.93799518 -37.45999874
OS 35.93799518 -36.50030546
OS 36.31521566 -36.50030546
OS 36.32492354 -36.5016923
OE
OB 32.3849111 -36.61402634 I
OS 32.06871158 -36.61402634
OS 32.06871158 -37.45999874
OS 31.9411223 -37.45999874
OS 31.9411223 -36.61402634
OS 31.62492278 -36.61402634
OS 31.62492278 -36.50030546
OS 32.3849111 -36.50030546
OS 32.3849111 -36.61402634
OE
OB 30.62639798 -37.45999874 I
OS 30.48216662 -37.45999874
OS 30.36983258 -37.16876234
OS 29.96764898 -37.16876234
OS 29.86363598 -37.45999874
OS 29.7291125 -37.45999874
OS 30.09523826 -36.50030546
OS 30.23392226 -36.50030546
OS 30.62639798 -37.45999874
OE
OB 29.3546657 -36.5016923 I
OS 29.37824198 -36.50307914
OS 29.4032051 -36.50446598
OS 29.42678138 -36.50723966
OS 29.44758398 -36.51001334
OS 29.45035766 -36.51001334
OS 29.46006554 -36.51278702
OS 29.4725471 -36.5155607
OS 29.48918918 -36.51972122
OS 29.5072181 -36.52665542
OS 29.52663386 -36.53497646
OS 29.54743646 -36.54468434
OS 29.56546538 -36.55577906
OS 29.56823906 -36.5571659
OS 29.57378642 -36.56132642
OS 29.58210746 -36.56964746
OS 29.59320218 -36.57935534
OS 29.60568374 -36.5918369
OS 29.6181653 -36.60847898
OS 29.6320337 -36.6265079
OS 29.64312842 -36.6473105
OS 29.64451526 -36.65008418
OS 29.64728894 -36.65701838
OS 29.6528363 -36.66949994
OS 29.65838366 -36.68614202
OS 29.66254418 -36.70555778
OS 29.66809154 -36.72774722
OS 29.67086522 -36.75271034
OS 29.67225206 -36.7790603
OS 29.67225206 -36.78044714
OS 29.67225206 -36.78460766
OS 29.67225206 -36.79015502
OS 29.67086522 -36.7998629
OS 29.66947838 -36.80957078
OS 29.66809154 -36.82205234
OS 29.66531786 -36.83592074
OS 29.66254418 -36.85117598
OS 29.6528363 -36.8830733
OS 29.64728894 -36.89971538
OS 29.6389679 -36.9177443
OS 29.62926002 -36.93577322
OS 29.61955214 -36.9524153
OS 29.60707058 -36.96905738
OS 29.59320218 -36.98569946
OS 29.59181534 -36.9870863
OS 29.58904166 -36.98985998
OS 29.58488114 -36.9940205
OS 29.57794694 -36.99818102
OS 29.5696259 -37.00511522
OS 29.55853118 -37.01204942
OS 29.54466278 -37.02037046
OS 29.52940754 -37.02730466
OS 29.51137862 -37.0356257
OS 29.49057602 -37.04394674
OS 29.46838658 -37.05088094
OS 29.44203662 -37.0564283
OS 29.41429982 -37.06197566
OS 29.38378934 -37.06613618
OS 29.34911834 -37.06890986
OS 29.3130605 -37.0702967
OS 29.06758982 -37.0702967
OS 29.06758982 -37.45999874
OS 28.94000054 -37.45999874
OS 28.94000054 -36.50030546
OS 29.3338631 -36.50030546
OS 29.3546657 -36.5016923
OE
OB 31.18668134 -36.5016923 I
OS 31.1991629 -36.5016923
OS 31.22828654 -36.50307914
OS 31.25879702 -36.50723966
OS 31.29208118 -36.51140018
OS 31.32259166 -36.51833438
OS 31.3378469 -36.5224949
OS 31.35032846 -36.52665542
OS 31.3517153 -36.52665542
OS 31.35310214 -36.52804226
OS 31.36142318 -36.53220278
OS 31.37390474 -36.53775014
OS 31.38915998 -36.54745802
OS 31.40580206 -36.55993958
OS 31.42383098 -36.57658166
OS 31.44047306 -36.59599742
OS 31.45711514 -36.61818686
OS 31.45711514 -36.6195737
OS 31.45850198 -36.62096054
OS 31.46404934 -36.62928158
OS 31.4695967 -36.64314998
OS 31.47791774 -36.6611789
OS 31.48485194 -36.6819815
OS 31.49178614 -36.70694462
OS 31.49594666 -36.73329458
OS 31.4973335 -36.76241822
OS 31.4973335 -36.76380506
OS 31.4973335 -36.76657874
OS 31.4973335 -36.7721261
OS 31.49594666 -36.7790603
OS 31.49594666 -36.78876818
OS 31.49455982 -36.79847606
OS 31.48901246 -36.82205234
OS 31.48069142 -36.84978914
OS 31.4695967 -36.87891278
OS 31.45295462 -36.90803642
OS 31.4418599 -36.92190482
OS 31.43076518 -36.93577322
OS 31.42937834 -36.93716006
OS 31.4279915 -36.9385469
OS 31.42383098 -36.94270742
OS 31.41828362 -36.94686794
OS 31.41134942 -36.9524153
OS 31.40302838 -36.95796266
OS 31.39193366 -36.96489686
OS 31.38083894 -36.9732179
OS 31.36697054 -36.9801521
OS 31.3517153 -36.9870863
OS 31.33507322 -36.99540734
OS 31.3170443 -37.00234154
OS 31.2962417 -37.0078889
OS 31.2754391 -37.0148231
OS 31.25186282 -37.01898362
OS 31.2268997 -37.02314414
OS 31.22967338 -37.02453098
OS 31.23522074 -37.02730466
OS 31.24354178 -37.03285202
OS 31.2546365 -37.03839938
OS 31.27959962 -37.05365462
OS 31.29208118 -37.0633625
OS 31.3031759 -37.07168354
OS 31.30594958 -37.07445722
OS 31.31288378 -37.08139142
OS 31.3239785 -37.09248614
OS 31.3378469 -37.10635454
OS 31.35310214 -37.1257703
OS 31.37113106 -37.1465729
OS 31.38915998 -37.17153602
OS 31.40857574 -37.19927282
OS 31.5736097 -37.45999874
OS 31.41550994 -37.45999874
OS 31.2893075 -37.26029378
OS 31.2893075 -37.25890694
OS 31.28653382 -37.25613326
OS 31.28376014 -37.25197274
OS 31.27959962 -37.24642538
OS 31.26989174 -37.23117014
OS 31.25741018 -37.21175438
OS 31.24215494 -37.19095178
OS 31.2268997 -37.16876234
OS 31.21164446 -37.14795974
OS 31.19777606 -37.12854398
OS 31.19638922 -37.12715714
OS 31.1922287 -37.12160978
OS 31.1852945 -37.11328874
OS 31.17558662 -37.10358086
OS 31.15478402 -37.08277826
OS 31.1436893 -37.07307038
OS 31.13259458 -37.06474934
OS 31.13120774 -37.0633625
OS 31.12843406 -37.06197566
OS 31.1228867 -37.05920198
OS 31.11456566 -37.05504146
OS 31.10624462 -37.05088094
OS 31.09653674 -37.04672042
OS 31.0743473 -37.03978622
OS 31.07296046 -37.03978622
OS 31.07018678 -37.03839938
OS 31.06463942 -37.03839938
OS 31.05770522 -37.03701254
OS 31.04799734 -37.0356257
OS 31.03690262 -37.0356257
OS 31.02164738 -37.03423886
OS 30.85800026 -37.03423886
OS 30.85800026 -37.45999874
OS 30.73041098 -37.45999874
OS 30.73041098 -36.50030546
OS 31.17558662 -36.50030546
OS 31.18668134 -36.5016923
OE
OB 38.16387338 -36.60709214 H
OS 37.86154226 -36.60709214
OS 37.86154226 -36.9246785
OS 38.1472313 -36.9246785
OS 38.16387338 -36.92329166
OS 38.18328914 -36.92190482
OS 38.20547858 -36.92051798
OS 38.22766802 -36.9177443
OS 38.24985746 -36.91358378
OS 38.26927322 -36.90803642
OS 38.2720469 -36.90664958
OS 38.27759426 -36.9038759
OS 38.2859153 -36.89971538
OS 38.29701002 -36.89416802
OS 38.30949158 -36.88584698
OS 38.32197314 -36.8761391
OS 38.3344547 -36.86365754
OS 38.34416258 -36.84978914
OS 38.34554942 -36.8484023
OS 38.3483231 -36.84285494
OS 38.35248362 -36.8345339
OS 38.35803098 -36.82343918
OS 38.3621915 -36.81095762
OS 38.36635202 -36.79708922
OS 38.3691257 -36.78044714
OS 38.37051254 -36.76380506
OS 38.37051254 -36.76241822
OS 38.37051254 -36.76103138
OS 38.3691257 -36.75271034
OS 38.36773886 -36.74022878
OS 38.36496518 -36.7235867
OS 38.35803098 -36.70694462
OS 38.34970994 -36.68752886
OS 38.33722838 -36.66949994
OS 38.3205863 -36.65147102
OS 38.31781262 -36.65008418
OS 38.31087842 -36.64453682
OS 38.2997837 -36.63760262
OS 38.28175478 -36.62928158
OS 38.26095218 -36.62096054
OS 38.23321538 -36.61402634
OS 38.20131806 -36.60847898
OS 38.16387338 -36.60709214
OE
OB 29.34218414 -36.61402634 H
OS 29.06758982 -36.61402634
OS 29.06758982 -36.95657582
OS 29.32554206 -36.95657582
OS 29.33524994 -36.95518898
OS 29.34495782 -36.95518898
OS 29.35605254 -36.95380214
OS 29.3824025 -36.95102846
OS 29.41152614 -36.9454811
OS 29.44064978 -36.93716006
OS 29.46699974 -36.92606534
OS 29.4794813 -36.91913114
OS 29.48918918 -36.9108101
OS 29.49196286 -36.90803642
OS 29.49751022 -36.90248906
OS 29.50583126 -36.89139434
OS 29.51553914 -36.87752594
OS 29.52524702 -36.85949702
OS 29.53356806 -36.83730758
OS 29.53911542 -36.81234446
OS 29.5418891 -36.78322082
OS 29.5418891 -36.78183398
OS 29.5418891 -36.78044714
OS 29.5418891 -36.77351294
OS 29.54050226 -36.76103138
OS 29.53772858 -36.74716298
OS 29.5349549 -36.73190774
OS 29.52940754 -36.71387882
OS 29.5210865 -36.69723674
OS 29.51137862 -36.68059466
OS 29.50999178 -36.67920782
OS 29.50583126 -36.67366046
OS 29.49889706 -36.66672626
OS 29.49057602 -36.65701838
OS 29.47809446 -36.6473105
OS 29.46422606 -36.63898946
OS 29.44897082 -36.63066842
OS 29.4309419 -36.62373422
OS 29.42955506 -36.62373422
OS 29.4240077 -36.62234738
OS 29.41568666 -36.62096054
OS 29.40459194 -36.61818686
OS 29.38794986 -36.61680002
OS 29.36714726 -36.61541318
OS 29.34218414 -36.61402634
OE
OB 30.16180658 -36.60015794 H
OS 30.16180658 -36.60154478
OS 30.16041974 -36.60431846
OS 30.16041974 -36.60986582
OS 30.15764606 -36.61541318
OS 30.15625922 -36.62512106
OS 30.15348554 -36.63482894
OS 30.14793818 -36.65840522
OS 30.14100398 -36.68614202
OS 30.1312961 -36.7166525
OS 30.12158822 -36.74993666
OS 30.10910666 -36.78460766
OS 30.00509366 -37.06474934
OS 30.32961422 -37.06474934
OS 30.22976174 -36.80124974
OS 30.22976174 -36.7998629
OS 30.2283749 -36.79570238
OS 30.22560122 -36.78876818
OS 30.22282754 -36.78044714
OS 30.21866702 -36.77073926
OS 30.2145065 -36.7582577
OS 30.21034598 -36.7443893
OS 30.20479862 -36.7305209
OS 30.1937039 -36.69862358
OS 30.18260918 -36.66533942
OS 30.17151446 -36.63205526
OS 30.16180658 -36.60015794
OE
OB 31.16033138 -36.60709214 H
OS 30.85800026 -36.60709214
OS 30.85800026 -36.9246785
OS 31.1436893 -36.9246785
OS 31.16033138 -36.92329166
OS 31.17974714 -36.92190482
OS 31.20193658 -36.92051798
OS 31.22412602 -36.9177443
OS 31.24631546 -36.91358378
OS 31.26573122 -36.90803642
OS 31.2685049 -36.90664958
OS 31.27405226 -36.9038759
OS 31.2823733 -36.89971538
OS 31.29346802 -36.89416802
OS 31.30594958 -36.88584698
OS 31.31843114 -36.8761391
OS 31.3309127 -36.86365754
OS 31.34062058 -36.84978914
OS 31.34200742 -36.8484023
OS 31.3447811 -36.84285494
OS 31.34894162 -36.8345339
OS 31.35448898 -36.82343918
OS 31.3586495 -36.81095762
OS 31.36281002 -36.79708922
OS 31.3655837 -36.78044714
OS 31.36697054 -36.76380506
OS 31.36697054 -36.76241822
OS 31.36697054 -36.76103138
OS 31.3655837 -36.75271034
OS 31.36419686 -36.74022878
OS 31.36142318 -36.7235867
OS 31.35448898 -36.70694462
OS 31.34616794 -36.68752886
OS 31.33368638 -36.66949994
OS 31.3170443 -36.65147102
OS 31.31427062 -36.65008418
OS 31.30733642 -36.64453682
OS 31.2962417 -36.63760262
OS 31.27821278 -36.62928158
OS 31.25741018 -36.62096054
OS 31.22967338 -36.61402634
OS 31.19777606 -36.60847898
OS 31.16033138 -36.60709214
OE
OB 36.29302622 -36.61402634 H
OS 36.06558446 -36.61402634
OS 36.06558446 -36.90248906
OS 36.30134726 -36.90248906
OS 36.31937618 -36.90110222
OS 36.33879194 -36.89971538
OS 36.3582077 -36.89832854
OS 36.37762346 -36.89555486
OS 36.3928787 -36.89278118
OS 36.39565238 -36.89139434
OS 36.40119974 -36.8900075
OS 36.40952078 -36.88584698
OS 36.4206155 -36.88029962
OS 36.43171022 -36.87475226
OS 36.44419178 -36.86643122
OS 36.45667334 -36.8553365
OS 36.46638122 -36.84424178
OS 36.46776806 -36.84285494
OS 36.47054174 -36.83869442
OS 36.47470226 -36.83037338
OS 36.47886278 -36.8206655
OS 36.4830233 -36.80957078
OS 36.48718382 -36.79570238
OS 36.4899575 -36.7790603
OS 36.49134434 -36.76103138
OS 36.49134434 -36.7582577
OS 36.49134434 -36.75271034
OS 36.4899575 -36.7443893
OS 36.48857066 -36.73329458
OS 36.48579698 -36.71942618
OS 36.48163646 -36.70555778
OS 36.4760891 -36.69168938
OS 36.46776806 -36.67782098
OS 36.46638122 -36.67643414
OS 36.46360754 -36.67227362
OS 36.45806018 -36.66533942
OS 36.45112598 -36.65840522
OS 36.4414181 -36.65008418
OS 36.43032338 -36.64176314
OS 36.41645498 -36.6334421
OS 36.40119974 -36.62789474
OS 36.3998129 -36.62789474
OS 36.3928787 -36.62512106
OS 36.38317082 -36.62373422
OS 36.36791558 -36.62096054
OS 36.34711298 -36.61818686
OS 36.3235367 -36.61680002
OS 36.29302622 -36.61402634
OE
OB 36.31798934 -37.01620994 H
OS 36.06558446 -37.01620994
OS 36.06558446 -37.34627786
OS 36.33879194 -37.34627786
OS 36.36791558 -37.34489102
OS 36.38039714 -37.34350418
OS 36.39149186 -37.34211734
OS 36.3928787 -37.34211734
OS 36.39842606 -37.3407305
OS 36.4067471 -37.33934366
OS 36.41645498 -37.33656998
OS 36.44003126 -37.32824894
OS 36.46360754 -37.31715422
OS 36.46499438 -37.31576738
OS 36.4691549 -37.3129937
OS 36.47470226 -37.30883318
OS 36.48163646 -37.30328582
OS 36.48857066 -37.29496478
OS 36.49827854 -37.28664374
OS 36.50521274 -37.27554902
OS 36.51353378 -37.26306746
OS 36.51492062 -37.26168062
OS 36.51630746 -37.2575201
OS 36.51908114 -37.24919906
OS 36.52324166 -37.23949118
OS 36.52740218 -37.22839646
OS 36.53017586 -37.21452806
OS 36.5315627 -37.19788598
OS 36.53294954 -37.1812439
OS 36.53294954 -37.17847022
OS 36.53294954 -37.17292286
OS 36.5315627 -37.16182814
OS 36.52878902 -37.14934658
OS 36.52601534 -37.13547818
OS 36.52046798 -37.12022294
OS 36.51353378 -37.1049677
OS 36.5038259 -37.08971246
OS 36.50243906 -37.08832562
OS 36.49827854 -37.08277826
OS 36.49273118 -37.07584406
OS 36.48441014 -37.06752302
OS 36.47331542 -37.05781514
OS 36.45944702 -37.04810726
OS 36.44419178 -37.03978622
OS 36.42616286 -37.03285202
OS 36.42338918 -37.03146518
OS 36.41784182 -37.03007834
OS 36.40536026 -37.02730466
OS 36.39010502 -37.02453098
OS 36.37068926 -37.0217573
OS 36.34711298 -37.01898362
OS 36.31798934 -37.01620994
OE
SE
S P 0
OB 40.9056459 -38.32112732 I
OS 40.92136342 -38.32205188
OS 40.9380055 -38.32297644
OS 40.95372302 -38.32482556
OS 40.96759142 -38.32667468
OS 40.96944054 -38.32667468
OS 40.97591246 -38.3285238
OS 40.9842335 -38.33037292
OS 40.99532822 -38.3331466
OS 41.0073475 -38.3377694
OS 41.02029134 -38.34331676
OS 41.03415974 -38.34978868
OS 41.04617902 -38.35718516
OS 41.04802814 -38.35810972
OS 41.05172638 -38.3608834
OS 41.05727374 -38.36643076
OS 41.06467022 -38.37290268
OS 41.07299126 -38.38122372
OS 41.0813123 -38.39231844
OS 41.0905579 -38.40433772
OS 41.09795438 -38.41820612
OS 41.09887894 -38.42005524
OS 41.10072806 -38.42467804
OS 41.1044263 -38.43299908
OS 41.10812454 -38.4440938
OS 41.11089822 -38.45703764
OS 41.11459646 -38.4718306
OS 41.11644558 -38.48847268
OS 41.11737014 -38.50603932
OS 41.11737014 -38.50696388
OS 41.11737014 -38.50973756
OS 41.11737014 -38.5134358
OS 41.11644558 -38.51990772
OS 41.11552102 -38.52637964
OS 41.11459646 -38.53470068
OS 41.11274734 -38.54394628
OS 41.11089822 -38.55411644
OS 41.1044263 -38.57538132
OS 41.10072806 -38.58647604
OS 41.0951807 -38.59849532
OS 41.08870878 -38.6105146
OS 41.08223686 -38.62160932
OS 41.07391582 -38.63270404
OS 41.06467022 -38.64379876
OS 41.06374566 -38.64472332
OS 41.06189654 -38.64657244
OS 41.05912286 -38.64934612
OS 41.05450006 -38.6521198
OS 41.0489527 -38.6567426
OS 41.04155622 -38.6613654
OS 41.03231062 -38.66691276
OS 41.02214046 -38.67153556
OS 41.01012118 -38.67708292
OS 40.99625278 -38.68263028
OS 40.98145982 -38.68725308
OS 40.96389318 -38.69095132
OS 40.94540198 -38.69464956
OS 40.92506166 -38.69742324
OS 40.90194766 -38.69927236
OS 40.8779091 -38.70019692
OS 40.71426198 -38.70019692
OS 40.71426198 -38.95999828
OS 40.62920246 -38.95999828
OS 40.62920246 -38.32020276
OS 40.8917775 -38.32020276
OS 40.9056459 -38.32112732
OE
OB 40.49791494 -38.98403684 I
OS 40.49791494 -38.9849614
OS 40.49791494 -38.98773508
OS 40.49791494 -38.99235788
OS 40.49791494 -38.99790524
OS 40.49699038 -39.00530172
OS 40.49699038 -39.0126982
OS 40.49514126 -39.0311894
OS 40.49236758 -39.05060516
OS 40.48866934 -39.07094548
OS 40.48312198 -39.08851212
OS 40.47942374 -39.09683316
OS 40.4757255 -39.10330508
OS 40.4757255 -39.10422964
OS 40.47480094 -39.1051542
OS 40.47017814 -39.109777
OS 40.46278166 -39.11717348
OS 40.45353606 -39.12549452
OS 40.44059222 -39.13381556
OS 40.42395014 -39.14028748
OS 40.40453438 -39.14583484
OS 40.39343966 -39.1467594
OS 40.38142038 -39.14768396
OS 40.37587302 -39.14768396
OS 40.37032566 -39.1467594
OS 40.36200462 -39.1467594
OS 40.35275902 -39.14583484
OS 40.34258886 -39.14398572
OS 40.32039942 -39.13843836
OS 40.33519238 -39.07187004
OS 40.33611694 -39.07187004
OS 40.33889062 -39.0727946
OS 40.34351342 -39.07371916
OS 40.34813622 -39.07464372
OS 40.3601555 -39.0774174
OS 40.36570286 -39.07834196
OS 40.37494846 -39.07834196
OS 40.37957126 -39.0774174
OS 40.38511862 -39.07649284
OS 40.39066598 -39.07464372
OS 40.39621334 -39.07094548
OS 40.40268526 -39.06724724
OS 40.40730806 -39.06169988
OS 40.40823262 -39.06077532
OS 40.40915718 -39.05800164
OS 40.4110063 -39.05337884
OS 40.41377998 -39.04598236
OS 40.4156291 -39.0358122
OS 40.41655366 -39.02841572
OS 40.41747822 -39.0219438
OS 40.41840278 -39.01362276
OS 40.41840278 -39.0034526
OS 40.41932734 -38.99328244
OS 40.41932734 -38.98218772
OS 40.41932734 -38.49586916
OS 40.49791494 -38.49586916
OS 40.49791494 -38.98403684
OE
OB 41.51770462 -38.3100326 I
OS 41.52602566 -38.31095716
OS 41.53619582 -38.31188172
OS 41.54636598 -38.31280628
OS 41.55838526 -38.31557996
OS 41.58334838 -38.32112732
OS 41.61108518 -38.32944836
OS 41.62495358 -38.33499572
OS 41.63789742 -38.34146764
OS 41.65084126 -38.34978868
OS 41.6637851 -38.35810972
OS 41.66470966 -38.35903428
OS 41.66655878 -38.35995884
OS 41.67025702 -38.36273252
OS 41.67487982 -38.36735532
OS 41.67950262 -38.37197812
OS 41.68597454 -38.37845004
OS 41.69244646 -38.38584652
OS 41.69984294 -38.393243
OS 41.70723942 -38.4024886
OS 41.7146359 -38.41358332
OS 41.72295694 -38.42467804
OS 41.73035342 -38.43669732
OS 41.73682534 -38.45056572
OS 41.74422182 -38.46443412
OS 41.74976918 -38.47922708
OS 41.75531654 -38.49586916
OS 41.67210614 -38.51528492
OS 41.67210614 -38.51436036
OS 41.67118158 -38.51251124
OS 41.66933246 -38.508813
OS 41.66748334 -38.5041902
OS 41.66563422 -38.49864284
OS 41.66286054 -38.49124636
OS 41.65546406 -38.4764534
OS 41.64621846 -38.45981132
OS 41.63512374 -38.44316924
OS 41.62125534 -38.42745172
OS 41.60646238 -38.41358332
OS 41.60461326 -38.4117342
OS 41.5990659 -38.40803596
OS 41.5898203 -38.40341316
OS 41.57780102 -38.39694124
OS 41.5620835 -38.39139388
OS 41.54451686 -38.38584652
OS 41.52325198 -38.38214828
OS 41.50013798 -38.38122372
OS 41.4927415 -38.38122372
OS 41.4881187 -38.38214828
OS 41.48164678 -38.38214828
OS 41.4742503 -38.38307284
OS 41.45668366 -38.38584652
OS 41.4372679 -38.38954476
OS 41.41692758 -38.39601668
OS 41.3956627 -38.40526228
OS 41.37624694 -38.41728156
OS 41.37532238 -38.41728156
OS 41.37439782 -38.41913068
OS 41.3679259 -38.42375348
OS 41.35960486 -38.43114996
OS 41.3494347 -38.44224468
OS 41.33741542 -38.45611308
OS 41.3263207 -38.4718306
OS 41.31615054 -38.49124636
OS 41.30690494 -38.51251124
OS 41.30690494 -38.5134358
OS 41.30598038 -38.51528492
OS 41.30505582 -38.5180586
OS 41.30413126 -38.5226814
OS 41.30228214 -38.52822876
OS 41.30043302 -38.53470068
OS 41.29765934 -38.5504182
OS 41.2939611 -38.5689094
OS 41.29026286 -38.58924972
OS 41.28841374 -38.61143916
OS 41.28748918 -38.63547772
OS 41.28748918 -38.63640228
OS 41.28748918 -38.63917596
OS 41.28748918 -38.64379876
OS 41.28748918 -38.64934612
OS 41.28841374 -38.65581804
OS 41.28841374 -38.66413908
OS 41.2893383 -38.67338468
OS 41.29026286 -38.68355484
OS 41.29303654 -38.70574428
OS 41.29765934 -38.72978284
OS 41.3032067 -38.7538214
OS 41.31060318 -38.77785996
OS 41.31060318 -38.77878452
OS 41.31152774 -38.78063364
OS 41.31337686 -38.78340732
OS 41.31522598 -38.78803012
OS 41.32077334 -38.79912484
OS 41.32909438 -38.81206868
OS 41.33926454 -38.82686164
OS 41.35220838 -38.84257916
OS 41.36700134 -38.85644756
OS 41.38456798 -38.8693914
OS 41.38549254 -38.8693914
OS 41.38734166 -38.87031596
OS 41.39011534 -38.87216508
OS 41.39381358 -38.8740142
OS 41.39843638 -38.87586332
OS 41.40398374 -38.878637
OS 41.41692758 -38.88418436
OS 41.43356966 -38.88973172
OS 41.45206086 -38.89435452
OS 41.47240118 -38.89805276
OS 41.49366606 -38.89897732
OS 41.50013798 -38.89897732
OS 41.50568534 -38.89805276
OS 41.51215726 -38.89805276
OS 41.51862918 -38.8971282
OS 41.53527126 -38.89342996
OS 41.55468702 -38.88880716
OS 41.57410278 -38.88141068
OS 41.5944431 -38.87124052
OS 41.60461326 -38.86569316
OS 41.61385886 -38.85829668
OS 41.61478342 -38.85737212
OS 41.61570798 -38.85644756
OS 41.61848166 -38.85367388
OS 41.6221799 -38.8509002
OS 41.62587814 -38.8462774
OS 41.63050094 -38.84073004
OS 41.6360483 -38.83518268
OS 41.6406711 -38.8277862
OS 41.64621846 -38.81946516
OS 41.65269038 -38.81021956
OS 41.65823774 -38.80097396
OS 41.6637851 -38.78987924
OS 41.6684079 -38.77785996
OS 41.6730307 -38.76491612
OS 41.6776535 -38.75104772
OS 41.68135174 -38.73625476
OS 41.76641126 -38.75751964
OS 41.76641126 -38.7584442
OS 41.7654867 -38.76214244
OS 41.76363758 -38.7676898
OS 41.7608639 -38.77508628
OS 41.75809022 -38.78340732
OS 41.75439198 -38.79357748
OS 41.74976918 -38.8046722
OS 41.74422182 -38.81669148
OS 41.73127798 -38.84257916
OS 41.7146359 -38.86846684
OS 41.70446574 -38.88141068
OS 41.69429558 -38.89435452
OS 41.68320086 -38.90544924
OS 41.67025702 -38.91654396
OS 41.66933246 -38.91746852
OS 41.66748334 -38.91931764
OS 41.66286054 -38.92116676
OS 41.65823774 -38.924865
OS 41.65084126 -38.9294878
OS 41.64344478 -38.9341106
OS 41.63327462 -38.9387334
OS 41.62310446 -38.9433562
OS 41.61108518 -38.94890356
OS 41.59814134 -38.95352636
OS 41.58427294 -38.95814916
OS 41.56947998 -38.96277196
OS 41.55376246 -38.9664702
OS 41.53712038 -38.96831932
OS 41.51955374 -38.97016844
OS 41.50106254 -38.971093
OS 41.49089238 -38.971093
OS 41.4834959 -38.97016844
OS 41.47517486 -38.97016844
OS 41.4650047 -38.96924388
OS 41.45390998 -38.96739476
OS 41.44096614 -38.96554564
OS 41.4141539 -38.96092284
OS 41.3864171 -38.95352636
OS 41.3586803 -38.9433562
OS 41.34573646 -38.93688428
OS 41.33279262 -38.9294878
OS 41.33186806 -38.92856324
OS 41.33001894 -38.92763868
OS 41.3263207 -38.924865
OS 41.32262246 -38.92116676
OS 41.3170751 -38.91746852
OS 41.31060318 -38.91192116
OS 41.3032067 -38.90544924
OS 41.29581022 -38.89805276
OS 41.28841374 -38.88973172
OS 41.2800927 -38.88141068
OS 41.26345062 -38.8601458
OS 41.2477331 -38.83518268
OS 41.2338647 -38.80744588
OS 41.2338647 -38.80652132
OS 41.23201558 -38.80374764
OS 41.23109102 -38.79912484
OS 41.22831734 -38.79357748
OS 41.22646822 -38.786181
OS 41.22369454 -38.7769354
OS 41.2199963 -38.76676524
OS 41.21722262 -38.75567052
OS 41.21444894 -38.74365124
OS 41.2107507 -38.72978284
OS 41.2061279 -38.70112148
OS 41.20242966 -38.66876188
OS 41.20058054 -38.63547772
OS 41.20058054 -38.63455316
OS 41.20058054 -38.63085492
OS 41.20058054 -38.62530756
OS 41.2015051 -38.61883564
OS 41.2015051 -38.60959004
OS 41.20242966 -38.60034444
OS 41.20335422 -38.58832516
OS 41.20520334 -38.57630588
OS 41.20982614 -38.54949364
OS 41.21629806 -38.51990772
OS 41.22554366 -38.4903218
OS 41.2384875 -38.46166044
OS 41.23941206 -38.46073588
OS 41.24033662 -38.4579622
OS 41.24218574 -38.45426396
OS 41.24588398 -38.44964116
OS 41.24958222 -38.44316924
OS 41.25420502 -38.43577276
OS 41.2662243 -38.41913068
OS 41.28194182 -38.40063948
OS 41.30043302 -38.38214828
OS 41.3216979 -38.36365708
OS 41.34666102 -38.34793956
OS 41.34758558 -38.347015
OS 41.35035926 -38.34609044
OS 41.3540575 -38.34424132
OS 41.3586803 -38.34146764
OS 41.36607678 -38.33869396
OS 41.37347326 -38.33592028
OS 41.38271886 -38.33222204
OS 41.39288902 -38.3285238
OS 41.40398374 -38.32482556
OS 41.41600302 -38.32112732
OS 41.4418907 -38.31557996
OS 41.47147662 -38.31095716
OS 41.5019871 -38.30910804
OS 41.5112327 -38.30910804
OS 41.51770462 -38.3100326
OE
OB 42.90454462 -39.1375138 I
OS 42.38401734 -39.1375138
OS 42.38401734 -39.08111564
OS 42.90454462 -39.08111564
OS 42.90454462 -39.1375138
OE
OB 42.12514054 -38.32112732 I
OS 42.13253702 -38.32112732
OS 42.1491791 -38.32297644
OS 42.1676703 -38.32482556
OS 42.18708606 -38.3285238
OS 42.20650182 -38.3331466
OS 42.22406846 -38.33961852
OS 42.22499302 -38.33961852
OS 42.22591758 -38.34054308
OS 42.23146494 -38.34331676
OS 42.23978598 -38.34793956
OS 42.24903158 -38.35441148
OS 42.2601263 -38.36273252
OS 42.27214558 -38.37290268
OS 42.2832403 -38.38584652
OS 42.29341046 -38.39971492
OS 42.29433502 -38.40156404
OS 42.2971087 -38.4071114
OS 42.3017315 -38.41450788
OS 42.3063543 -38.4256026
OS 42.3109771 -38.43854644
OS 42.3155999 -38.45241484
OS 42.31837358 -38.46813236
OS 42.31929814 -38.48384988
OS 42.31929814 -38.485699
OS 42.31929814 -38.4903218
OS 42.31837358 -38.49864284
OS 42.31652446 -38.508813
OS 42.31375078 -38.52083228
OS 42.30912798 -38.53377612
OS 42.30358062 -38.54671996
OS 42.29618414 -38.56058836
OS 42.29525958 -38.56243748
OS 42.2924859 -38.56613572
OS 42.28693854 -38.5735322
OS 42.27954206 -38.58092868
OS 42.27029646 -38.59017428
OS 42.25920174 -38.60034444
OS 42.24533334 -38.60959004
OS 42.22961582 -38.61883564
OS 42.23054038 -38.61883564
OS 42.2323895 -38.6197602
OS 42.23516318 -38.62068476
OS 42.23886142 -38.62253388
OS 42.24995614 -38.62623212
OS 42.26289998 -38.63270404
OS 42.27676838 -38.64102508
OS 42.2924859 -38.65119524
OS 42.3063543 -38.66321452
OS 42.31929814 -38.67800748
OS 42.3202227 -38.6798566
OS 42.32392094 -38.68540396
OS 42.3294683 -38.693725
OS 42.33501566 -38.70481972
OS 42.34056302 -38.71961268
OS 42.34611038 -38.7353302
OS 42.34980862 -38.7538214
OS 42.35073318 -38.77416172
OS 42.35073318 -38.77508628
OS 42.35073318 -38.77601084
OS 42.35073318 -38.7815582
OS 42.34980862 -38.7908038
OS 42.3479595 -38.80189852
OS 42.34611038 -38.81484236
OS 42.34241214 -38.82871076
OS 42.33778934 -38.84350372
OS 42.33131742 -38.85829668
OS 42.33039286 -38.8601458
OS 42.32761918 -38.8647686
OS 42.32392094 -38.87124052
OS 42.31837358 -38.88048612
OS 42.3109771 -38.88973172
OS 42.30358062 -38.89990188
OS 42.29433502 -38.91007204
OS 42.28416486 -38.91839308
OS 42.2832403 -38.91931764
OS 42.27954206 -38.92209132
OS 42.27307014 -38.92578956
OS 42.2647491 -38.9294878
OS 42.25457894 -38.93503516
OS 42.24255966 -38.94058252
OS 42.22961582 -38.94520532
OS 42.2138983 -38.94982812
OS 42.21204918 -38.94982812
OS 42.20650182 -38.95167724
OS 42.19725622 -38.9526018
OS 42.18523694 -38.95445092
OS 42.17044398 -38.95630004
OS 42.15287734 -38.95814916
OS 42.13346158 -38.95907372
OS 42.11127214 -38.95999828
OS 41.8671883 -38.95999828
OS 41.8671883 -38.32020276
OS 42.11866862 -38.32020276
OS 42.12514054 -38.32112732
OE
OB 40.30745558 -38.48662356 I
OS 40.31762574 -38.48847268
OS 40.32964502 -38.49217092
OS 40.34258886 -38.49679372
OS 40.35738182 -38.50326564
OS 40.37309934 -38.51158668
OS 40.34443798 -38.58370236
OS 40.34351342 -38.5827778
OS 40.33981518 -38.58092868
OS 40.33426782 -38.578155
OS 40.32687134 -38.57538132
OS 40.3185503 -38.57260764
OS 40.30838014 -38.56983396
OS 40.29820998 -38.56798484
OS 40.28803982 -38.56706028
OS 40.28341702 -38.56706028
OS 40.27879422 -38.56798484
OS 40.2723223 -38.5689094
OS 40.26585038 -38.57075852
OS 40.25752934 -38.5735322
OS 40.2492083 -38.57723044
OS 40.24181182 -38.5827778
OS 40.24088726 -38.58370236
OS 40.23811358 -38.58555148
OS 40.2353399 -38.58924972
OS 40.2307171 -38.59387252
OS 40.2260943 -38.60034444
OS 40.2214715 -38.60774092
OS 40.2168487 -38.61606196
OS 40.21315046 -38.62623212
OS 40.2122259 -38.62808124
OS 40.21130134 -38.6336286
OS 40.20945222 -38.64194964
OS 40.20667854 -38.65304436
OS 40.20390486 -38.66691276
OS 40.20205574 -38.68263028
OS 40.20113118 -38.69927236
OS 40.20020662 -38.71776356
OS 40.20020662 -38.95999828
OS 40.12161902 -38.95999828
OS 40.12161902 -38.49586916
OS 40.19281014 -38.49586916
OS 40.19281014 -38.56613572
OS 40.1937347 -38.56521116
OS 40.19743294 -38.55873924
OS 40.20205574 -38.5504182
OS 40.20945222 -38.54024804
OS 40.2168487 -38.53007788
OS 40.22516974 -38.51898316
OS 40.23349078 -38.50973756
OS 40.24181182 -38.50234108
OS 40.24273638 -38.50141652
OS 40.24551006 -38.4995674
OS 40.25105742 -38.49679372
OS 40.25660478 -38.49402004
OS 40.26400126 -38.49124636
OS 40.27324686 -38.48847268
OS 40.28249246 -38.48662356
OS 40.29266262 -38.485699
OS 40.29913454 -38.485699
OS 40.30745558 -38.48662356
OE
OB 39.48829542 -38.95999828 I
OS 39.3986131 -38.95999828
OS 39.3986131 -38.87031596
OS 39.48829542 -38.87031596
OS 39.48829542 -38.95999828
OE
OB 38.6404739 -38.95999828 I
OS 38.55171614 -38.95999828
OS 38.30393406 -38.32020276
OS 38.39639006 -38.32020276
OS 38.56281086 -38.78525644
OS 38.56281086 -38.786181
OS 38.56373542 -38.78803012
OS 38.56465998 -38.7908038
OS 38.5665091 -38.79450204
OS 38.56743366 -38.8000494
OS 38.56928278 -38.80559676
OS 38.57390558 -38.81946516
OS 38.57945294 -38.83518268
OS 38.5850003 -38.85274932
OS 38.59609502 -38.88973172
OS 38.59609502 -38.88880716
OS 38.59701958 -38.88695804
OS 38.59794414 -38.88418436
OS 38.5988687 -38.88048612
OS 38.60164238 -38.87031596
OS 38.60626518 -38.85644756
OS 38.61088798 -38.84073004
OS 38.61643534 -38.8231634
OS 38.62290726 -38.8046722
OS 38.63030374 -38.78525644
OS 38.80412102 -38.32020276
OS 38.8901051 -38.32020276
OS 38.6404739 -38.95999828
OE
OB 39.27564662 -38.42745172 I
OS 39.25438174 -38.54671996
OS 39.20538006 -38.54671996
OS 39.1859643 -38.42745172
OS 39.1859643 -38.32020276
OS 39.27564662 -38.32020276
OS 39.27564662 -38.42745172
OE
OB 40.49791494 -38.4117342 I
OS 40.41932734 -38.4117342
OS 40.41932734 -38.32020276
OS 40.49791494 -38.32020276
OS 40.49791494 -38.4117342
OE
OB 39.84517558 -38.48662356 I
OS 39.8516475 -38.48754812
OS 39.8655159 -38.48939724
OS 39.88215798 -38.49309548
OS 39.89972462 -38.49864284
OS 39.91729126 -38.50696388
OS 39.9348579 -38.51713404
OS 39.93578246 -38.51713404
OS 39.93670702 -38.51898316
OS 39.94225438 -38.5226814
OS 39.95057542 -38.53007788
OS 39.96074558 -38.53932348
OS 39.9718403 -38.55134276
OS 39.98293502 -38.56613572
OS 39.99402974 -38.58370236
OS 40.00327534 -38.60311812
OS 40.00327534 -38.60404268
OS 40.0041999 -38.6058918
OS 40.00512446 -38.60866548
OS 40.00697358 -38.61236372
OS 40.0088227 -38.61791108
OS 40.01067182 -38.624383
OS 40.01529462 -38.63917596
OS 40.01991742 -38.65766716
OS 40.02361566 -38.67800748
OS 40.02638934 -38.70112148
OS 40.0273139 -38.72516004
OS 40.0273139 -38.7260846
OS 40.0273139 -38.72793372
OS 40.0273139 -38.73163196
OS 40.0273139 -38.73717932
OS 40.02638934 -38.74365124
OS 40.02638934 -38.75104772
OS 40.02454022 -38.7676898
OS 40.02084198 -38.78803012
OS 40.01621918 -38.809295
OS 40.00974726 -38.83148444
OS 40.00142622 -38.85367388
OS 40.00142622 -38.85459844
OS 40.00050166 -38.85644756
OS 39.99865254 -38.85922124
OS 39.99680342 -38.86291948
OS 39.9903315 -38.87308964
OS 39.98201046 -38.88603348
OS 39.9718403 -38.89990188
OS 39.95889646 -38.91377028
OS 39.9441035 -38.92763868
OS 39.92653686 -38.94058252
OS 39.9256123 -38.94058252
OS 39.92468774 -38.94150708
OS 39.92191406 -38.9433562
OS 39.91821582 -38.94520532
OS 39.90897022 -38.94982812
OS 39.89602638 -38.95537548
OS 39.88030886 -38.96092284
OS 39.86366678 -38.96554564
OS 39.84425102 -38.96924388
OS 39.82483526 -38.97016844
OS 39.81836334 -38.97016844
OS 39.81096686 -38.96924388
OS 39.80172126 -38.96831932
OS 39.79062654 -38.9664702
OS 39.77860726 -38.96369652
OS 39.76658798 -38.95999828
OS 39.7545687 -38.95445092
OS 39.75364414 -38.95352636
OS 39.74902134 -38.95167724
OS 39.74347398 -38.947979
OS 39.7360775 -38.94243164
OS 39.72868102 -38.93688428
OS 39.71943542 -38.9294878
OS 39.71111438 -38.92116676
OS 39.7037179 -38.91192116
OS 39.7037179 -39.1375138
OS 39.6251303 -39.1375138
OS 39.6251303 -38.49586916
OS 39.69632142 -38.49586916
OS 39.69632142 -38.55689012
OS 39.69724598 -38.555041
OS 39.70094422 -38.55134276
OS 39.70556702 -38.54487084
OS 39.7129635 -38.53747436
OS 39.72128454 -38.52822876
OS 39.73053014 -38.51990772
OS 39.74162486 -38.51158668
OS 39.75271958 -38.5041902
OS 39.7545687 -38.50326564
OS 39.75826694 -38.50141652
OS 39.76566342 -38.49864284
OS 39.77490902 -38.4949446
OS 39.78600374 -38.49124636
OS 39.79894758 -38.48847268
OS 39.81374054 -38.48662356
OS 39.83038262 -38.485699
OS 39.84055278 -38.485699
OS 39.84517558 -38.48662356
OE
OB 44.92193454 -38.40988508 I
OS 44.84334694 -38.40988508
OS 44.84334694 -38.32020276
OS 44.92193454 -38.32020276
OS 44.92193454 -38.40988508
OE
OB 45.24553054 -38.48662356 I
OS 45.25385158 -38.48754812
OS 45.26309718 -38.48939724
OS 45.27326734 -38.49124636
OS 45.28528662 -38.49309548
OS 45.31024974 -38.50141652
OS 45.32319358 -38.50603932
OS 45.33613742 -38.51251124
OS 45.34908126 -38.51898316
OS 45.3620251 -38.52822876
OS 45.37404438 -38.53747436
OS 45.38606366 -38.54856908
OS 45.38698822 -38.54949364
OS 45.38883734 -38.55134276
OS 45.39161102 -38.555041
OS 45.39530926 -38.5596638
OS 45.39993206 -38.56613572
OS 45.40547942 -38.57445676
OS 45.41102678 -38.58370236
OS 45.41657414 -38.59387252
OS 45.4221215 -38.60496724
OS 45.42766886 -38.61883564
OS 45.43321622 -38.63270404
OS 45.43783902 -38.64842156
OS 45.44153726 -38.66506364
OS 45.44431094 -38.68263028
OS 45.44616006 -38.70112148
OS 45.44708462 -38.7214618
OS 45.44708462 -38.72238636
OS 45.44708462 -38.72516004
OS 45.44708462 -38.72978284
OS 45.44708462 -38.73625476
OS 45.44616006 -38.74365124
OS 45.4452355 -38.75289684
OS 45.4452355 -38.76214244
OS 45.44338638 -38.7723126
OS 45.4406127 -38.7954266
OS 45.43506534 -38.8185406
OS 45.42859342 -38.8416546
OS 45.41934782 -38.86291948
OS 45.41934782 -38.86384404
OS 45.41842326 -38.8647686
OS 45.41657414 -38.86754228
OS 45.41472502 -38.87124052
OS 45.4082531 -38.88048612
OS 45.39993206 -38.89158084
OS 45.38883734 -38.90452468
OS 45.37496894 -38.91746852
OS 45.35925142 -38.93041236
OS 45.34076022 -38.94243164
OS 45.33983566 -38.94243164
OS 45.3389111 -38.9433562
OS 45.33613742 -38.94520532
OS 45.33151462 -38.94705444
OS 45.32689182 -38.94890356
OS 45.32134446 -38.95075268
OS 45.30747606 -38.95630004
OS 45.29175854 -38.96092284
OS 45.27234278 -38.96554564
OS 45.25200246 -38.96924388
OS 45.22981302 -38.97016844
OS 45.22056742 -38.97016844
OS 45.21317094 -38.96924388
OS 45.2048499 -38.96831932
OS 45.1956043 -38.9664702
OS 45.18450958 -38.96462108
OS 45.17341486 -38.96277196
OS 45.14845174 -38.95537548
OS 45.13458334 -38.94982812
OS 45.1216395 -38.94428076
OS 45.10869566 -38.93688428
OS 45.09575182 -38.92856324
OS 45.08373254 -38.91931764
OS 45.07171326 -38.90822292
OS 45.0707887 -38.90729836
OS 45.06893958 -38.90544924
OS 45.0661659 -38.901751
OS 45.06246766 -38.89620364
OS 45.05784486 -38.88973172
OS 45.05322206 -38.88233524
OS 45.0476747 -38.87308964
OS 45.04212734 -38.86199492
OS 45.03657998 -38.84997564
OS 45.03103262 -38.83610724
OS 45.02640982 -38.82131428
OS 45.02178702 -38.80559676
OS 45.01808878 -38.78803012
OS 45.0153151 -38.76953892
OS 45.01346598 -38.7491986
OS 45.01254142 -38.72793372
OS 45.01254142 -38.7260846
OS 45.01254142 -38.72238636
OS 45.01346598 -38.71591444
OS 45.01346598 -38.70666884
OS 45.01439054 -38.69649868
OS 45.01623966 -38.68355484
OS 45.01808878 -38.670611
OS 45.02178702 -38.65581804
OS 45.02548526 -38.64102508
OS 45.03010806 -38.62530756
OS 45.03565542 -38.60866548
OS 45.0430519 -38.59294796
OS 45.05044838 -38.578155
OS 45.06061854 -38.56336204
OS 45.0707887 -38.54949364
OS 45.08373254 -38.53747436
OS 45.0846571 -38.5365498
OS 45.08650622 -38.53562524
OS 45.09020446 -38.53285156
OS 45.09482726 -38.52915332
OS 45.10037462 -38.52545508
OS 45.1077711 -38.52083228
OS 45.11516758 -38.51620948
OS 45.12441318 -38.51158668
OS 45.13458334 -38.50696388
OS 45.14567806 -38.50234108
OS 45.17064118 -38.49402004
OS 45.19930254 -38.48754812
OS 45.2140955 -38.48662356
OS 45.22981302 -38.485699
OS 45.23905862 -38.485699
OS 45.24553054 -38.48662356
OE
OB 44.92193454 -38.95999828 I
OS 44.84334694 -38.95999828
OS 44.84334694 -38.49586916
OS 44.92193454 -38.49586916
OS 44.92193454 -38.95999828
OE
OB 46.10722046 -38.42745172 I
OS 46.08595558 -38.54671996
OS 46.0369539 -38.54671996
OS 46.01753814 -38.42745172
OS 46.01753814 -38.32020276
OS 46.10722046 -38.32020276
OS 46.10722046 -38.42745172
OE
OB 45.77160518 -38.48662356 I
OS 45.78177534 -38.48754812
OS 45.79379462 -38.48939724
OS 45.80673846 -38.49217092
OS 45.82060686 -38.49586916
OS 45.8335507 -38.50141652
OS 45.83539982 -38.50234108
OS 45.83909806 -38.5041902
OS 45.84556998 -38.50696388
OS 45.85296646 -38.51158668
OS 45.86221206 -38.51713404
OS 45.8705331 -38.52453052
OS 45.87885414 -38.531927
OS 45.88625062 -38.5411726
OS 45.88717518 -38.54209716
OS 45.8890243 -38.5457954
OS 45.89179798 -38.5504182
OS 45.89642078 -38.55689012
OS 45.90011902 -38.56613572
OS 45.90381726 -38.57538132
OS 45.90844006 -38.58647604
OS 45.91121374 -38.59849532
OS 45.91121374 -38.59941988
OS 45.9121383 -38.60311812
OS 45.91306286 -38.60866548
OS 45.91398742 -38.61606196
OS 45.91398742 -38.62715668
OS 45.91491198 -38.64010052
OS 45.91583654 -38.65581804
OS 45.91583654 -38.6752338
OS 45.91583654 -38.95999828
OS 45.83724894 -38.95999828
OS 45.83724894 -38.67893204
OS 45.83724894 -38.67800748
OS 45.83724894 -38.67708292
OS 45.83724894 -38.670611
OS 45.83724894 -38.66228996
OS 45.83632438 -38.6521198
OS 45.83539982 -38.64010052
OS 45.8335507 -38.62808124
OS 45.83077702 -38.61698652
OS 45.82800334 -38.60681636
OS 45.82800334 -38.6058918
OS 45.82615422 -38.60311812
OS 45.82338054 -38.59849532
OS 45.82060686 -38.59294796
OS 45.81598406 -38.5874006
OS 45.8104367 -38.58092868
OS 45.80304022 -38.57445676
OS 45.79471918 -38.5689094
OS 45.79379462 -38.56798484
OS 45.79102094 -38.56613572
OS 45.78547358 -38.5642866
OS 45.77900166 -38.56151292
OS 45.77160518 -38.55873924
OS 45.76235958 -38.55596556
OS 45.75126486 -38.555041
OS 45.74017014 -38.55411644
OS 45.73554734 -38.55411644
OS 45.7318491 -38.555041
OS 45.7226035 -38.55596556
OS 45.71058422 -38.55781468
OS 45.69764038 -38.56243748
OS 45.68284742 -38.56798484
OS 45.66805446 -38.57538132
OS 45.65418606 -38.58647604
OS 45.65233694 -38.58832516
OS 45.6486387 -38.59294796
OS 45.64586502 -38.5966462
OS 45.64309134 -38.601269
OS 45.6393931 -38.60681636
OS 45.63661942 -38.61328828
OS 45.63292118 -38.62068476
OS 45.62922294 -38.62993036
OS 45.62644926 -38.64010052
OS 45.62367558 -38.65119524
OS 45.62182646 -38.66321452
OS 45.61997734 -38.67615836
OS 45.61812822 -38.69187588
OS 45.61812822 -38.7075934
OS 45.61812822 -38.95999828
OS 45.53954062 -38.95999828
OS 45.53954062 -38.49586916
OS 45.60980718 -38.49586916
OS 45.60980718 -38.56243748
OS 45.61073174 -38.56151292
OS 45.61258086 -38.55873924
OS 45.61535454 -38.555041
OS 45.61905278 -38.5504182
OS 45.62460014 -38.54487084
OS 45.63107206 -38.53839892
OS 45.63846854 -38.53100244
OS 45.64771414 -38.52360596
OS 45.65695974 -38.51713404
OS 45.66805446 -38.50973756
OS 45.68007374 -38.50326564
OS 45.69301758 -38.49771828
OS 45.70781054 -38.49309548
OS 45.7226035 -38.48939724
OS 45.73924558 -38.48662356
OS 45.75681222 -38.485699
OS 45.7642087 -38.485699
OS 45.77160518 -38.48662356
OE
OB 44.2756671 -38.95999828 I
OS 44.1970795 -38.95999828
OS 44.1970795 -38.49586916
OS 44.2756671 -38.49586916
OS 44.2756671 -38.95999828
OE
OB 43.4574315 -38.48662356 I
OS 43.46482798 -38.48754812
OS 43.47407358 -38.48939724
OS 43.48424374 -38.49124636
OS 43.49626302 -38.49402004
OS 43.50735774 -38.49679372
OS 43.52030158 -38.50141652
OS 43.53232086 -38.50603932
OS 43.5452647 -38.51251124
OS 43.55820854 -38.51990772
OS 43.57115238 -38.52822876
OS 43.58317166 -38.53839892
OS 43.59426638 -38.54949364
OS 43.59519094 -38.5504182
OS 43.59704006 -38.55226732
OS 43.59981374 -38.55596556
OS 43.60351198 -38.56151292
OS 43.60813478 -38.56798484
OS 43.61275758 -38.57538132
OS 43.61830494 -38.58462692
OS 43.6238523 -38.59572164
OS 43.62939966 -38.60774092
OS 43.63494702 -38.62068476
OS 43.63956982 -38.63547772
OS 43.64419262 -38.65119524
OS 43.64789086 -38.66876188
OS 43.65066454 -38.68725308
OS 43.65251366 -38.70666884
OS 43.65343822 -38.72793372
OS 43.65343822 -38.72885828
OS 43.65343822 -38.73255652
OS 43.65343822 -38.73902844
OS 43.65251366 -38.74827404
OS 43.30580366 -38.74827404
OS 43.30580366 -38.7491986
OS 43.30580366 -38.75197228
OS 43.30672822 -38.75567052
OS 43.30672822 -38.76121788
OS 43.30765278 -38.7676898
OS 43.3095019 -38.77508628
OS 43.31227558 -38.79172836
OS 43.31782294 -38.81021956
OS 43.32521942 -38.83055988
OS 43.33538958 -38.84905108
OS 43.34833342 -38.86569316
OS 43.34925798 -38.86569316
OS 43.35018254 -38.86754228
OS 43.3557299 -38.87216508
OS 43.36405094 -38.878637
OS 43.37514566 -38.88510892
OS 43.38993862 -38.8925054
OS 43.4065807 -38.89897732
OS 43.4250719 -38.90360012
OS 43.43524206 -38.90452468
OS 43.44633678 -38.90544924
OS 43.45373326 -38.90544924
OS 43.4620543 -38.90452468
OS 43.47222446 -38.90267556
OS 43.48331918 -38.89990188
OS 43.49626302 -38.89620364
OS 43.5082823 -38.89065628
OS 43.52030158 -38.8832598
OS 43.52122614 -38.88233524
OS 43.52584894 -38.878637
OS 43.5313963 -38.87308964
OS 43.53786822 -38.86569316
OS 43.5452647 -38.855523
OS 43.55358574 -38.84257916
OS 43.56190678 -38.8277862
OS 43.56930326 -38.81021956
OS 43.65066454 -38.82038972
OS 43.65066454 -38.82131428
OS 43.64973998 -38.8231634
OS 43.64881542 -38.82686164
OS 43.6469663 -38.832409
OS 43.64419262 -38.83795636
OS 43.64141894 -38.84535284
OS 43.63402246 -38.86107036
OS 43.62477686 -38.878637
OS 43.61183302 -38.8971282
OS 43.59704006 -38.91469484
OS 43.57854886 -38.93133692
OS 43.5776243 -38.93133692
OS 43.57577518 -38.93318604
OS 43.5730015 -38.93503516
OS 43.56930326 -38.93780884
OS 43.5637559 -38.94058252
OS 43.55820854 -38.9433562
OS 43.55081206 -38.94705444
OS 43.54249102 -38.95075268
OS 43.53324542 -38.95445092
OS 43.52399982 -38.95814916
OS 43.50088582 -38.96369652
OS 43.47499814 -38.96831932
OS 43.44633678 -38.97016844
OS 43.43616662 -38.97016844
OS 43.4296947 -38.96924388
OS 43.42137366 -38.96831932
OS 43.4112035 -38.9664702
OS 43.40010878 -38.96462108
OS 43.3880895 -38.96277196
OS 43.36220182 -38.95537548
OS 43.34833342 -38.94982812
OS 43.33538958 -38.94428076
OS 43.32152118 -38.93688428
OS 43.30857734 -38.92856324
OS 43.29655806 -38.91931764
OS 43.28453878 -38.90822292
OS 43.28361422 -38.90729836
OS 43.2817651 -38.90544924
OS 43.27899142 -38.901751
OS 43.27529318 -38.89620364
OS 43.27067038 -38.88973172
OS 43.26604758 -38.88233524
OS 43.26050022 -38.87308964
OS 43.25495286 -38.86291948
OS 43.2494055 -38.8509002
OS 43.24385814 -38.83795636
OS 43.23923534 -38.8231634
OS 43.23461254 -38.80744588
OS 43.2309143 -38.7908038
OS 43.22814062 -38.7723126
OS 43.2262915 -38.75289684
OS 43.22536694 -38.73255652
OS 43.22536694 -38.73163196
OS 43.22536694 -38.72700916
OS 43.22536694 -38.7214618
OS 43.2262915 -38.71314076
OS 43.22721606 -38.7029706
OS 43.22814062 -38.69187588
OS 43.22998974 -38.67893204
OS 43.23276342 -38.6659882
OS 43.2401599 -38.63640228
OS 43.2447827 -38.62160932
OS 43.25033006 -38.6058918
OS 43.25772654 -38.59109884
OS 43.26604758 -38.57723044
OS 43.27529318 -38.56336204
OS 43.28546334 -38.5504182
OS 43.2863879 -38.54949364
OS 43.28823702 -38.54764452
OS 43.29193526 -38.54487084
OS 43.29655806 -38.54024804
OS 43.30210542 -38.53562524
OS 43.3095019 -38.53007788
OS 43.31782294 -38.52360596
OS 43.3279931 -38.5180586
OS 43.33816326 -38.51158668
OS 43.35018254 -38.50603932
OS 43.36312638 -38.50049196
OS 43.37699478 -38.49586916
OS 43.39178774 -38.49124636
OS 43.40750526 -38.48847268
OS 43.42414734 -38.48662356
OS 43.44171398 -38.485699
OS 43.45095958 -38.485699
OS 43.4574315 -38.48662356
OE
OB 43.13938286 -38.48662356 I
OS 43.14955302 -38.48847268
OS 43.1615723 -38.49217092
OS 43.17451614 -38.49679372
OS 43.1893091 -38.50326564
OS 43.20502662 -38.51158668
OS 43.17636526 -38.58370236
OS 43.1754407 -38.5827778
OS 43.17174246 -38.58092868
OS 43.1661951 -38.578155
OS 43.15879862 -38.57538132
OS 43.15047758 -38.57260764
OS 43.14030742 -38.56983396
OS 43.13013726 -38.56798484
OS 43.1199671 -38.56706028
OS 43.1153443 -38.56706028
OS 43.1107215 -38.56798484
OS 43.10424958 -38.5689094
OS 43.09777766 -38.57075852
OS 43.08945662 -38.5735322
OS 43.08113558 -38.57723044
OS 43.0737391 -38.5827778
OS 43.07281454 -38.58370236
OS 43.07004086 -38.58555148
OS 43.06726718 -38.58924972
OS 43.06264438 -38.59387252
OS 43.05802158 -38.60034444
OS 43.05339878 -38.60774092
OS 43.04877598 -38.61606196
OS 43.04507774 -38.62623212
OS 43.04415318 -38.62808124
OS 43.04322862 -38.6336286
OS 43.0413795 -38.64194964
OS 43.03860582 -38.65304436
OS 43.03583214 -38.66691276
OS 43.03398302 -38.68263028
OS 43.03305846 -38.69927236
OS 43.0321339 -38.71776356
OS 43.0321339 -38.95999828
OS 42.9535463 -38.95999828
OS 42.9535463 -38.49586916
OS 43.02473742 -38.49586916
OS 43.02473742 -38.56613572
OS 43.02566198 -38.56521116
OS 43.02936022 -38.55873924
OS 43.03398302 -38.5504182
OS 43.0413795 -38.54024804
OS 43.04877598 -38.53007788
OS 43.05709702 -38.51898316
OS 43.06541806 -38.50973756
OS 43.0737391 -38.50234108
OS 43.07466366 -38.50141652
OS 43.07743734 -38.4995674
OS 43.0829847 -38.49679372
OS 43.08853206 -38.49402004
OS 43.09592854 -38.49124636
OS 43.10517414 -38.48847268
OS 43.11441974 -38.48662356
OS 43.1245899 -38.485699
OS 43.13106182 -38.485699
OS 43.13938286 -38.48662356
OE
OB 43.95022198 -38.95999828 I
OS 43.87533262 -38.95999828
OS 43.70059078 -38.49586916
OS 43.78380118 -38.49586916
OS 43.88365366 -38.77416172
OS 43.88365366 -38.77508628
OS 43.88457822 -38.77601084
OS 43.88550278 -38.77878452
OS 43.88642734 -38.7815582
OS 43.88920102 -38.7908038
OS 43.89289926 -38.80282308
OS 43.89752206 -38.81669148
OS 43.90306942 -38.832409
OS 43.90769222 -38.84997564
OS 43.91323958 -38.86754228
OS 43.91416414 -38.86569316
OS 43.9150887 -38.86107036
OS 43.91786238 -38.85367388
OS 43.92063606 -38.84257916
OS 43.92525886 -38.83055988
OS 43.92988166 -38.81484236
OS 43.93635358 -38.79820028
OS 43.9428255 -38.77970908
OS 44.04545166 -38.49586916
OS 44.12681294 -38.49586916
OS 43.95022198 -38.95999828
OE
OB 44.2756671 -38.40988508 I
OS 44.1970795 -38.40988508
OS 44.1970795 -38.32020276
OS 44.2756671 -38.32020276
OS 44.2756671 -38.40988508
OE
OB 44.5669035 -38.48662356 I
OS 44.5807719 -38.48754812
OS 44.59556486 -38.48939724
OS 44.61128238 -38.49309548
OS 44.62792446 -38.49679372
OS 44.64364198 -38.50234108
OS 44.64456654 -38.50234108
OS 44.6454911 -38.50326564
OS 44.6501139 -38.50511476
OS 44.65751038 -38.508813
OS 44.66675598 -38.5134358
OS 44.67692614 -38.51990772
OS 44.6870963 -38.5273042
OS 44.6963419 -38.53562524
OS 44.70466294 -38.54487084
OS 44.7055875 -38.5457954
OS 44.70743662 -38.54949364
OS 44.71113486 -38.55596556
OS 44.71575766 -38.56336204
OS 44.72038046 -38.57445676
OS 44.72500326 -38.58647604
OS 44.7287015 -38.60034444
OS 44.73239974 -38.61606196
OS 44.65566126 -38.62623212
OS 44.65566126 -38.624383
OS 44.6547367 -38.62068476
OS 44.65288758 -38.61421284
OS 44.6501139 -38.6058918
OS 44.6454911 -38.59757076
OS 44.63994374 -38.58832516
OS 44.63347182 -38.57907956
OS 44.62422622 -38.57075852
OS 44.62330166 -38.56983396
OS 44.61960342 -38.56798484
OS 44.61405606 -38.5642866
OS 44.60573502 -38.56058836
OS 44.59648942 -38.55689012
OS 44.58447014 -38.55319188
OS 44.56967718 -38.55134276
OS 44.55395966 -38.5504182
OS 44.54471406 -38.5504182
OS 44.53546846 -38.55134276
OS 44.52344918 -38.55226732
OS 44.5114299 -38.555041
OS 44.49848606 -38.55781468
OS 44.48646678 -38.56243748
OS 44.47629662 -38.5689094
OS 44.47537206 -38.56983396
OS 44.47259838 -38.57168308
OS 44.46890014 -38.57538132
OS 44.4652019 -38.58092868
OS 44.4605791 -38.58647604
OS 44.45688086 -38.59387252
OS 44.45410718 -38.60219356
OS 44.45318262 -38.6105146
OS 44.45318262 -38.61143916
OS 44.45318262 -38.61328828
OS 44.45410718 -38.61606196
OS 44.45410718 -38.6197602
OS 44.45688086 -38.6290058
OS 44.46242822 -38.6382514
OS 44.46335278 -38.63917596
OS 44.46427734 -38.64010052
OS 44.46612646 -38.6428742
OS 44.4698247 -38.64564788
OS 44.47352294 -38.64842156
OS 44.4790703 -38.6521198
OS 44.48554222 -38.65489348
OS 44.4929387 -38.65859172
OS 44.49386326 -38.65859172
OS 44.49571238 -38.65951628
OS 44.49941062 -38.66044084
OS 44.50588254 -38.66321452
OS 44.51512814 -38.6659882
OS 44.52714742 -38.66876188
OS 44.5345439 -38.67153556
OS 44.54286494 -38.67338468
OS 44.55211054 -38.67615836
OS 44.5622807 -38.67893204
OS 44.56320526 -38.67893204
OS 44.56597894 -38.6798566
OS 44.57060174 -38.68078116
OS 44.5761491 -38.68263028
OS 44.58262102 -38.6844794
OS 44.59094206 -38.68632852
OS 44.6085087 -38.69187588
OS 44.62792446 -38.69742324
OS 44.64734022 -38.70389516
OS 44.66490686 -38.71036708
OS 44.67230334 -38.71314076
OS 44.67877526 -38.71591444
OS 44.68062438 -38.716839
OS 44.68432262 -38.71868812
OS 44.68986998 -38.7214618
OS 44.69819102 -38.7260846
OS 44.70651206 -38.73163196
OS 44.7148331 -38.73902844
OS 44.72315414 -38.74734948
OS 44.73055062 -38.75659508
OS 44.73147518 -38.75751964
OS 44.7333243 -38.76121788
OS 44.73702254 -38.76676524
OS 44.74072078 -38.77508628
OS 44.74349446 -38.78525644
OS 44.7471927 -38.79635116
OS 44.74904182 -38.809295
OS 44.74996638 -38.82408796
OS 44.74996638 -38.82593708
OS 44.74996638 -38.83055988
OS 44.74904182 -38.83795636
OS 44.7471927 -38.84812652
OS 44.74441902 -38.85922124
OS 44.73979622 -38.87124052
OS 44.73424886 -38.88510892
OS 44.72685238 -38.89805276
OS 44.72592782 -38.89990188
OS 44.72222958 -38.90360012
OS 44.71760678 -38.91007204
OS 44.7102103 -38.91746852
OS 44.70004014 -38.92578956
OS 44.68894542 -38.93503516
OS 44.67600158 -38.9433562
OS 44.66028406 -38.95167724
OS 44.6593595 -38.95167724
OS 44.65843494 -38.9526018
OS 44.65288758 -38.95445092
OS 44.64364198 -38.9572246
OS 44.6316227 -38.96092284
OS 44.61682974 -38.96462108
OS 44.60018766 -38.96739476
OS 44.58262102 -38.96924388
OS 44.5622807 -38.97016844
OS 44.55395966 -38.97016844
OS 44.54748774 -38.96924388
OS 44.54009126 -38.96924388
OS 44.53084566 -38.96831932
OS 44.52160006 -38.96739476
OS 44.5114299 -38.96554564
OS 44.48924046 -38.96092284
OS 44.46612646 -38.95445092
OS 44.44393702 -38.94520532
OS 44.43376686 -38.93965796
OS 44.42452126 -38.93318604
OS 44.4235967 -38.93226148
OS 44.42267214 -38.93133692
OS 44.41712478 -38.92578956
OS 44.40880374 -38.91746852
OS 44.39955814 -38.90452468
OS 44.38938798 -38.88880716
OS 44.37921782 -38.87031596
OS 44.37089678 -38.84720196
OS 44.36442486 -38.82131428
OS 44.4420879 -38.809295
OS 44.4420879 -38.81021956
OS 44.4420879 -38.81114412
OS 44.44393702 -38.81669148
OS 44.44578614 -38.82593708
OS 44.44948438 -38.83610724
OS 44.45410718 -38.84720196
OS 44.45965454 -38.85922124
OS 44.46797558 -38.87124052
OS 44.47814574 -38.88141068
OS 44.47999486 -38.88233524
OS 44.4836931 -38.88510892
OS 44.49108958 -38.88880716
OS 44.50033518 -38.89342996
OS 44.51235446 -38.89805276
OS 44.52622286 -38.901751
OS 44.54286494 -38.90452468
OS 44.5622807 -38.90544924
OS 44.5715263 -38.90544924
OS 44.5807719 -38.90452468
OS 44.59279118 -38.90267556
OS 44.60573502 -38.89990188
OS 44.61960342 -38.89620364
OS 44.6316227 -38.89158084
OS 44.64271742 -38.88418436
OS 44.64364198 -38.8832598
OS 44.64734022 -38.88048612
OS 44.65103846 -38.87586332
OS 44.65658582 -38.8693914
OS 44.66120862 -38.86199492
OS 44.66583142 -38.85274932
OS 44.6686051 -38.84350372
OS 44.66952966 -38.832409
OS 44.66952966 -38.83148444
OS 44.66952966 -38.8277862
OS 44.6686051 -38.8231634
OS 44.66675598 -38.81669148
OS 44.6639823 -38.81021956
OS 44.6593595 -38.80374764
OS 44.65381214 -38.79635116
OS 44.6454911 -38.7908038
OS 44.64456654 -38.78987924
OS 44.64179286 -38.78895468
OS 44.63717006 -38.786181
OS 44.62977358 -38.78340732
OS 44.61867886 -38.77970908
OS 44.61220694 -38.7769354
OS 44.60481046 -38.77508628
OS 44.59648942 -38.7723126
OS 44.58724382 -38.76953892
OS 44.57707366 -38.76676524
OS 44.56505438 -38.76399156
OS 44.56412982 -38.76399156
OS 44.56135614 -38.763067
OS 44.55673334 -38.76214244
OS 44.55118598 -38.76029332
OS 44.5437895 -38.7584442
OS 44.53546846 -38.75567052
OS 44.51790182 -38.75104772
OS 44.4975615 -38.7445758
OS 44.47814574 -38.73902844
OS 44.45965454 -38.73255652
OS 44.4513335 -38.72885828
OS 44.44486158 -38.7260846
OS 44.44301246 -38.72516004
OS 44.43931422 -38.72331092
OS 44.43376686 -38.71961268
OS 44.42637038 -38.71498988
OS 44.41804934 -38.70851796
OS 44.4097283 -38.70112148
OS 44.40140726 -38.69280044
OS 44.39401078 -38.68263028
OS 44.39308622 -38.68170572
OS 44.3912371 -38.67800748
OS 44.38846342 -38.67153556
OS 44.38568974 -38.66413908
OS 44.38291606 -38.65489348
OS 44.38014238 -38.64379876
OS 44.37829326 -38.63270404
OS 44.3773687 -38.6197602
OS 44.3773687 -38.61791108
OS 44.3773687 -38.61421284
OS 44.37829326 -38.60866548
OS 44.37921782 -38.60034444
OS 44.38106694 -38.5920234
OS 44.38291606 -38.58185324
OS 44.3866143 -38.57260764
OS 44.3912371 -38.56243748
OS 44.39216166 -38.56151292
OS 44.39401078 -38.55781468
OS 44.39678446 -38.55319188
OS 44.40140726 -38.54671996
OS 44.40695462 -38.54024804
OS 44.41342654 -38.531927
OS 44.42082302 -38.52453052
OS 44.43006862 -38.5180586
OS 44.43099318 -38.51713404
OS 44.43376686 -38.51620948
OS 44.4374651 -38.5134358
OS 44.44301246 -38.51066212
OS 44.45040894 -38.50696388
OS 44.45872998 -38.50326564
OS 44.46890014 -38.4995674
OS 44.47999486 -38.49586916
OS 44.48184398 -38.4949446
OS 44.48554222 -38.49402004
OS 44.49201414 -38.49217092
OS 44.50033518 -38.4903218
OS 44.51050534 -38.48847268
OS 44.52160006 -38.48754812
OS 44.5345439 -38.485699
OS 44.55673334 -38.485699
OS 44.5669035 -38.48662356
OE
OB 33.15968222 -38.32112732 I
OS 33.17539974 -38.32205188
OS 33.19204182 -38.32297644
OS 33.20775934 -38.32482556
OS 33.22162774 -38.32667468
OS 33.22347686 -38.32667468
OS 33.22994878 -38.3285238
OS 33.23826982 -38.33037292
OS 33.24936454 -38.3331466
OS 33.26138382 -38.3377694
OS 33.27432766 -38.34331676
OS 33.28819606 -38.34978868
OS 33.30021534 -38.35718516
OS 33.30206446 -38.35810972
OS 33.3057627 -38.3608834
OS 33.31131006 -38.36643076
OS 33.31870654 -38.37290268
OS 33.32702758 -38.38122372
OS 33.33534862 -38.39231844
OS 33.34459422 -38.40433772
OS 33.3519907 -38.41820612
OS 33.35291526 -38.42005524
OS 33.35476438 -38.42467804
OS 33.35846262 -38.43299908
OS 33.36216086 -38.4440938
OS 33.36493454 -38.45703764
OS 33.36863278 -38.4718306
OS 33.3704819 -38.48847268
OS 33.37140646 -38.50603932
OS 33.37140646 -38.50696388
OS 33.37140646 -38.50973756
OS 33.37140646 -38.5134358
OS 33.3704819 -38.51990772
OS 33.36955734 -38.52637964
OS 33.36863278 -38.53470068
OS 33.36678366 -38.54394628
OS 33.36493454 -38.55411644
OS 33.35846262 -38.57538132
OS 33.35476438 -38.58647604
OS 33.34921702 -38.59849532
OS 33.3427451 -38.6105146
OS 33.33627318 -38.62160932
OS 33.32795214 -38.63270404
OS 33.31870654 -38.64379876
OS 33.31778198 -38.64472332
OS 33.31593286 -38.64657244
OS 33.31315918 -38.64934612
OS 33.30853638 -38.6521198
OS 33.30298902 -38.6567426
OS 33.29559254 -38.6613654
OS 33.28634694 -38.66691276
OS 33.27617678 -38.67153556
OS 33.2641575 -38.67708292
OS 33.2502891 -38.68263028
OS 33.23549614 -38.68725308
OS 33.2179295 -38.69095132
OS 33.1994383 -38.69464956
OS 33.17909798 -38.69742324
OS 33.15598398 -38.69927236
OS 33.13194542 -38.70019692
OS 32.9682983 -38.70019692
OS 32.9682983 -38.95999828
OS 32.88323878 -38.95999828
OS 32.88323878 -38.32020276
OS 33.14581382 -38.32020276
OS 33.15968222 -38.32112732
OE
OB 32.75195126 -38.98403684 I
OS 32.75195126 -38.9849614
OS 32.75195126 -38.98773508
OS 32.75195126 -38.99235788
OS 32.75195126 -38.99790524
OS 32.7510267 -39.00530172
OS 32.7510267 -39.0126982
OS 32.74917758 -39.0311894
OS 32.7464039 -39.05060516
OS 32.74270566 -39.07094548
OS 32.7371583 -39.08851212
OS 32.73346006 -39.09683316
OS 32.72976182 -39.10330508
OS 32.72976182 -39.10422964
OS 32.72883726 -39.1051542
OS 32.72421446 -39.109777
OS 32.71681798 -39.11717348
OS 32.70757238 -39.12549452
OS 32.69462854 -39.13381556
OS 32.67798646 -39.14028748
OS 32.6585707 -39.14583484
OS 32.64747598 -39.1467594
OS 32.6354567 -39.14768396
OS 32.62990934 -39.14768396
OS 32.62436198 -39.1467594
OS 32.61604094 -39.1467594
OS 32.60679534 -39.14583484
OS 32.59662518 -39.14398572
OS 32.57443574 -39.13843836
OS 32.5892287 -39.07187004
OS 32.59015326 -39.07187004
OS 32.59292694 -39.0727946
OS 32.59754974 -39.07371916
OS 32.60217254 -39.07464372
OS 32.61419182 -39.0774174
OS 32.61973918 -39.07834196
OS 32.62898478 -39.07834196
OS 32.63360758 -39.0774174
OS 32.63915494 -39.07649284
OS 32.6447023 -39.07464372
OS 32.65024966 -39.07094548
OS 32.65672158 -39.06724724
OS 32.66134438 -39.06169988
OS 32.66226894 -39.06077532
OS 32.6631935 -39.05800164
OS 32.66504262 -39.05337884
OS 32.6678163 -39.04598236
OS 32.66966542 -39.0358122
OS 32.67058998 -39.02841572
OS 32.67151454 -39.0219438
OS 32.6724391 -39.01362276
OS 32.6724391 -39.0034526
OS 32.67336366 -38.99328244
OS 32.67336366 -38.98218772
OS 32.67336366 -38.49586916
OS 32.75195126 -38.49586916
OS 32.75195126 -38.98403684
OE
OB 33.77174094 -38.3100326 I
OS 33.78006198 -38.31095716
OS 33.79023214 -38.31188172
OS 33.8004023 -38.31280628
OS 33.81242158 -38.31557996
OS 33.8373847 -38.32112732
OS 33.8651215 -38.32944836
OS 33.8789899 -38.33499572
OS 33.89193374 -38.34146764
OS 33.90487758 -38.34978868
OS 33.91782142 -38.35810972
OS 33.91874598 -38.35903428
OS 33.9205951 -38.35995884
OS 33.92429334 -38.36273252
OS 33.92891614 -38.36735532
OS 33.93353894 -38.37197812
OS 33.94001086 -38.37845004
OS 33.94648278 -38.38584652
OS 33.95387926 -38.393243
OS 33.96127574 -38.4024886
OS 33.96867222 -38.41358332
OS 33.97699326 -38.42467804
OS 33.98438974 -38.43669732
OS 33.99086166 -38.45056572
OS 33.99825814 -38.46443412
OS 34.0038055 -38.47922708
OS 34.00935286 -38.49586916
OS 33.92614246 -38.51528492
OS 33.92614246 -38.51436036
OS 33.9252179 -38.51251124
OS 33.92336878 -38.508813
OS 33.92151966 -38.5041902
OS 33.91967054 -38.49864284
OS 33.91689686 -38.49124636
OS 33.90950038 -38.4764534
OS 33.90025478 -38.45981132
OS 33.88916006 -38.44316924
OS 33.87529166 -38.42745172
OS 33.8604987 -38.41358332
OS 33.85864958 -38.4117342
OS 33.85310222 -38.40803596
OS 33.84385662 -38.40341316
OS 33.83183734 -38.39694124
OS 33.81611982 -38.39139388
OS 33.79855318 -38.38584652
OS 33.7772883 -38.38214828
OS 33.7541743 -38.38122372
OS 33.74677782 -38.38122372
OS 33.74215502 -38.38214828
OS 33.7356831 -38.38214828
OS 33.72828662 -38.38307284
OS 33.71071998 -38.38584652
OS 33.69130422 -38.38954476
OS 33.6709639 -38.39601668
OS 33.64969902 -38.40526228
OS 33.63028326 -38.41728156
OS 33.6293587 -38.41728156
OS 33.62843414 -38.41913068
OS 33.62196222 -38.42375348
OS 33.61364118 -38.43114996
OS 33.60347102 -38.44224468
OS 33.59145174 -38.45611308
OS 33.58035702 -38.4718306
OS 33.57018686 -38.49124636
OS 33.56094126 -38.51251124
OS 33.56094126 -38.5134358
OS 33.5600167 -38.51528492
OS 33.55909214 -38.5180586
OS 33.55816758 -38.5226814
OS 33.55631846 -38.52822876
OS 33.55446934 -38.53470068
OS 33.55169566 -38.5504182
OS 33.54799742 -38.5689094
OS 33.54429918 -38.58924972
OS 33.54245006 -38.61143916
OS 33.5415255 -38.63547772
OS 33.5415255 -38.63640228
OS 33.5415255 -38.63917596
OS 33.5415255 -38.64379876
OS 33.5415255 -38.64934612
OS 33.54245006 -38.65581804
OS 33.54245006 -38.66413908
OS 33.54337462 -38.67338468
OS 33.54429918 -38.68355484
OS 33.54707286 -38.70574428
OS 33.55169566 -38.72978284
OS 33.55724302 -38.7538214
OS 33.5646395 -38.77785996
OS 33.5646395 -38.77878452
OS 33.56556406 -38.78063364
OS 33.56741318 -38.78340732
OS 33.5692623 -38.78803012
OS 33.57480966 -38.79912484
OS 33.5831307 -38.81206868
OS 33.59330086 -38.82686164
OS 33.6062447 -38.84257916
OS 33.62103766 -38.85644756
OS 33.6386043 -38.8693914
OS 33.63952886 -38.8693914
OS 33.64137798 -38.87031596
OS 33.64415166 -38.87216508
OS 33.6478499 -38.8740142
OS 33.6524727 -38.87586332
OS 33.65802006 -38.878637
OS 33.6709639 -38.88418436
OS 33.68760598 -38.88973172
OS 33.70609718 -38.89435452
OS 33.7264375 -38.89805276
OS 33.74770238 -38.89897732
OS 33.7541743 -38.89897732
OS 33.75972166 -38.89805276
OS 33.76619358 -38.89805276
OS 33.7726655 -38.8971282
OS 33.78930758 -38.89342996
OS 33.80872334 -38.88880716
OS 33.8281391 -38.88141068
OS 33.84847942 -38.87124052
OS 33.85864958 -38.86569316
OS 33.86789518 -38.85829668
OS 33.86881974 -38.85737212
OS 33.8697443 -38.85644756
OS 33.87251798 -38.85367388
OS 33.87621622 -38.8509002
OS 33.87991446 -38.8462774
OS 33.88453726 -38.84073004
OS 33.89008462 -38.83518268
OS 33.89470742 -38.8277862
OS 33.90025478 -38.81946516
OS 33.9067267 -38.81021956
OS 33.91227406 -38.80097396
OS 33.91782142 -38.78987924
OS 33.92244422 -38.77785996
OS 33.92706702 -38.76491612
OS 33.93168982 -38.75104772
OS 33.93538806 -38.73625476
OS 34.02044758 -38.75751964
OS 34.02044758 -38.7584442
OS 34.01952302 -38.76214244
OS 34.0176739 -38.7676898
OS 34.01490022 -38.77508628
OS 34.01212654 -38.78340732
OS 34.0084283 -38.79357748
OS 34.0038055 -38.8046722
OS 33.99825814 -38.81669148
OS 33.9853143 -38.84257916
OS 33.96867222 -38.86846684
OS 33.95850206 -38.88141068
OS 33.9483319 -38.89435452
OS 33.93723718 -38.90544924
OS 33.92429334 -38.91654396
OS 33.92336878 -38.91746852
OS 33.92151966 -38.91931764
OS 33.91689686 -38.92116676
OS 33.91227406 -38.924865
OS 33.90487758 -38.9294878
OS 33.8974811 -38.9341106
OS 33.88731094 -38.9387334
OS 33.87714078 -38.9433562
OS 33.8651215 -38.94890356
OS 33.85217766 -38.95352636
OS 33.83830926 -38.95814916
OS 33.8235163 -38.96277196
OS 33.80779878 -38.9664702
OS 33.7911567 -38.96831932
OS 33.77359006 -38.97016844
OS 33.75509886 -38.971093
OS 33.7449287 -38.971093
OS 33.73753222 -38.97016844
OS 33.72921118 -38.97016844
OS 33.71904102 -38.96924388
OS 33.7079463 -38.96739476
OS 33.69500246 -38.96554564
OS 33.66819022 -38.96092284
OS 33.64045342 -38.95352636
OS 33.61271662 -38.9433562
OS 33.59977278 -38.93688428
OS 33.58682894 -38.9294878
OS 33.58590438 -38.92856324
OS 33.58405526 -38.92763868
OS 33.58035702 -38.924865
OS 33.57665878 -38.92116676
OS 33.57111142 -38.91746852
OS 33.5646395 -38.91192116
OS 33.55724302 -38.90544924
OS 33.54984654 -38.89805276
OS 33.54245006 -38.88973172
OS 33.53412902 -38.88141068
OS 33.51748694 -38.8601458
OS 33.50176942 -38.83518268
OS 33.48790102 -38.80744588
OS 33.48790102 -38.80652132
OS 33.4860519 -38.80374764
OS 33.48512734 -38.79912484
OS 33.48235366 -38.79357748
OS 33.48050454 -38.786181
OS 33.47773086 -38.7769354
OS 33.47403262 -38.76676524
OS 33.47125894 -38.75567052
OS 33.46848526 -38.74365124
OS 33.46478702 -38.72978284
OS 33.46016422 -38.70112148
OS 33.45646598 -38.66876188
OS 33.45461686 -38.63547772
OS 33.45461686 -38.63455316
OS 33.45461686 -38.63085492
OS 33.45461686 -38.62530756
OS 33.45554142 -38.61883564
OS 33.45554142 -38.60959004
OS 33.45646598 -38.60034444
OS 33.45739054 -38.58832516
OS 33.45923966 -38.57630588
OS 33.46386246 -38.54949364
OS 33.47033438 -38.51990772
OS 33.47957998 -38.4903218
OS 33.49252382 -38.46166044
OS 33.49344838 -38.46073588
OS 33.49437294 -38.4579622
OS 33.49622206 -38.45426396
OS 33.4999203 -38.44964116
OS 33.50361854 -38.44316924
OS 33.50824134 -38.43577276
OS 33.52026062 -38.41913068
OS 33.53597814 -38.40063948
OS 33.55446934 -38.38214828
OS 33.57573422 -38.36365708
OS 33.60069734 -38.34793956
OS 33.6016219 -38.347015
OS 33.60439558 -38.34609044
OS 33.60809382 -38.34424132
OS 33.61271662 -38.34146764
OS 33.6201131 -38.33869396
OS 33.62750958 -38.33592028
OS 33.63675518 -38.33222204
OS 33.64692534 -38.3285238
OS 33.65802006 -38.32482556
OS 33.67003934 -38.32112732
OS 33.69592702 -38.31557996
OS 33.72551294 -38.31095716
OS 33.75602342 -38.30910804
OS 33.76526902 -38.30910804
OS 33.77174094 -38.3100326
OE
OB 35.15858094 -39.1375138 I
OS 34.63805366 -39.1375138
OS 34.63805366 -39.08111564
OS 35.15858094 -39.08111564
OS 35.15858094 -39.1375138
OE
OB 34.37917686 -38.32112732 I
OS 34.38657334 -38.32112732
OS 34.40321542 -38.32297644
OS 34.42170662 -38.32482556
OS 34.44112238 -38.3285238
OS 34.46053814 -38.3331466
OS 34.47810478 -38.33961852
OS 34.47902934 -38.33961852
OS 34.4799539 -38.34054308
OS 34.48550126 -38.34331676
OS 34.4938223 -38.34793956
OS 34.5030679 -38.35441148
OS 34.51416262 -38.36273252
OS 34.5261819 -38.37290268
OS 34.53727662 -38.38584652
OS 34.54744678 -38.39971492
OS 34.54837134 -38.40156404
OS 34.55114502 -38.4071114
OS 34.55576782 -38.41450788
OS 34.56039062 -38.4256026
OS 34.56501342 -38.43854644
OS 34.56963622 -38.45241484
OS 34.5724099 -38.46813236
OS 34.57333446 -38.48384988
OS 34.57333446 -38.485699
OS 34.57333446 -38.4903218
OS 34.5724099 -38.49864284
OS 34.57056078 -38.508813
OS 34.5677871 -38.52083228
OS 34.5631643 -38.53377612
OS 34.55761694 -38.54671996
OS 34.55022046 -38.56058836
OS 34.5492959 -38.56243748
OS 34.54652222 -38.56613572
OS 34.54097486 -38.5735322
OS 34.53357838 -38.58092868
OS 34.52433278 -38.59017428
OS 34.51323806 -38.60034444
OS 34.49936966 -38.60959004
OS 34.48365214 -38.61883564
OS 34.4845767 -38.61883564
OS 34.48642582 -38.6197602
OS 34.4891995 -38.62068476
OS 34.49289774 -38.62253388
OS 34.50399246 -38.62623212
OS 34.5169363 -38.63270404
OS 34.5308047 -38.64102508
OS 34.54652222 -38.65119524
OS 34.56039062 -38.66321452
OS 34.57333446 -38.67800748
OS 34.57425902 -38.6798566
OS 34.57795726 -38.68540396
OS 34.58350462 -38.693725
OS 34.58905198 -38.70481972
OS 34.59459934 -38.71961268
OS 34.6001467 -38.7353302
OS 34.60384494 -38.7538214
OS 34.6047695 -38.77416172
OS 34.6047695 -38.77508628
OS 34.6047695 -38.77601084
OS 34.6047695 -38.7815582
OS 34.60384494 -38.7908038
OS 34.60199582 -38.80189852
OS 34.6001467 -38.81484236
OS 34.59644846 -38.82871076
OS 34.59182566 -38.84350372
OS 34.58535374 -38.85829668
OS 34.58442918 -38.8601458
OS 34.5816555 -38.8647686
OS 34.57795726 -38.87124052
OS 34.5724099 -38.88048612
OS 34.56501342 -38.88973172
OS 34.55761694 -38.89990188
OS 34.54837134 -38.91007204
OS 34.53820118 -38.91839308
OS 34.53727662 -38.91931764
OS 34.53357838 -38.92209132
OS 34.52710646 -38.92578956
OS 34.51878542 -38.9294878
OS 34.50861526 -38.93503516
OS 34.49659598 -38.94058252
OS 34.48365214 -38.94520532
OS 34.46793462 -38.94982812
OS 34.4660855 -38.94982812
OS 34.46053814 -38.95167724
OS 34.45129254 -38.9526018
OS 34.43927326 -38.95445092
OS 34.4244803 -38.95630004
OS 34.40691366 -38.95814916
OS 34.3874979 -38.95907372
OS 34.36530846 -38.95999828
OS 34.12122462 -38.95999828
OS 34.12122462 -38.32020276
OS 34.37270494 -38.32020276
OS 34.37917686 -38.32112732
OE
OB 31.74233174 -38.95999828 I
OS 31.65264942 -38.95999828
OS 31.65264942 -38.87031596
OS 31.74233174 -38.87031596
OS 31.74233174 -38.95999828
OE
OB 31.52968294 -38.42745172 I
OS 31.50841806 -38.54671996
OS 31.45941638 -38.54671996
OS 31.44000062 -38.42745172
OS 31.44000062 -38.32020276
OS 31.52968294 -38.32020276
OS 31.52968294 -38.42745172
OE
OB 32.0992119 -38.48662356 I
OS 32.10568382 -38.48754812
OS 32.11955222 -38.48939724
OS 32.1361943 -38.49309548
OS 32.15376094 -38.49864284
OS 32.17132758 -38.50696388
OS 32.18889422 -38.51713404
OS 32.18981878 -38.51713404
OS 32.19074334 -38.51898316
OS 32.1962907 -38.5226814
OS 32.20461174 -38.53007788
OS 32.2147819 -38.53932348
OS 32.22587662 -38.55134276
OS 32.23697134 -38.56613572
OS 32.24806606 -38.58370236
OS 32.25731166 -38.60311812
OS 32.25731166 -38.60404268
OS 32.25823622 -38.6058918
OS 32.25916078 -38.60866548
OS 32.2610099 -38.61236372
OS 32.26285902 -38.61791108
OS 32.26470814 -38.624383
OS 32.26933094 -38.63917596
OS 32.27395374 -38.65766716
OS 32.27765198 -38.67800748
OS 32.28042566 -38.70112148
OS 32.28135022 -38.72516004
OS 32.28135022 -38.7260846
OS 32.28135022 -38.72793372
OS 32.28135022 -38.73163196
OS 32.28135022 -38.73717932
OS 32.28042566 -38.74365124
OS 32.28042566 -38.75104772
OS 32.27857654 -38.7676898
OS 32.2748783 -38.78803012
OS 32.2702555 -38.809295
OS 32.26378358 -38.83148444
OS 32.25546254 -38.85367388
OS 32.25546254 -38.85459844
OS 32.25453798 -38.85644756
OS 32.25268886 -38.85922124
OS 32.25083974 -38.86291948
OS 32.24436782 -38.87308964
OS 32.23604678 -38.88603348
OS 32.22587662 -38.89990188
OS 32.21293278 -38.91377028
OS 32.19813982 -38.92763868
OS 32.18057318 -38.94058252
OS 32.17964862 -38.94058252
OS 32.17872406 -38.94150708
OS 32.17595038 -38.9433562
OS 32.17225214 -38.94520532
OS 32.16300654 -38.94982812
OS 32.1500627 -38.95537548
OS 32.13434518 -38.96092284
OS 32.1177031 -38.96554564
OS 32.09828734 -38.96924388
OS 32.07887158 -38.97016844
OS 32.07239966 -38.97016844
OS 32.06500318 -38.96924388
OS 32.05575758 -38.96831932
OS 32.04466286 -38.9664702
OS 32.03264358 -38.96369652
OS 32.0206243 -38.95999828
OS 32.00860502 -38.95445092
OS 32.00768046 -38.95352636
OS 32.00305766 -38.95167724
OS 31.9975103 -38.947979
OS 31.99011382 -38.94243164
OS 31.98271734 -38.93688428
OS 31.97347174 -38.9294878
OS 31.9651507 -38.92116676
OS 31.95775422 -38.91192116
OS 31.95775422 -39.1375138
OS 31.87916662 -39.1375138
OS 31.87916662 -38.49586916
OS 31.95035774 -38.49586916
OS 31.95035774 -38.55689012
OS 31.9512823 -38.555041
OS 31.95498054 -38.55134276
OS 31.95960334 -38.54487084
OS 31.96699982 -38.53747436
OS 31.97532086 -38.52822876
OS 31.98456646 -38.51990772
OS 31.99566118 -38.51158668
OS 32.0067559 -38.5041902
OS 32.00860502 -38.50326564
OS 32.01230326 -38.50141652
OS 32.01969974 -38.49864284
OS 32.02894534 -38.4949446
OS 32.04004006 -38.49124636
OS 32.0529839 -38.48847268
OS 32.06777686 -38.48662356
OS 32.08441894 -38.485699
OS 32.0945891 -38.485699
OS 32.0992119 -38.48662356
OE
OB 32.5614919 -38.48662356 I
OS 32.57166206 -38.48847268
OS 32.58368134 -38.49217092
OS 32.59662518 -38.49679372
OS 32.61141814 -38.50326564
OS 32.62713566 -38.51158668
OS 32.5984743 -38.58370236
OS 32.59754974 -38.5827778
OS 32.5938515 -38.58092868
OS 32.58830414 -38.578155
OS 32.58090766 -38.57538132
OS 32.57258662 -38.57260764
OS 32.56241646 -38.56983396
OS 32.5522463 -38.56798484
OS 32.54207614 -38.56706028
OS 32.53745334 -38.56706028
OS 32.53283054 -38.56798484
OS 32.52635862 -38.5689094
OS 32.5198867 -38.57075852
OS 32.51156566 -38.5735322
OS 32.50324462 -38.57723044
OS 32.49584814 -38.5827778
OS 32.49492358 -38.58370236
OS 32.4921499 -38.58555148
OS 32.48937622 -38.58924972
OS 32.48475342 -38.59387252
OS 32.48013062 -38.60034444
OS 32.47550782 -38.60774092
OS 32.47088502 -38.61606196
OS 32.46718678 -38.62623212
OS 32.46626222 -38.62808124
OS 32.46533766 -38.6336286
OS 32.46348854 -38.64194964
OS 32.46071486 -38.65304436
OS 32.45794118 -38.66691276
OS 32.45609206 -38.68263028
OS 32.4551675 -38.69927236
OS 32.45424294 -38.71776356
OS 32.45424294 -38.95999828
OS 32.37565534 -38.95999828
OS 32.37565534 -38.49586916
OS 32.44684646 -38.49586916
OS 32.44684646 -38.56613572
OS 32.44777102 -38.56521116
OS 32.45146926 -38.55873924
OS 32.45609206 -38.5504182
OS 32.46348854 -38.54024804
OS 32.47088502 -38.53007788
OS 32.47920606 -38.51898316
OS 32.4875271 -38.50973756
OS 32.49584814 -38.50234108
OS 32.4967727 -38.50141652
OS 32.49954638 -38.4995674
OS 32.50509374 -38.49679372
OS 32.5106411 -38.49402004
OS 32.51803758 -38.49124636
OS 32.52728318 -38.48847268
OS 32.53652878 -38.48662356
OS 32.54669894 -38.485699
OS 32.55317086 -38.485699
OS 32.5614919 -38.48662356
OE
OB 32.75195126 -38.4117342 I
OS 32.67336366 -38.4117342
OS 32.67336366 -38.32020276
OS 32.75195126 -38.32020276
OS 32.75195126 -38.4117342
OE
OB 36.56668582 -38.95999828 I
OS 36.47885262 -38.95999828
OS 36.1441619 -38.4579622
OS 36.1441619 -38.95999828
OS 36.06280062 -38.95999828
OS 36.06280062 -38.32020276
OS 36.14970926 -38.32020276
OS 36.48532454 -38.8231634
OS 36.48532454 -38.32020276
OS 36.56668582 -38.32020276
OS 36.56668582 -38.95999828
OE
OB 35.74382742 -38.32112732 I
OS 35.75954494 -38.32205188
OS 35.77618702 -38.32297644
OS 35.79190454 -38.32482556
OS 35.80577294 -38.32667468
OS 35.80762206 -38.32667468
OS 35.81409398 -38.3285238
OS 35.82241502 -38.33037292
OS 35.83350974 -38.3331466
OS 35.84552902 -38.3377694
OS 35.85847286 -38.34331676
OS 35.87234126 -38.34978868
OS 35.88436054 -38.35718516
OS 35.88620966 -38.35810972
OS 35.8899079 -38.3608834
OS 35.89545526 -38.36643076
OS 35.90285174 -38.37290268
OS 35.91117278 -38.38122372
OS 35.91949382 -38.39231844
OS 35.92873942 -38.40433772
OS 35.9361359 -38.41820612
OS 35.93706046 -38.42005524
OS 35.93890958 -38.42467804
OS 35.94260782 -38.43299908
OS 35.94630606 -38.4440938
OS 35.94907974 -38.45703764
OS 35.95277798 -38.4718306
OS 35.9546271 -38.48847268
OS 35.95555166 -38.50603932
OS 35.95555166 -38.50696388
OS 35.95555166 -38.50973756
OS 35.95555166 -38.5134358
OS 35.9546271 -38.51990772
OS 35.95370254 -38.52637964
OS 35.95277798 -38.53470068
OS 35.95092886 -38.54394628
OS 35.94907974 -38.55411644
OS 35.94260782 -38.57538132
OS 35.93890958 -38.58647604
OS 35.93336222 -38.59849532
OS 35.9268903 -38.6105146
OS 35.92041838 -38.62160932
OS 35.91209734 -38.63270404
OS 35.90285174 -38.64379876
OS 35.90192718 -38.64472332
OS 35.90007806 -38.64657244
OS 35.89730438 -38.64934612
OS 35.89268158 -38.6521198
OS 35.88713422 -38.6567426
OS 35.87973774 -38.6613654
OS 35.87049214 -38.66691276
OS 35.86032198 -38.67153556
OS 35.8483027 -38.67708292
OS 35.8344343 -38.68263028
OS 35.81964134 -38.68725308
OS 35.8020747 -38.69095132
OS 35.7835835 -38.69464956
OS 35.76324318 -38.69742324
OS 35.74012918 -38.69927236
OS 35.71609062 -38.70019692
OS 35.5524435 -38.70019692
OS 35.5524435 -38.95999828
OS 35.46738398 -38.95999828
OS 35.46738398 -38.32020276
OS 35.72995902 -38.32020276
OS 35.74382742 -38.32112732
OE
OB 36.76916446 -38.42745172 I
OS 36.74789958 -38.54671996
OS 36.6988979 -38.54671996
OS 36.67948214 -38.42745172
OS 36.67948214 -38.32020276
OS 36.76916446 -38.32020276
OS 36.76916446 -38.42745172
OE
OB 38.2382903 -38.39601668 I
OS 37.86014526 -38.39601668
OS 37.86014526 -38.59109884
OS 38.21425174 -38.59109884
OS 38.21425174 -38.66691276
OS 37.86014526 -38.66691276
OS 37.86014526 -38.88418436
OS 38.25308326 -38.88418436
OS 38.25308326 -38.95999828
OS 37.77508574 -38.95999828
OS 37.77508574 -38.32020276
OS 38.2382903 -38.32020276
OS 38.2382903 -38.39601668
OE
OB 37.4339231 -38.32112732 I
OS 37.44224414 -38.32112732
OS 37.4616599 -38.32205188
OS 37.48200022 -38.32482556
OS 37.50418966 -38.32759924
OS 37.52452998 -38.33222204
OS 37.53470014 -38.33499572
OS 37.54302118 -38.3377694
OS 37.54394574 -38.3377694
OS 37.5448703 -38.33869396
OS 37.55041766 -38.34146764
OS 37.5587387 -38.34516588
OS 37.56890886 -38.3516378
OS 37.58000358 -38.35995884
OS 37.59202286 -38.37105356
OS 37.60311758 -38.3839974
OS 37.6142123 -38.39879036
OS 37.6142123 -38.39971492
OS 37.61513686 -38.40063948
OS 37.6188351 -38.40618684
OS 37.62253334 -38.41543244
OS 37.6280807 -38.42745172
OS 37.6327035 -38.44132012
OS 37.6373263 -38.4579622
OS 37.64009998 -38.47552884
OS 37.64102454 -38.4949446
OS 37.64102454 -38.49586916
OS 37.64102454 -38.49771828
OS 37.64102454 -38.50141652
OS 37.64009998 -38.50603932
OS 37.64009998 -38.51251124
OS 37.63917542 -38.51898316
OS 37.63547718 -38.53470068
OS 37.62992982 -38.55319188
OS 37.62253334 -38.57260764
OS 37.61143862 -38.5920234
OS 37.60404214 -38.601269
OS 37.59664566 -38.6105146
OS 37.5957211 -38.61143916
OS 37.59479654 -38.61236372
OS 37.59202286 -38.6151374
OS 37.58832462 -38.61791108
OS 37.58370182 -38.62160932
OS 37.57815446 -38.62530756
OS 37.57075798 -38.62993036
OS 37.5633615 -38.63547772
OS 37.5541159 -38.64010052
OS 37.54394574 -38.64472332
OS 37.53285102 -38.65027068
OS 37.52083174 -38.65489348
OS 37.50696334 -38.65859172
OS 37.49309494 -38.66321452
OS 37.47737742 -38.6659882
OS 37.46073534 -38.66876188
OS 37.46258446 -38.66968644
OS 37.4662827 -38.67153556
OS 37.47183006 -38.6752338
OS 37.47922654 -38.67893204
OS 37.49586862 -38.6891022
OS 37.50418966 -38.69557412
OS 37.51158614 -38.70112148
OS 37.51343526 -38.7029706
OS 37.51805806 -38.7075934
OS 37.52545454 -38.71498988
OS 37.53470014 -38.72423548
OS 37.5448703 -38.73717932
OS 37.55688958 -38.75104772
OS 37.56890886 -38.7676898
OS 37.5818527 -38.786181
OS 37.69187534 -38.95999828
OS 37.5864755 -38.95999828
OS 37.50234054 -38.82686164
OS 37.50234054 -38.82593708
OS 37.50049142 -38.82408796
OS 37.4986423 -38.82131428
OS 37.49586862 -38.81761604
OS 37.4893967 -38.80744588
OS 37.48107566 -38.79450204
OS 37.4709055 -38.78063364
OS 37.46073534 -38.76584068
OS 37.45056518 -38.75197228
OS 37.44131958 -38.73902844
OS 37.44039502 -38.73810388
OS 37.43762134 -38.73440564
OS 37.43299854 -38.72885828
OS 37.42652662 -38.72238636
OS 37.41265822 -38.70851796
OS 37.40526174 -38.70204604
OS 37.39786526 -38.69649868
OS 37.3969407 -38.69557412
OS 37.39509158 -38.69464956
OS 37.39139334 -38.69280044
OS 37.38584598 -38.69002676
OS 37.38029862 -38.68725308
OS 37.3738267 -38.6844794
OS 37.35903374 -38.6798566
OS 37.35810918 -38.6798566
OS 37.35626006 -38.67893204
OS 37.35256182 -38.67893204
OS 37.34793902 -38.67800748
OS 37.3414671 -38.67708292
OS 37.33407062 -38.67708292
OS 37.32390046 -38.67615836
OS 37.21480238 -38.67615836
OS 37.21480238 -38.95999828
OS 37.12974286 -38.95999828
OS 37.12974286 -38.32020276
OS 37.42652662 -38.32020276
OS 37.4339231 -38.32112732
OE
OB 35.31760526 -38.95999828 I
OS 35.23254574 -38.95999828
OS 35.23254574 -38.32020276
OS 35.31760526 -38.32020276
OS 35.31760526 -38.95999828
OE
OB 42.12051774 -38.66413908 H
OS 41.95224782 -38.66413908
OS 41.95224782 -38.88418436
OS 42.13438614 -38.88418436
OS 42.1538019 -38.8832598
OS 42.16212294 -38.88233524
OS 42.16951942 -38.88141068
OS 42.17044398 -38.88141068
OS 42.17414222 -38.88048612
OS 42.17968958 -38.87956156
OS 42.1861615 -38.87771244
OS 42.20187902 -38.87216508
OS 42.21759654 -38.8647686
OS 42.2185211 -38.86384404
OS 42.22129478 -38.86199492
OS 42.22499302 -38.85922124
OS 42.22961582 -38.855523
OS 42.23423862 -38.84997564
OS 42.24071054 -38.84442828
OS 42.24533334 -38.8370318
OS 42.2508807 -38.82871076
OS 42.25180526 -38.8277862
OS 42.25272982 -38.82501252
OS 42.25457894 -38.81946516
OS 42.25735262 -38.81299324
OS 42.2601263 -38.80559676
OS 42.26197542 -38.79635116
OS 42.26289998 -38.78525644
OS 42.26382454 -38.77416172
OS 42.26382454 -38.7723126
OS 42.26382454 -38.76861436
OS 42.26289998 -38.76121788
OS 42.26105086 -38.75289684
OS 42.25920174 -38.74365124
OS 42.2555035 -38.73348108
OS 42.2508807 -38.72331092
OS 42.24440878 -38.71314076
OS 42.24348422 -38.7122162
OS 42.24071054 -38.70851796
OS 42.2370123 -38.70389516
OS 42.23146494 -38.6983478
OS 42.22406846 -38.69187588
OS 42.21482286 -38.68540396
OS 42.2046527 -38.6798566
OS 42.19263342 -38.6752338
OS 42.1907843 -38.67430924
OS 42.18708606 -38.67338468
OS 42.17876502 -38.67153556
OS 42.16859486 -38.66968644
OS 42.15565102 -38.66783732
OS 42.1399335 -38.6659882
OS 42.12051774 -38.66413908
OE
OB 45.22981302 -38.5504182 H
OS 45.22426566 -38.5504182
OS 45.21964286 -38.55134276
OS 45.2094727 -38.55226732
OS 45.1956043 -38.55596556
OS 45.17988678 -38.56151292
OS 45.1632447 -38.5689094
OS 45.14752718 -38.58000412
OS 45.13920614 -38.5874006
OS 45.13180966 -38.59479708
OS 45.13180966 -38.59572164
OS 45.12996054 -38.5966462
OS 45.12811142 -38.59941988
OS 45.12533774 -38.60311812
OS 45.12256406 -38.60774092
OS 45.11979038 -38.61328828
OS 45.11609214 -38.62068476
OS 45.1123939 -38.62808124
OS 45.10869566 -38.63732684
OS 45.10499742 -38.64657244
OS 45.10222374 -38.65766716
OS 45.09945006 -38.66968644
OS 45.09667638 -38.68263028
OS 45.09482726 -38.69649868
OS 45.0939027 -38.7122162
OS 45.09297814 -38.72793372
OS 45.09297814 -38.72885828
OS 45.09297814 -38.73163196
OS 45.09297814 -38.73625476
OS 45.0939027 -38.74272668
OS 45.0939027 -38.75012316
OS 45.09482726 -38.7584442
OS 45.09760094 -38.77785996
OS 45.10222374 -38.8000494
OS 45.10962022 -38.82223884
OS 45.11886582 -38.84350372
OS 45.12533774 -38.85274932
OS 45.13180966 -38.86199492
OS 45.13273422 -38.86199492
OS 45.13365878 -38.86384404
OS 45.13920614 -38.86846684
OS 45.14752718 -38.87586332
OS 45.1586219 -38.8832598
OS 45.1724903 -38.89158084
OS 45.18913238 -38.89897732
OS 45.20854814 -38.90360012
OS 45.2187183 -38.90452468
OS 45.22981302 -38.90544924
OS 45.23536038 -38.90544924
OS 45.23998318 -38.90452468
OS 45.25015334 -38.90267556
OS 45.26402174 -38.89990188
OS 45.2788147 -38.89435452
OS 45.29545678 -38.88695804
OS 45.3111743 -38.87586332
OS 45.31949534 -38.86846684
OS 45.32689182 -38.86107036
OS 45.32781638 -38.8601458
OS 45.32874094 -38.85922124
OS 45.33059006 -38.85644756
OS 45.33336374 -38.85274932
OS 45.33613742 -38.84812652
OS 45.33983566 -38.84257916
OS 45.3435339 -38.83518268
OS 45.34723214 -38.8277862
OS 45.35093038 -38.8185406
OS 45.35370406 -38.80837044
OS 45.3574023 -38.79727572
OS 45.36017598 -38.78525644
OS 45.36294966 -38.77138804
OS 45.36479878 -38.75751964
OS 45.3666479 -38.74180212
OS 45.3666479 -38.72516004
OS 45.3666479 -38.72423548
OS 45.3666479 -38.7214618
OS 45.3666479 -38.716839
OS 45.36572334 -38.71129164
OS 45.36572334 -38.70389516
OS 45.36479878 -38.69557412
OS 45.3620251 -38.67615836
OS 45.3574023 -38.65581804
OS 45.35000582 -38.6336286
OS 45.33983566 -38.61328828
OS 45.3342883 -38.60311812
OS 45.32689182 -38.59479708
OS 45.32689182 -38.59387252
OS 45.3250427 -38.59294796
OS 45.31949534 -38.5874006
OS 45.3111743 -38.58092868
OS 45.30007958 -38.57260764
OS 45.28621118 -38.5642866
OS 45.2695691 -38.55689012
OS 45.2510779 -38.55226732
OS 45.24090774 -38.55134276
OS 45.22981302 -38.5504182
OE
OB 32.07702246 -38.54764452 H
OS 32.07239966 -38.54764452
OS 32.06870142 -38.54856908
OS 32.05945582 -38.5504182
OS 32.04743654 -38.55319188
OS 32.03356814 -38.55873924
OS 32.01877518 -38.56706028
OS 32.01045414 -38.57260764
OS 32.00305766 -38.57907956
OS 31.99566118 -38.58647604
OS 31.9882647 -38.59479708
OS 31.9882647 -38.59572164
OS 31.98641558 -38.5966462
OS 31.98456646 -38.59941988
OS 31.98271734 -38.60311812
OS 31.97994366 -38.60866548
OS 31.97624542 -38.61421284
OS 31.97254718 -38.62160932
OS 31.9697735 -38.6290058
OS 31.96607526 -38.6382514
OS 31.96237702 -38.64842156
OS 31.95960334 -38.65951628
OS 31.9559051 -38.67153556
OS 31.95405598 -38.68540396
OS 31.95220686 -38.69927236
OS 31.95035774 -38.71406532
OS 31.95035774 -38.7307074
OS 31.95035774 -38.73163196
OS 31.95035774 -38.73440564
OS 31.95035774 -38.73902844
OS 31.9512823 -38.74550036
OS 31.9512823 -38.75289684
OS 31.95220686 -38.76121788
OS 31.95498054 -38.78063364
OS 31.95960334 -38.80282308
OS 31.9651507 -38.82408796
OS 31.9743963 -38.84535284
OS 31.97994366 -38.85459844
OS 31.98641558 -38.86291948
OS 31.9882647 -38.8647686
OS 31.9928875 -38.8693914
OS 32.00028398 -38.87678788
OS 32.01045414 -38.88418436
OS 32.02339798 -38.89158084
OS 32.03819094 -38.89897732
OS 32.05483302 -38.90360012
OS 32.06407862 -38.90452468
OS 32.07332422 -38.90544924
OS 32.07887158 -38.90544924
OS 32.08256982 -38.90452468
OS 32.09181542 -38.90267556
OS 32.10475926 -38.89990188
OS 32.11862766 -38.89435452
OS 32.13342062 -38.88695804
OS 32.14821358 -38.87586332
OS 32.15561006 -38.8693914
OS 32.16300654 -38.86199492
OS 32.16300654 -38.86107036
OS 32.16485566 -38.8601458
OS 32.16670478 -38.85737212
OS 32.1685539 -38.85367388
OS 32.17225214 -38.84905108
OS 32.17502582 -38.84257916
OS 32.17872406 -38.83610724
OS 32.1824223 -38.8277862
OS 32.18519598 -38.81946516
OS 32.18889422 -38.80837044
OS 32.19259246 -38.79727572
OS 32.19536614 -38.78525644
OS 32.19721526 -38.77138804
OS 32.19906438 -38.75659508
OS 32.2009135 -38.74087756
OS 32.2009135 -38.72423548
OS 32.2009135 -38.72331092
OS 32.2009135 -38.72053724
OS 32.2009135 -38.71591444
OS 32.19998894 -38.70944252
OS 32.19998894 -38.70204604
OS 32.19906438 -38.693725
OS 32.1962907 -38.67430924
OS 32.1916679 -38.65304436
OS 32.18519598 -38.63177948
OS 32.17595038 -38.6105146
OS 32.17040302 -38.60034444
OS 32.1639311 -38.5920234
OS 32.1639311 -38.59109884
OS 32.16208198 -38.59017428
OS 32.15745918 -38.58462692
OS 32.1500627 -38.578155
OS 32.13989254 -38.56983396
OS 32.1269487 -38.56151292
OS 32.11215574 -38.55411644
OS 32.09551366 -38.54949364
OS 32.08626806 -38.54856908
OS 32.07702246 -38.54764452
OE
OB 42.10387566 -38.39601668 H
OS 41.95224782 -38.39601668
OS 41.95224782 -38.58832516
OS 42.10942302 -38.58832516
OS 42.1214423 -38.5874006
OS 42.13438614 -38.58647604
OS 42.14732998 -38.58555148
OS 42.16027382 -38.58370236
OS 42.17044398 -38.58185324
OS 42.1722931 -38.58092868
OS 42.17599134 -38.58000412
OS 42.1815387 -38.57723044
OS 42.18893518 -38.5735322
OS 42.19633166 -38.56983396
OS 42.2046527 -38.5642866
OS 42.21297374 -38.55689012
OS 42.21944566 -38.54949364
OS 42.22037022 -38.54856908
OS 42.22221934 -38.5457954
OS 42.22499302 -38.54024804
OS 42.2277667 -38.53377612
OS 42.23054038 -38.52637964
OS 42.23331406 -38.51713404
OS 42.23516318 -38.50603932
OS 42.23608774 -38.49402004
OS 42.23608774 -38.49217092
OS 42.23608774 -38.48847268
OS 42.23516318 -38.48292532
OS 42.23423862 -38.47552884
OS 42.2323895 -38.46628324
OS 42.22961582 -38.45703764
OS 42.22591758 -38.44779204
OS 42.22037022 -38.43854644
OS 42.21944566 -38.43762188
OS 42.21759654 -38.4348482
OS 42.2138983 -38.4302254
OS 42.2092755 -38.4256026
OS 42.20280358 -38.42005524
OS 42.1954071 -38.41450788
OS 42.1861615 -38.40896052
OS 42.17599134 -38.40526228
OS 42.17506678 -38.40526228
OS 42.17044398 -38.40341316
OS 42.16397206 -38.4024886
OS 42.1538019 -38.40063948
OS 42.1399335 -38.39879036
OS 42.12421598 -38.3978658
OS 42.10387566 -38.39601668
OE
OB 37.41635646 -38.39139388 H
OS 37.21480238 -38.39139388
OS 37.21480238 -38.60311812
OS 37.40526174 -38.60311812
OS 37.41635646 -38.60219356
OS 37.4293003 -38.601269
OS 37.44409326 -38.60034444
OS 37.45888622 -38.59849532
OS 37.47367918 -38.59572164
OS 37.48662302 -38.5920234
OS 37.48847214 -38.59109884
OS 37.49217038 -38.58924972
OS 37.49771774 -38.58647604
OS 37.50511422 -38.5827778
OS 37.51343526 -38.57723044
OS 37.5217563 -38.57075852
OS 37.53007734 -38.56243748
OS 37.53654926 -38.55319188
OS 37.53747382 -38.55226732
OS 37.53932294 -38.54856908
OS 37.54209662 -38.54302172
OS 37.54579486 -38.53562524
OS 37.54856854 -38.5273042
OS 37.55134222 -38.5180586
OS 37.55319134 -38.50696388
OS 37.5541159 -38.49586916
OS 37.5541159 -38.4949446
OS 37.5541159 -38.49402004
OS 37.55319134 -38.48847268
OS 37.55226678 -38.48015164
OS 37.55041766 -38.46905692
OS 37.54579486 -38.4579622
OS 37.5402475 -38.44501836
OS 37.53192646 -38.43299908
OS 37.52083174 -38.4209798
OS 37.51898262 -38.42005524
OS 37.51435982 -38.416357
OS 37.50696334 -38.4117342
OS 37.49494406 -38.40618684
OS 37.48107566 -38.40063948
OS 37.46258446 -38.39601668
OS 37.44131958 -38.39231844
OS 37.41635646 -38.39139388
OE
OB 39.82298614 -38.54764452 H
OS 39.81836334 -38.54764452
OS 39.8146651 -38.54856908
OS 39.8054195 -38.5504182
OS 39.79340022 -38.55319188
OS 39.77953182 -38.55873924
OS 39.76473886 -38.56706028
OS 39.75641782 -38.57260764
OS 39.74902134 -38.57907956
OS 39.74162486 -38.58647604
OS 39.73422838 -38.59479708
OS 39.73422838 -38.59572164
OS 39.73237926 -38.5966462
OS 39.73053014 -38.59941988
OS 39.72868102 -38.60311812
OS 39.72590734 -38.60866548
OS 39.7222091 -38.61421284
OS 39.71851086 -38.62160932
OS 39.71573718 -38.6290058
OS 39.71203894 -38.6382514
OS 39.7083407 -38.64842156
OS 39.70556702 -38.65951628
OS 39.70186878 -38.67153556
OS 39.70001966 -38.68540396
OS 39.69817054 -38.69927236
OS 39.69632142 -38.71406532
OS 39.69632142 -38.7307074
OS 39.69632142 -38.73163196
OS 39.69632142 -38.73440564
OS 39.69632142 -38.73902844
OS 39.69724598 -38.74550036
OS 39.69724598 -38.75289684
OS 39.69817054 -38.76121788
OS 39.70094422 -38.78063364
OS 39.70556702 -38.80282308
OS 39.71111438 -38.82408796
OS 39.72035998 -38.84535284
OS 39.72590734 -38.85459844
OS 39.73237926 -38.86291948
OS 39.73422838 -38.8647686
OS 39.73885118 -38.8693914
OS 39.74624766 -38.87678788
OS 39.75641782 -38.88418436
OS 39.76936166 -38.89158084
OS 39.78415462 -38.89897732
OS 39.8007967 -38.90360012
OS 39.8100423 -38.90452468
OS 39.8192879 -38.90544924
OS 39.82483526 -38.90544924
OS 39.8285335 -38.90452468
OS 39.8377791 -38.90267556
OS 39.85072294 -38.89990188
OS 39.86459134 -38.89435452
OS 39.8793843 -38.88695804
OS 39.89417726 -38.87586332
OS 39.90157374 -38.8693914
OS 39.90897022 -38.86199492
OS 39.90897022 -38.86107036
OS 39.91081934 -38.8601458
OS 39.91266846 -38.85737212
OS 39.91451758 -38.85367388
OS 39.91821582 -38.84905108
OS 39.9209895 -38.84257916
OS 39.92468774 -38.83610724
OS 39.92838598 -38.8277862
OS 39.93115966 -38.81946516
OS 39.9348579 -38.80837044
OS 39.93855614 -38.79727572
OS 39.94132982 -38.78525644
OS 39.94317894 -38.77138804
OS 39.94502806 -38.75659508
OS 39.94687718 -38.74087756
OS 39.94687718 -38.72423548
OS 39.94687718 -38.72331092
OS 39.94687718 -38.72053724
OS 39.94687718 -38.71591444
OS 39.94595262 -38.70944252
OS 39.94595262 -38.70204604
OS 39.94502806 -38.693725
OS 39.94225438 -38.67430924
OS 39.93763158 -38.65304436
OS 39.93115966 -38.63177948
OS 39.92191406 -38.6105146
OS 39.9163667 -38.60034444
OS 39.90989478 -38.5920234
OS 39.90989478 -38.59109884
OS 39.90804566 -38.59017428
OS 39.90342286 -38.58462692
OS 39.89602638 -38.578155
OS 39.88585622 -38.56983396
OS 39.87291238 -38.56151292
OS 39.85811942 -38.55411644
OS 39.84147734 -38.54949364
OS 39.83223174 -38.54856908
OS 39.82298614 -38.54764452
OE
OB 35.73550638 -38.39601668 H
OS 35.5524435 -38.39601668
OS 35.5524435 -38.624383
OS 35.72441166 -38.624383
OS 35.73088358 -38.62345844
OS 35.7373555 -38.62345844
OS 35.74475198 -38.62253388
OS 35.76231862 -38.62068476
OS 35.78173438 -38.61698652
OS 35.80115014 -38.61143916
OS 35.81871678 -38.60404268
OS 35.82703782 -38.59941988
OS 35.83350974 -38.59387252
OS 35.83535886 -38.5920234
OS 35.8390571 -38.58832516
OS 35.84460446 -38.58092868
OS 35.85107638 -38.57168308
OS 35.8575483 -38.5596638
OS 35.86309566 -38.54487084
OS 35.8667939 -38.52822876
OS 35.86864302 -38.508813
OS 35.86864302 -38.50788844
OS 35.86864302 -38.50696388
OS 35.86864302 -38.50234108
OS 35.86771846 -38.49402004
OS 35.86586934 -38.48477444
OS 35.86402022 -38.47460428
OS 35.86032198 -38.462585
OS 35.85477462 -38.45149028
OS 35.8483027 -38.44039556
OS 35.84737814 -38.439471
OS 35.84460446 -38.43577276
OS 35.83998166 -38.43114996
OS 35.8344343 -38.42467804
OS 35.82611326 -38.41820612
OS 35.81686766 -38.41265876
OS 35.8066975 -38.4071114
OS 35.79467822 -38.4024886
OS 35.79375366 -38.4024886
OS 35.79005542 -38.40156404
OS 35.78450806 -38.40063948
OS 35.77711158 -38.39879036
OS 35.76601686 -38.3978658
OS 35.75214846 -38.39694124
OS 35.73550638 -38.39601668
OE
OB 43.44263854 -38.5504182 H
OS 43.43709118 -38.5504182
OS 43.43339294 -38.55134276
OS 43.42322278 -38.55226732
OS 43.4112035 -38.555041
OS 43.39641054 -38.5596638
OS 43.38069302 -38.56613572
OS 43.36590006 -38.57538132
OS 43.3511071 -38.5874006
OS 43.34925798 -38.58924972
OS 43.34555974 -38.59387252
OS 43.33908782 -38.60219356
OS 43.3326159 -38.61328828
OS 43.32521942 -38.62623212
OS 43.3187475 -38.6428742
OS 43.31320014 -38.66228996
OS 43.31042646 -38.68355484
OS 43.57022782 -38.68355484
OS 43.57022782 -38.68263028
OS 43.57022782 -38.68078116
OS 43.56930326 -38.67800748
OS 43.56930326 -38.67430924
OS 43.56745414 -38.66321452
OS 43.56468046 -38.65119524
OS 43.56005766 -38.63640228
OS 43.55543486 -38.62253388
OS 43.54803838 -38.60866548
OS 43.53971734 -38.5966462
OS 43.53971734 -38.59572164
OS 43.53786822 -38.59479708
OS 43.53324542 -38.58924972
OS 43.52492438 -38.58185324
OS 43.51382966 -38.5735322
OS 43.49996126 -38.56521116
OS 43.48331918 -38.55781468
OS 43.46390342 -38.55226732
OS 43.45373326 -38.55134276
OS 43.44263854 -38.5504182
OE
OB 34.35791198 -38.39601668 H
OS 34.20628414 -38.39601668
OS 34.20628414 -38.58832516
OS 34.36345934 -38.58832516
OS 34.37547862 -38.5874006
OS 34.38842246 -38.58647604
OS 34.4013663 -38.58555148
OS 34.41431014 -38.58370236
OS 34.4244803 -38.58185324
OS 34.42632942 -38.58092868
OS 34.43002766 -38.58000412
OS 34.43557502 -38.57723044
OS 34.4429715 -38.5735322
OS 34.45036798 -38.56983396
OS 34.45868902 -38.5642866
OS 34.46701006 -38.55689012
OS 34.47348198 -38.54949364
OS 34.47440654 -38.54856908
OS 34.47625566 -38.5457954
OS 34.47902934 -38.54024804
OS 34.48180302 -38.53377612
OS 34.4845767 -38.52637964
OS 34.48735038 -38.51713404
OS 34.4891995 -38.50603932
OS 34.49012406 -38.49402004
OS 34.49012406 -38.49217092
OS 34.49012406 -38.48847268
OS 34.4891995 -38.48292532
OS 34.48827494 -38.47552884
OS 34.48642582 -38.46628324
OS 34.48365214 -38.45703764
OS 34.4799539 -38.44779204
OS 34.47440654 -38.43854644
OS 34.47348198 -38.43762188
OS 34.47163286 -38.4348482
OS 34.46793462 -38.4302254
OS 34.46331182 -38.4256026
OS 34.4568399 -38.42005524
OS 34.44944342 -38.41450788
OS 34.44019782 -38.40896052
OS 34.43002766 -38.40526228
OS 34.4291031 -38.40526228
OS 34.4244803 -38.40341316
OS 34.41800838 -38.4024886
OS 34.40783822 -38.40063948
OS 34.39396982 -38.39879036
OS 34.3782523 -38.3978658
OS 34.35791198 -38.39601668
OE
OB 40.89732486 -38.39601668 H
OS 40.71426198 -38.39601668
OS 40.71426198 -38.624383
OS 40.88623014 -38.624383
OS 40.89270206 -38.62345844
OS 40.89917398 -38.62345844
OS 40.90657046 -38.62253388
OS 40.9241371 -38.62068476
OS 40.94355286 -38.61698652
OS 40.96296862 -38.61143916
OS 40.98053526 -38.60404268
OS 40.9888563 -38.59941988
OS 40.99532822 -38.59387252
OS 40.99717734 -38.5920234
OS 41.00087558 -38.58832516
OS 41.00642294 -38.58092868
OS 41.01289486 -38.57168308
OS 41.01936678 -38.5596638
OS 41.02491414 -38.54487084
OS 41.02861238 -38.52822876
OS 41.0304615 -38.508813
OS 41.0304615 -38.50788844
OS 41.0304615 -38.50696388
OS 41.0304615 -38.50234108
OS 41.02953694 -38.49402004
OS 41.02768782 -38.48477444
OS 41.0258387 -38.47460428
OS 41.02214046 -38.462585
OS 41.0165931 -38.45149028
OS 41.01012118 -38.44039556
OS 41.00919662 -38.439471
OS 41.00642294 -38.43577276
OS 41.00180014 -38.43114996
OS 40.99625278 -38.42467804
OS 40.98793174 -38.41820612
OS 40.97868614 -38.41265876
OS 40.96851598 -38.4071114
OS 40.9564967 -38.4024886
OS 40.95557214 -38.4024886
OS 40.9518739 -38.40156404
OS 40.94632654 -38.40063948
OS 40.93893006 -38.39879036
OS 40.92783534 -38.3978658
OS 40.91396694 -38.39694124
OS 40.89732486 -38.39601668
OE
OB 33.15136118 -38.39601668 H
OS 32.9682983 -38.39601668
OS 32.9682983 -38.624383
OS 33.14026646 -38.624383
OS 33.14673838 -38.62345844
OS 33.1532103 -38.62345844
OS 33.16060678 -38.62253388
OS 33.17817342 -38.62068476
OS 33.19758918 -38.61698652
OS 33.21700494 -38.61143916
OS 33.23457158 -38.60404268
OS 33.24289262 -38.59941988
OS 33.24936454 -38.59387252
OS 33.25121366 -38.5920234
OS 33.2549119 -38.58832516
OS 33.26045926 -38.58092868
OS 33.26693118 -38.57168308
OS 33.2734031 -38.5596638
OS 33.27895046 -38.54487084
OS 33.2826487 -38.52822876
OS 33.28449782 -38.508813
OS 33.28449782 -38.50788844
OS 33.28449782 -38.50696388
OS 33.28449782 -38.50234108
OS 33.28357326 -38.49402004
OS 33.28172414 -38.48477444
OS 33.27987502 -38.47460428
OS 33.27617678 -38.462585
OS 33.27062942 -38.45149028
OS 33.2641575 -38.44039556
OS 33.26323294 -38.439471
OS 33.26045926 -38.43577276
OS 33.25583646 -38.43114996
OS 33.2502891 -38.42467804
OS 33.24196806 -38.41820612
OS 33.23272246 -38.41265876
OS 33.2225523 -38.4071114
OS 33.21053302 -38.4024886
OS 33.20960846 -38.4024886
OS 33.20591022 -38.40156404
OS 33.20036286 -38.40063948
OS 33.19296638 -38.39879036
OS 33.18187166 -38.3978658
OS 33.16800326 -38.39694124
OS 33.15136118 -38.39601668
OE
OB 34.37455406 -38.66413908 H
OS 34.20628414 -38.66413908
OS 34.20628414 -38.88418436
OS 34.38842246 -38.88418436
OS 34.40783822 -38.8832598
OS 34.41615926 -38.88233524
OS 34.42355574 -38.88141068
OS 34.4244803 -38.88141068
OS 34.42817854 -38.88048612
OS 34.4337259 -38.87956156
OS 34.44019782 -38.87771244
OS 34.45591534 -38.87216508
OS 34.47163286 -38.8647686
OS 34.47255742 -38.86384404
OS 34.4753311 -38.86199492
OS 34.47902934 -38.85922124
OS 34.48365214 -38.855523
OS 34.48827494 -38.84997564
OS 34.49474686 -38.84442828
OS 34.49936966 -38.8370318
OS 34.50491702 -38.82871076
OS 34.50584158 -38.8277862
OS 34.50676614 -38.82501252
OS 34.50861526 -38.81946516
OS 34.51138894 -38.81299324
OS 34.51416262 -38.80559676
OS 34.51601174 -38.79635116
OS 34.5169363 -38.78525644
OS 34.51786086 -38.77416172
OS 34.51786086 -38.7723126
OS 34.51786086 -38.76861436
OS 34.5169363 -38.76121788
OS 34.51508718 -38.75289684
OS 34.51323806 -38.74365124
OS 34.50953982 -38.73348108
OS 34.50491702 -38.72331092
OS 34.4984451 -38.71314076
OS 34.49752054 -38.7122162
OS 34.49474686 -38.70851796
OS 34.49104862 -38.70389516
OS 34.48550126 -38.6983478
OS 34.47810478 -38.69187588
OS 34.46885918 -38.68540396
OS 34.45868902 -38.6798566
OS 34.44666974 -38.6752338
OS 34.44482062 -38.67430924
OS 34.44112238 -38.67338468
OS 34.43280134 -38.67153556
OS 34.42263118 -38.66968644
OS 34.40968734 -38.66783732
OS 34.39396982 -38.6659882
OS 34.37455406 -38.66413908
OE
SE
S P 0
OB 48.49040086 -36.61402634 I
OS 48.17420134 -36.61402634
OS 48.17420134 -37.45999874
OS 48.04661206 -37.45999874
OS 48.04661206 -36.61402634
OS 47.73041254 -36.61402634
OS 47.73041254 -36.50030546
OS 48.49040086 -36.50030546
OS 48.49040086 -36.61402634
OE
OB 47.69990206 -37.45999874 I
OS 47.5556707 -37.45999874
OS 47.44333666 -37.16876234
OS 47.04115306 -37.16876234
OS 46.93714006 -37.45999874
OS 46.80261658 -37.45999874
OS 47.16874234 -36.50030546
OS 47.30742634 -36.50030546
OS 47.69990206 -37.45999874
OE
OB 49.31834434 -36.61402634 I
OS 48.75112678 -36.61402634
OS 48.75112678 -36.90664958
OS 49.2822865 -36.90664958
OS 49.2822865 -37.02037046
OS 48.75112678 -37.02037046
OS 48.75112678 -37.34627786
OS 49.34053378 -37.34627786
OS 49.34053378 -37.45999874
OS 48.6235375 -37.45999874
OS 48.6235375 -36.50030546
OS 49.31834434 -36.50030546
OS 49.31834434 -36.61402634
OE
OB 46.33386466 -36.5016923 I
OS 46.36160146 -36.50307914
OS 46.38933826 -36.50585282
OS 46.41707506 -36.51001334
OS 46.44065134 -36.51417386
OS 46.44203818 -36.51417386
OS 46.44481186 -36.5155607
OS 46.44897238 -36.5155607
OS 46.45451974 -36.51833438
OS 46.46977498 -36.5224949
OS 46.48919074 -36.5294291
OS 46.51138018 -36.53913698
OS 46.53495646 -36.55161854
OS 46.55853274 -36.56548694
OS 46.58072218 -36.58351586
OS 46.58210902 -36.5849027
OS 46.58349586 -36.58628954
OS 46.58765638 -36.59045006
OS 46.59320374 -36.59461058
OS 46.60707214 -36.60847898
OS 46.62371422 -36.62789474
OS 46.64174314 -36.65147102
OS 46.6611589 -36.67920782
OS 46.67918782 -36.71110514
OS 46.69444306 -36.74716298
OS 46.69444306 -36.74854982
OS 46.6958299 -36.7513235
OS 46.69860358 -36.75687086
OS 46.69999042 -36.7651919
OS 46.70415094 -36.77489978
OS 46.70692462 -36.7859945
OS 46.7096983 -36.79847606
OS 46.71385882 -36.8137313
OS 46.71801934 -36.82898654
OS 46.72079302 -36.84701546
OS 46.72772722 -36.88584698
OS 46.73188774 -36.92883902
OS 46.73327458 -36.97599158
OS 46.73327458 -36.97737842
OS 46.73327458 -36.9801521
OS 46.73327458 -36.9870863
OS 46.73327458 -36.9940205
OS 46.73188774 -37.00372838
OS 46.73188774 -37.0148231
OS 46.7305009 -37.04117306
OS 46.72634038 -37.07168354
OS 46.72217986 -37.10358086
OS 46.71524566 -37.13686502
OS 46.70692462 -37.17014918
OS 46.70692462 -37.17153602
OS 46.70553778 -37.1743097
OS 46.70415094 -37.17847022
OS 46.7027641 -37.18401758
OS 46.69721674 -37.19927282
OS 46.6888957 -37.21868858
OS 46.68057466 -37.24087802
OS 46.66947994 -37.26306746
OS 46.65561154 -37.28664374
OS 46.64174314 -37.30883318
OS 46.6403563 -37.31160686
OS 46.63480894 -37.31854106
OS 46.6264879 -37.32824894
OS 46.61539318 -37.3407305
OS 46.60291162 -37.3545989
OS 46.58765638 -37.3684673
OS 46.57240114 -37.38372254
OS 46.55437222 -37.3962041
OS 46.55159854 -37.39759094
OS 46.54605118 -37.40175146
OS 46.5363433 -37.40729882
OS 46.5224749 -37.41423302
OS 46.50583282 -37.42255406
OS 46.48641706 -37.42948826
OS 46.46422762 -37.4378093
OS 46.4392645 -37.4447435
OS 46.43649082 -37.4447435
OS 46.4323303 -37.44613034
OS 46.42816978 -37.44751718
OS 46.41430138 -37.44890402
OS 46.39488562 -37.4516777
OS 46.37269618 -37.45445138
OS 46.34634622 -37.45722506
OS 46.31722258 -37.4586119
OS 46.28532526 -37.45999874
OS 45.9400021 -37.45999874
OS 45.9400021 -36.50030546
OS 46.30890154 -36.50030546
OS 46.33386466 -36.5016923
OE
OB 46.28948578 -36.61402634 H
OS 46.06759138 -36.61402634
OS 46.06759138 -37.34627786
OS 46.29503314 -37.34627786
OS 46.30474102 -37.34489102
OS 46.32554362 -37.34350418
OS 46.3491199 -37.34211734
OS 46.37408302 -37.33934366
OS 46.39904614 -37.33518314
OS 46.41984874 -37.32963578
OS 46.42262242 -37.32824894
OS 46.42955662 -37.3268621
OS 46.4392645 -37.32270158
OS 46.45174606 -37.31715422
OS 46.46561446 -37.30883318
OS 46.47948286 -37.30051214
OS 46.49335126 -37.29080426
OS 46.50721966 -37.27970954
OS 46.5086065 -37.27693586
OS 46.51415386 -37.2713885
OS 46.5224749 -37.26168062
OS 46.53218278 -37.24781222
OS 46.5432775 -37.2297833
OS 46.55575906 -37.2089807
OS 46.56685378 -37.18540442
OS 46.57656166 -37.15905446
OS 46.57656166 -37.15766762
OS 46.5779485 -37.15489394
OS 46.57933534 -37.15073342
OS 46.58072218 -37.14518606
OS 46.58210902 -37.13825186
OS 46.5848827 -37.12854398
OS 46.58765638 -37.1188361
OS 46.59043006 -37.10774138
OS 46.59459058 -37.08000458
OS 46.5987511 -37.04810726
OS 46.60152478 -37.01204942
OS 46.60291162 -36.9732179
OS 46.60291162 -36.97183106
OS 46.60291162 -36.9662837
OS 46.60291162 -36.9593495
OS 46.60152478 -36.94825478
OS 46.60152478 -36.93577322
OS 46.60013794 -36.92190482
OS 46.5987511 -36.90526274
OS 46.59736426 -36.88862066
OS 46.59043006 -36.85117598
OS 46.58210902 -36.81234446
OS 46.56962746 -36.77628662
OS 46.56130642 -36.7582577
OS 46.55298538 -36.74300246
OS 46.55298538 -36.74161562
OS 46.5502117 -36.73884194
OS 46.54743802 -36.73468142
OS 46.54466434 -36.72913406
OS 46.53356962 -36.71526566
OS 46.51970122 -36.69862358
OS 46.5016723 -36.68059466
OS 46.4808697 -36.66256574
OS 46.45729342 -36.6473105
OS 46.4323303 -36.63482894
OS 46.42955662 -36.6334421
OS 46.42262242 -36.63205526
OS 46.41014086 -36.62789474
OS 46.39211194 -36.62373422
OS 46.3699225 -36.62096054
OS 46.3421857 -36.61680002
OS 46.32554362 -36.61541318
OS 46.3075147 -36.61541318
OS 46.28948578 -36.61402634
OE
OB 47.23531066 -36.60015794 H
OS 47.23531066 -36.60154478
OS 47.23392382 -36.60431846
OS 47.23392382 -36.60986582
OS 47.23115014 -36.61541318
OS 47.2297633 -36.62512106
OS 47.22698962 -36.63482894
OS 47.22144226 -36.65840522
OS 47.21450806 -36.68614202
OS 47.20480018 -36.7166525
OS 47.1950923 -36.74993666
OS 47.18261074 -36.78460766
OS 47.07859774 -37.06474934
OS 47.4031183 -37.06474934
OS 47.30326582 -36.80124974
OS 47.30326582 -36.7998629
OS 47.30187898 -36.79570238
OS 47.2991053 -36.78876818
OS 47.29633162 -36.78044714
OS 47.2921711 -36.77073926
OS 47.28801058 -36.7582577
OS 47.28385006 -36.7443893
OS 47.2783027 -36.7305209
OS 47.26720798 -36.69862358
OS 47.25611326 -36.66533942
OS 47.24501854 -36.63205526
OS 47.23531066 -36.60015794
OE
SE
S P 0
OB 53.64989524 -38.94890356 I
OS 53.57130764 -38.94890356
OS 53.57130764 -38.4487166
OS 53.57038308 -38.44964116
OS 53.56576028 -38.4533394
OS 53.56021292 -38.45888676
OS 53.55096732 -38.46535868
OS 53.54079716 -38.47367972
OS 53.52785332 -38.48292532
OS 53.51306036 -38.49309548
OS 53.49641828 -38.50326564
OS 53.49549372 -38.50326564
OS 53.49456916 -38.5041902
OS 53.4890218 -38.50788844
OS 53.4797762 -38.51251124
OS 53.46868148 -38.5180586
OS 53.45573764 -38.52453052
OS 53.44186924 -38.53100244
OS 53.42800084 -38.53747436
OS 53.41413244 -38.54302172
OS 53.41413244 -38.4672078
OS 53.415057 -38.4672078
OS 53.41690612 -38.46535868
OS 53.42060436 -38.46443412
OS 53.42522716 -38.46166044
OS 53.43077452 -38.45888676
OS 53.43724644 -38.45518852
OS 53.45296396 -38.44594292
OS 53.47145516 -38.43577276
OS 53.48994636 -38.42282892
OS 53.50936212 -38.40803596
OS 53.52877788 -38.39231844
OS 53.52970244 -38.39139388
OS 53.530627 -38.39046932
OS 53.53340068 -38.38769564
OS 53.53709892 -38.38492196
OS 53.54541996 -38.37567636
OS 53.55651468 -38.36458164
OS 53.5676094 -38.3516378
OS 53.57962868 -38.33684484
OS 53.58979884 -38.32205188
OS 53.59904444 -38.30633436
OS 53.64989524 -38.30633436
OS 53.64989524 -38.94890356
OE
OB 54.07334372 -38.30725892 I
OS 54.0807402 -38.30818348
OS 54.08906124 -38.30910804
OS 54.09830684 -38.3100326
OS 54.10755244 -38.31280628
OS 54.12974188 -38.31835364
OS 54.15193132 -38.32667468
OS 54.16302604 -38.33222204
OS 54.17412076 -38.33869396
OS 54.18429092 -38.347015
OS 54.19446108 -38.35533604
OS 54.19538564 -38.3562606
OS 54.1963102 -38.35718516
OS 54.19908388 -38.35995884
OS 54.20278212 -38.36365708
OS 54.20648036 -38.36920444
OS 54.21110316 -38.3747518
OS 54.22034876 -38.3886202
OS 54.22959436 -38.40618684
OS 54.2379154 -38.42652716
OS 54.24438732 -38.44964116
OS 54.24531188 -38.46166044
OS 54.24623644 -38.47460428
OS 54.24623644 -38.47552884
OS 54.24623644 -38.4764534
OS 54.24623644 -38.48200076
OS 54.24531188 -38.4903218
OS 54.24346276 -38.50049196
OS 54.24068908 -38.5134358
OS 54.23606628 -38.52637964
OS 54.23051892 -38.53932348
OS 54.22219788 -38.55226732
OS 54.22127332 -38.55411644
OS 54.21757508 -38.55781468
OS 54.21202772 -38.56336204
OS 54.20463124 -38.57075852
OS 54.19446108 -38.57907956
OS 54.1824418 -38.5874006
OS 54.1685734 -38.59572164
OS 54.15193132 -38.60311812
OS 54.15285588 -38.60311812
OS 54.154705 -38.60404268
OS 54.15747868 -38.60496724
OS 54.16117692 -38.60681636
OS 54.17227164 -38.61143916
OS 54.18521548 -38.61791108
OS 54.19908388 -38.62715668
OS 54.21387684 -38.63732684
OS 54.22774524 -38.65027068
OS 54.24068908 -38.66506364
OS 54.24068908 -38.6659882
OS 54.24161364 -38.66691276
OS 54.24531188 -38.67246012
OS 54.25085924 -38.68170572
OS 54.2564066 -38.693725
OS 54.26195396 -38.70851796
OS 54.26750132 -38.7260846
OS 54.27119956 -38.74550036
OS 54.27212412 -38.76676524
OS 54.27212412 -38.7676898
OS 54.27212412 -38.77046348
OS 54.27212412 -38.77508628
OS 54.27119956 -38.78063364
OS 54.270275 -38.78710556
OS 54.26935044 -38.7954266
OS 54.26750132 -38.8046722
OS 54.26472764 -38.81484236
OS 54.25825572 -38.83610724
OS 54.25363292 -38.84812652
OS 54.247161 -38.85922124
OS 54.24068908 -38.87124052
OS 54.2332926 -38.88233524
OS 54.224047 -38.89342996
OS 54.21387684 -38.90452468
OS 54.21295228 -38.90544924
OS 54.21110316 -38.90729836
OS 54.20832948 -38.91007204
OS 54.20370668 -38.91284572
OS 54.19723476 -38.91746852
OS 54.19076284 -38.92209132
OS 54.1824418 -38.92671412
OS 54.1731962 -38.93226148
OS 54.16302604 -38.93780884
OS 54.15100676 -38.94243164
OS 54.13806292 -38.94705444
OS 54.12511908 -38.95167724
OS 54.11032612 -38.95445092
OS 54.0946086 -38.9572246
OS 54.07889108 -38.95907372
OS 54.06132444 -38.95999828
OS 54.05207884 -38.95999828
OS 54.04560692 -38.95907372
OS 54.03728588 -38.95814916
OS 54.02804028 -38.9572246
OS 54.01787012 -38.95537548
OS 54.0067754 -38.9526018
OS 53.98181228 -38.94612988
OS 53.96886844 -38.94150708
OS 53.95684916 -38.93688428
OS 53.94390532 -38.93041236
OS 53.93096148 -38.92301588
OS 53.9189422 -38.91469484
OS 53.90784748 -38.90452468
OS 53.90692292 -38.90360012
OS 53.9050738 -38.901751
OS 53.90230012 -38.89897732
OS 53.89860188 -38.89435452
OS 53.89490364 -38.88880716
OS 53.88935628 -38.88233524
OS 53.88473348 -38.87493876
OS 53.87918612 -38.86569316
OS 53.87363876 -38.85644756
OS 53.86901596 -38.84535284
OS 53.85977036 -38.82223884
OS 53.85607212 -38.80837044
OS 53.85329844 -38.79450204
OS 53.85144932 -38.77970908
OS 53.85052476 -38.76491612
OS 53.85052476 -38.76399156
OS 53.85052476 -38.76214244
OS 53.85052476 -38.7584442
OS 53.85144932 -38.75474596
OS 53.85144932 -38.7491986
OS 53.85237388 -38.74272668
OS 53.854223 -38.72793372
OS 53.85792124 -38.71129164
OS 53.8634686 -38.69464956
OS 53.87178964 -38.67708292
OS 53.8819598 -38.66044084
OS 53.8819598 -38.65951628
OS 53.88380892 -38.65859172
OS 53.88750716 -38.65396892
OS 53.89490364 -38.64657244
OS 53.9050738 -38.63732684
OS 53.91801764 -38.62808124
OS 53.93373516 -38.61791108
OS 53.9513018 -38.60959004
OS 53.97256668 -38.60311812
OS 53.97164212 -38.60311812
OS 53.97071756 -38.60219356
OS 53.96794388 -38.601269
OS 53.96424564 -38.59941988
OS 53.9559246 -38.59572164
OS 53.94482988 -38.59017428
OS 53.9328106 -38.5827778
OS 53.92079132 -38.5735322
OS 53.9096966 -38.56336204
OS 53.89952644 -38.55226732
OS 53.89860188 -38.5504182
OS 53.8958282 -38.54671996
OS 53.89212996 -38.53932348
OS 53.88843172 -38.53007788
OS 53.88380892 -38.5180586
OS 53.88011068 -38.5041902
OS 53.877337 -38.48847268
OS 53.87641244 -38.4718306
OS 53.87641244 -38.47090604
OS 53.87641244 -38.46905692
OS 53.87641244 -38.46535868
OS 53.877337 -38.45981132
OS 53.87826156 -38.45426396
OS 53.87918612 -38.44686748
OS 53.88288436 -38.43114996
OS 53.88843172 -38.41265876
OS 53.89767732 -38.393243
OS 53.90322468 -38.38307284
OS 53.9096966 -38.37290268
OS 53.91801764 -38.36365708
OS 53.92633868 -38.35441148
OS 53.92726324 -38.35348692
OS 53.92911236 -38.35256236
OS 53.93188604 -38.34978868
OS 53.93558428 -38.347015
OS 53.94020708 -38.34331676
OS 53.946679 -38.33961852
OS 53.95407548 -38.33499572
OS 53.96147196 -38.33037292
OS 53.97071756 -38.32575012
OS 53.98088772 -38.32112732
OS 53.99198244 -38.31742908
OS 54.00400172 -38.31373084
OS 54.0298894 -38.30818348
OS 54.04468236 -38.30725892
OS 54.05947532 -38.30633436
OS 54.06779636 -38.30633436
OS 54.07334372 -38.30725892
OE
OB 53.23846604 -38.94890356 I
OS 53.14878372 -38.94890356
OS 53.14878372 -38.85922124
OS 53.23846604 -38.85922124
OS 53.23846604 -38.94890356
OE
OB 53.00177868 -38.39231844 I
OS 52.74567556 -38.39231844
OS 52.71146684 -38.56521116
OS 52.7123914 -38.5642866
OS 52.71424052 -38.56336204
OS 52.7170142 -38.56151292
OS 52.721637 -38.55873924
OS 52.72718436 -38.55596556
OS 52.73365628 -38.55226732
OS 52.74844924 -38.54487084
OS 52.76694044 -38.53747436
OS 52.78728076 -38.53100244
OS 52.8094702 -38.52637964
OS 52.82056492 -38.52453052
OS 52.84090524 -38.52453052
OS 52.8464526 -38.52545508
OS 52.85384908 -38.52637964
OS 52.86217012 -38.5273042
OS 52.87141572 -38.52915332
OS 52.88158588 -38.531927
OS 52.90377532 -38.53839892
OS 52.9157946 -38.54302172
OS 52.92781388 -38.54949364
OS 52.93983316 -38.55596556
OS 52.95185244 -38.56336204
OS 52.96294716 -38.57260764
OS 52.97404188 -38.5827778
OS 52.97496644 -38.58370236
OS 52.97681556 -38.58555148
OS 52.97958924 -38.58832516
OS 52.98328748 -38.59294796
OS 52.98791028 -38.59941988
OS 52.99253308 -38.6058918
OS 52.99808044 -38.61421284
OS 53.0036278 -38.62345844
OS 53.0082506 -38.6336286
OS 53.01379796 -38.64472332
OS 53.01842076 -38.65766716
OS 53.02304356 -38.670611
OS 53.0267418 -38.6844794
OS 53.02951548 -38.70019692
OS 53.0313646 -38.71591444
OS 53.03228916 -38.73255652
OS 53.03228916 -38.73348108
OS 53.03228916 -38.73625476
OS 53.03228916 -38.74087756
OS 53.0313646 -38.74734948
OS 53.03044004 -38.75474596
OS 53.02951548 -38.763067
OS 53.02766636 -38.77323716
OS 53.02581724 -38.78340732
OS 53.02026988 -38.80744588
OS 53.01102428 -38.832409
OS 53.00547692 -38.84535284
OS 52.99808044 -38.85737212
OS 52.99068396 -38.87031596
OS 52.98143836 -38.88233524
OS 52.9805138 -38.8832598
OS 52.97866468 -38.88603348
OS 52.97496644 -38.88973172
OS 52.97034364 -38.89435452
OS 52.96387172 -38.89990188
OS 52.95647524 -38.90729836
OS 52.94722964 -38.91377028
OS 52.93705948 -38.92116676
OS 52.92596476 -38.92856324
OS 52.91302092 -38.93503516
OS 52.89915252 -38.94150708
OS 52.88435956 -38.947979
OS 52.86864204 -38.9526018
OS 52.8510754 -38.95630004
OS 52.8325842 -38.95907372
OS 52.81316844 -38.95999828
OS 52.8048474 -38.95999828
OS 52.79837548 -38.95907372
OS 52.790979 -38.95814916
OS 52.78265796 -38.9572246
OS 52.7724878 -38.95630004
OS 52.76231764 -38.95352636
OS 52.73920364 -38.947979
OS 52.71608964 -38.93965796
OS 52.70407036 -38.9341106
OS 52.69205108 -38.92763868
OS 52.68095636 -38.9202422
OS 52.66986164 -38.91192116
OS 52.66893708 -38.9109966
OS 52.66708796 -38.91007204
OS 52.66523884 -38.9063738
OS 52.6615406 -38.90267556
OS 52.6569178 -38.89805276
OS 52.652295 -38.8925054
OS 52.64674764 -38.88510892
OS 52.64212484 -38.87678788
OS 52.63657748 -38.86846684
OS 52.63103012 -38.85829668
OS 52.62085996 -38.83610724
OS 52.61253892 -38.81021956
OS 52.60976524 -38.79635116
OS 52.60791612 -38.7815582
OS 52.69020196 -38.77508628
OS 52.69020196 -38.77601084
OS 52.69020196 -38.77785996
OS 52.69112652 -38.78063364
OS 52.69205108 -38.78525644
OS 52.69482476 -38.7954266
OS 52.698523 -38.809295
OS 52.70407036 -38.8231634
OS 52.71146684 -38.83888092
OS 52.72071244 -38.85274932
OS 52.73180716 -38.86569316
OS 52.73365628 -38.86661772
OS 52.73735452 -38.87031596
OS 52.744751 -38.87493876
OS 52.75492116 -38.88048612
OS 52.76601588 -38.88603348
OS 52.77988428 -38.89065628
OS 52.7956018 -38.89435452
OS 52.81316844 -38.89527908
OS 52.8187158 -38.89527908
OS 52.82241404 -38.89435452
OS 52.83350876 -38.89342996
OS 52.8464526 -38.88973172
OS 52.86217012 -38.88510892
OS 52.87788764 -38.87771244
OS 52.89452972 -38.86661772
OS 52.9019262 -38.8601458
OS 52.90932268 -38.85274932
OS 52.91024724 -38.85182476
OS 52.9111718 -38.8509002
OS 52.91302092 -38.84812652
OS 52.9157946 -38.84535284
OS 52.92226652 -38.83518268
OS 52.929663 -38.82223884
OS 52.93613492 -38.80652132
OS 52.94260684 -38.78710556
OS 52.94722964 -38.76399156
OS 52.94907876 -38.75197228
OS 52.94907876 -38.73902844
OS 52.94907876 -38.73810388
OS 52.94907876 -38.73625476
OS 52.94907876 -38.73255652
OS 52.9481542 -38.72793372
OS 52.9481542 -38.72238636
OS 52.94722964 -38.71591444
OS 52.94445596 -38.70112148
OS 52.93983316 -38.68355484
OS 52.93336124 -38.6659882
OS 52.92411564 -38.64934612
OS 52.9111718 -38.6336286
OS 52.9111718 -38.63270404
OS 52.90932268 -38.63177948
OS 52.90469988 -38.62715668
OS 52.89637884 -38.62068476
OS 52.88528412 -38.61328828
OS 52.87049116 -38.60681636
OS 52.85384908 -38.60034444
OS 52.83443332 -38.59572164
OS 52.8233386 -38.59387252
OS 52.80577196 -38.59387252
OS 52.79837548 -38.59479708
OS 52.78912988 -38.59572164
OS 52.77803516 -38.59849532
OS 52.76694044 -38.601269
OS 52.75492116 -38.6058918
OS 52.74290188 -38.61143916
OS 52.74197732 -38.61236372
OS 52.73827908 -38.61421284
OS 52.73273172 -38.61883564
OS 52.72533524 -38.62345844
OS 52.71793876 -38.62993036
OS 52.71054228 -38.6382514
OS 52.70222124 -38.64657244
OS 52.69574932 -38.6567426
OS 52.62178452 -38.64657244
OS 52.68373004 -38.31742908
OS 53.00177868 -38.31742908
OS 53.00177868 -38.39231844
OE
OB 53.23846604 -38.57445676 I
OS 53.14878372 -38.57445676
OS 53.14878372 -38.48477444
OS 53.23846604 -38.48477444
OS 53.23846604 -38.57445676
OE
OB 54.48199924 -38.57445676 I
OS 54.39231692 -38.57445676
OS 54.39231692 -38.48477444
OS 54.48199924 -38.48477444
OS 54.48199924 -38.57445676
OE
OB 56.14990548 -38.3100326 I
OS 56.165623 -38.31095716
OS 56.18226508 -38.31188172
OS 56.1979826 -38.31373084
OS 56.211851 -38.31557996
OS 56.21370012 -38.31557996
OS 56.22017204 -38.31742908
OS 56.22849308 -38.3192782
OS 56.2395878 -38.32205188
OS 56.25160708 -38.32667468
OS 56.26455092 -38.33222204
OS 56.27841932 -38.33869396
OS 56.2904386 -38.34609044
OS 56.29228772 -38.347015
OS 56.29598596 -38.34978868
OS 56.30153332 -38.35533604
OS 56.3089298 -38.36180796
OS 56.31725084 -38.370129
OS 56.32557188 -38.38122372
OS 56.33481748 -38.393243
OS 56.34221396 -38.4071114
OS 56.34313852 -38.40896052
OS 56.34498764 -38.41358332
OS 56.34868588 -38.42190436
OS 56.35238412 -38.43299908
OS 56.3551578 -38.44594292
OS 56.35885604 -38.46073588
OS 56.36070516 -38.47737796
OS 56.36162972 -38.4949446
OS 56.36162972 -38.49586916
OS 56.36162972 -38.49864284
OS 56.36162972 -38.50234108
OS 56.36070516 -38.508813
OS 56.3597806 -38.51528492
OS 56.35885604 -38.52360596
OS 56.35700692 -38.53285156
OS 56.3551578 -38.54302172
OS 56.34868588 -38.5642866
OS 56.34498764 -38.57538132
OS 56.33944028 -38.5874006
OS 56.33296836 -38.59941988
OS 56.32649644 -38.6105146
OS 56.3181754 -38.62160932
OS 56.3089298 -38.63270404
OS 56.30800524 -38.6336286
OS 56.30615612 -38.63547772
OS 56.30338244 -38.6382514
OS 56.29875964 -38.64102508
OS 56.29321228 -38.64564788
OS 56.2858158 -38.65027068
OS 56.2765702 -38.65581804
OS 56.26640004 -38.66044084
OS 56.25438076 -38.6659882
OS 56.24051236 -38.67153556
OS 56.2257194 -38.67615836
OS 56.20815276 -38.6798566
OS 56.18966156 -38.68355484
OS 56.16932124 -38.68632852
OS 56.14620724 -38.68817764
OS 56.12216868 -38.6891022
OS 55.95852156 -38.6891022
OS 55.95852156 -38.94890356
OS 55.87346204 -38.94890356
OS 55.87346204 -38.30910804
OS 56.13603708 -38.30910804
OS 56.14990548 -38.3100326
OE
OB 57.07723916 -38.94890356 I
OS 56.99587788 -38.94890356
OS 56.99587788 -38.41358332
OS 56.80911676 -38.94890356
OS 56.73330284 -38.94890356
OS 56.54839084 -38.40433772
OS 56.54839084 -38.94890356
OS 56.46702956 -38.94890356
OS 56.46702956 -38.30910804
OS 56.59369428 -38.30910804
OS 56.74532212 -38.763067
OS 56.74532212 -38.76399156
OS 56.74624668 -38.76584068
OS 56.74717124 -38.76861436
OS 56.74902036 -38.77323716
OS 56.7527186 -38.78433188
OS 56.7573414 -38.79820028
OS 56.7619642 -38.8139178
OS 56.76751156 -38.82963532
OS 56.77213436 -38.84442828
OS 56.7758326 -38.85737212
OS 56.77675716 -38.855523
OS 56.77768172 -38.8509002
OS 56.7804554 -38.84257916
OS 56.78415364 -38.83148444
OS 56.78877644 -38.81669148
OS 56.79524836 -38.79912484
OS 56.80172028 -38.77878452
OS 56.81004132 -38.75474596
OS 56.96351828 -38.30910804
OS 57.07723916 -38.30910804
OS 57.07723916 -38.94890356
OE
OB 55.39084172 -38.94890356 I
OS 55.31225412 -38.94890356
OS 55.31225412 -38.4487166
OS 55.31132956 -38.44964116
OS 55.30670676 -38.4533394
OS 55.3011594 -38.45888676
OS 55.2919138 -38.46535868
OS 55.28174364 -38.47367972
OS 55.2687998 -38.48292532
OS 55.25400684 -38.49309548
OS 55.23736476 -38.50326564
OS 55.2364402 -38.50326564
OS 55.23551564 -38.5041902
OS 55.22996828 -38.50788844
OS 55.22072268 -38.51251124
OS 55.20962796 -38.5180586
OS 55.19668412 -38.52453052
OS 55.18281572 -38.53100244
OS 55.16894732 -38.53747436
OS 55.15507892 -38.54302172
OS 55.15507892 -38.4672078
OS 55.15600348 -38.4672078
OS 55.1578526 -38.46535868
OS 55.16155084 -38.46443412
OS 55.16617364 -38.46166044
OS 55.171721 -38.45888676
OS 55.17819292 -38.45518852
OS 55.19391044 -38.44594292
OS 55.21240164 -38.43577276
OS 55.23089284 -38.42282892
OS 55.2503086 -38.40803596
OS 55.26972436 -38.39231844
OS 55.27064892 -38.39139388
OS 55.27157348 -38.39046932
OS 55.27434716 -38.38769564
OS 55.2780454 -38.38492196
OS 55.28636644 -38.37567636
OS 55.29746116 -38.36458164
OS 55.30855588 -38.3516378
OS 55.32057516 -38.33684484
OS 55.33074532 -38.32205188
OS 55.33999092 -38.30633436
OS 55.39084172 -38.30633436
OS 55.39084172 -38.94890356
OE
OB 54.48199924 -38.94890356 I
OS 54.39231692 -38.94890356
OS 54.39231692 -38.85922124
OS 54.48199924 -38.85922124
OS 54.48199924 -38.94890356
OE
OB 54.825011 -38.30725892 I
OS 54.83703028 -38.30910804
OS 54.85089868 -38.31188172
OS 54.86569164 -38.31557996
OS 54.88140916 -38.32020276
OS 54.89620212 -38.32759924
OS 54.89712668 -38.32759924
OS 54.89805124 -38.3285238
OS 54.90267404 -38.33129748
OS 54.91007052 -38.33592028
OS 54.91931612 -38.3423922
OS 54.92948628 -38.3516378
OS 54.940581 -38.36180796
OS 54.95075116 -38.37382724
OS 54.96092132 -38.38769564
OS 54.96184588 -38.38954476
OS 54.96554412 -38.39416756
OS 54.96924236 -38.4024886
OS 54.97571428 -38.41450788
OS 54.98126164 -38.42837628
OS 54.98865812 -38.4440938
OS 54.99513004 -38.462585
OS 55.0006774 -38.48292532
OS 55.0006774 -38.48384988
OS 55.00160196 -38.485699
OS 55.00252652 -38.48847268
OS 55.00345108 -38.49309548
OS 55.00437564 -38.49864284
OS 55.0053002 -38.50511476
OS 55.00714932 -38.5134358
OS 55.00807388 -38.5226814
OS 55.009923 -38.53285156
OS 55.01084756 -38.54394628
OS 55.01177212 -38.55689012
OS 55.01362124 -38.56983396
OS 55.0145458 -38.58462692
OS 55.0145458 -38.59941988
OS 55.01547036 -38.61606196
OS 55.01547036 -38.6336286
OS 55.01547036 -38.63455316
OS 55.01547036 -38.6382514
OS 55.01547036 -38.64472332
OS 55.01547036 -38.6521198
OS 55.0145458 -38.66228996
OS 55.0145458 -38.67338468
OS 55.01362124 -38.68540396
OS 55.01269668 -38.6983478
OS 55.009923 -38.72793372
OS 55.0053002 -38.7584442
OS 54.99975284 -38.78803012
OS 54.9960546 -38.80189852
OS 54.9914318 -38.81576692
OS 54.9914318 -38.81669148
OS 54.99050724 -38.8185406
OS 54.98865812 -38.82223884
OS 54.986809 -38.82686164
OS 54.98495988 -38.83333356
OS 54.98126164 -38.83980548
OS 54.97386516 -38.855523
OS 54.96461956 -38.87216508
OS 54.95260028 -38.89065628
OS 54.93873188 -38.90729836
OS 54.9220898 -38.92301588
OS 54.92116524 -38.92301588
OS 54.92024068 -38.924865
OS 54.917467 -38.92671412
OS 54.91376876 -38.92856324
OS 54.90914596 -38.93133692
OS 54.90452316 -38.93503516
OS 54.89065476 -38.94150708
OS 54.87401268 -38.947979
OS 54.85459692 -38.95445092
OS 54.83148292 -38.95814916
OS 54.8065198 -38.95999828
OS 54.7972742 -38.95999828
OS 54.79080228 -38.95907372
OS 54.7834058 -38.95814916
OS 54.7741602 -38.95630004
OS 54.76399004 -38.95445092
OS 54.75289532 -38.95167724
OS 54.7418006 -38.947979
OS 54.72978132 -38.94428076
OS 54.71776204 -38.9387334
OS 54.70574276 -38.93226148
OS 54.69372348 -38.924865
OS 54.6817042 -38.9156194
OS 54.67060948 -38.90544924
OS 54.66043932 -38.89435452
OS 54.65951476 -38.89342996
OS 54.65766564 -38.89065628
OS 54.65489196 -38.88603348
OS 54.65026916 -38.878637
OS 54.64564636 -38.87031596
OS 54.64102356 -38.85922124
OS 54.63455164 -38.8462774
OS 54.62900428 -38.83148444
OS 54.62345692 -38.81484236
OS 54.61790956 -38.7954266
OS 54.6123622 -38.77416172
OS 54.6077394 -38.75012316
OS 54.6031166 -38.72423548
OS 54.60034292 -38.69649868
OS 54.5984938 -38.6659882
OS 54.59756924 -38.6336286
OS 54.59756924 -38.63270404
OS 54.59756924 -38.6290058
OS 54.59756924 -38.62253388
OS 54.59756924 -38.6151374
OS 54.5984938 -38.60496724
OS 54.5984938 -38.59387252
OS 54.59941836 -38.58185324
OS 54.60034292 -38.56798484
OS 54.6031166 -38.53932348
OS 54.6077394 -38.508813
OS 54.61328676 -38.47830252
OS 54.616985 -38.46443412
OS 54.62068324 -38.45056572
OS 54.62068324 -38.44964116
OS 54.6216078 -38.44779204
OS 54.62345692 -38.4440938
OS 54.62530604 -38.439471
OS 54.62715516 -38.43299908
OS 54.6308534 -38.42652716
OS 54.63824988 -38.41080964
OS 54.64749548 -38.39416756
OS 54.65951476 -38.37660092
OS 54.67338316 -38.35903428
OS 54.69002524 -38.34424132
OS 54.6909498 -38.34424132
OS 54.69187436 -38.3423922
OS 54.69464804 -38.34054308
OS 54.69834628 -38.33869396
OS 54.70296908 -38.33499572
OS 54.70851644 -38.33222204
OS 54.72238484 -38.32482556
OS 54.73902692 -38.31835364
OS 54.75844268 -38.31188172
OS 54.78155668 -38.30818348
OS 54.8065198 -38.30633436
OS 54.81484084 -38.30633436
OS 54.825011 -38.30725892
OE
OB 49.95350436 -38.72331092 I
OS 50.040413 -38.72331092
OS 50.040413 -38.7954266
OS 49.95350436 -38.7954266
OS 49.95350436 -38.94890356
OS 49.87491676 -38.94890356
OS 49.87491676 -38.7954266
OS 49.5966242 -38.7954266
OS 49.5966242 -38.72331092
OS 49.88970972 -38.30910804
OS 49.95350436 -38.30910804
OS 49.95350436 -38.72331092
OE
OB 50.1467374 -38.95999828 I
OS 50.08386732 -38.95999828
OS 50.26970388 -38.29801332
OS 50.33257396 -38.29801332
OS 50.1467374 -38.95999828
OE
OB 50.59699812 -38.30725892 I
OS 50.6043946 -38.30818348
OS 50.6136402 -38.30910804
OS 50.62381036 -38.31095716
OS 50.63398052 -38.31280628
OS 50.65801908 -38.3192782
OS 50.68205764 -38.3285238
OS 50.69407692 -38.33407116
OS 50.7060962 -38.34054308
OS 50.71719092 -38.34886412
OS 50.72736108 -38.35810972
OS 50.72828564 -38.35903428
OS 50.73013476 -38.35995884
OS 50.73198388 -38.36365708
OS 50.73568212 -38.36735532
OS 50.74030492 -38.37197812
OS 50.74492772 -38.37845004
OS 50.74955052 -38.38492196
OS 50.75509788 -38.393243
OS 50.76434348 -38.41080964
OS 50.77358908 -38.43299908
OS 50.77728732 -38.4440938
OS 50.77913644 -38.45703764
OS 50.78098556 -38.46998148
OS 50.78191012 -38.48384988
OS 50.78191012 -38.485699
OS 50.78191012 -38.4903218
OS 50.78098556 -38.49771828
OS 50.780061 -38.50788844
OS 50.77821188 -38.51898316
OS 50.77451364 -38.531927
OS 50.7708154 -38.5457954
OS 50.76526804 -38.5596638
OS 50.76434348 -38.56151292
OS 50.76249436 -38.56613572
OS 50.75879612 -38.5735322
OS 50.75324876 -38.58370236
OS 50.74585228 -38.59479708
OS 50.73660668 -38.60866548
OS 50.72551196 -38.62253388
OS 50.71256812 -38.6382514
OS 50.710719 -38.64010052
OS 50.7060962 -38.64564788
OS 50.7014734 -38.65027068
OS 50.6968506 -38.65489348
OS 50.69130324 -38.66044084
OS 50.68390676 -38.66783732
OS 50.67651028 -38.6752338
OS 50.66726468 -38.68355484
OS 50.65801908 -38.69280044
OS 50.64692436 -38.7029706
OS 50.63490508 -38.71314076
OS 50.62196124 -38.72516004
OS 50.60716828 -38.73717932
OS 50.59237532 -38.75012316
OS 50.59145076 -38.75104772
OS 50.58960164 -38.75289684
OS 50.5859034 -38.75567052
OS 50.5812806 -38.75936876
OS 50.57573324 -38.76491612
OS 50.56926132 -38.77046348
OS 50.55446836 -38.78248276
OS 50.53875084 -38.79635116
OS 50.52395788 -38.81021956
OS 50.51101404 -38.82223884
OS 50.50546668 -38.82686164
OS 50.50084388 -38.83148444
OS 50.49991932 -38.832409
OS 50.49714564 -38.83518268
OS 50.4934474 -38.83888092
OS 50.4888246 -38.84442828
OS 50.4842018 -38.8509002
OS 50.47865444 -38.85737212
OS 50.46755972 -38.87308964
OS 50.78283468 -38.87308964
OS 50.78283468 -38.94890356
OS 50.35846164 -38.94890356
OS 50.35846164 -38.947979
OS 50.35846164 -38.94428076
OS 50.35846164 -38.9387334
OS 50.3593862 -38.93133692
OS 50.36031076 -38.92301588
OS 50.36215988 -38.91377028
OS 50.364009 -38.90452468
OS 50.36770724 -38.89435452
OS 50.36770724 -38.89342996
OS 50.3686318 -38.8925054
OS 50.37048092 -38.88695804
OS 50.37417916 -38.878637
OS 50.37972652 -38.86754228
OS 50.387123 -38.85459844
OS 50.3963686 -38.83980548
OS 50.40653876 -38.82501252
OS 50.4194826 -38.809295
OS 50.4194826 -38.80837044
OS 50.42133172 -38.80744588
OS 50.42595452 -38.80189852
OS 50.43427556 -38.79357748
OS 50.44629484 -38.7815582
OS 50.46016324 -38.7676898
OS 50.47772988 -38.75104772
OS 50.49899476 -38.73255652
OS 50.52210876 -38.71314076
OS 50.52303332 -38.7122162
OS 50.52673156 -38.70944252
OS 50.53227892 -38.70481972
OS 50.53875084 -38.69927236
OS 50.54707188 -38.69187588
OS 50.55724204 -38.68355484
OS 50.5674122 -38.67430924
OS 50.57943148 -38.66413908
OS 50.60254548 -38.64194964
OS 50.62565948 -38.6197602
OS 50.6367542 -38.60866548
OS 50.64692436 -38.59757076
OS 50.65616996 -38.5874006
OS 50.66356644 -38.57723044
OS 50.66356644 -38.57630588
OS 50.66541556 -38.57538132
OS 50.66726468 -38.57260764
OS 50.6691138 -38.5689094
OS 50.67558572 -38.55873924
OS 50.6829822 -38.54671996
OS 50.68945412 -38.531927
OS 50.69592604 -38.51620948
OS 50.69962428 -38.49864284
OS 50.7014734 -38.48200076
OS 50.7014734 -38.4810762
OS 50.7014734 -38.48015164
OS 50.70054884 -38.47460428
OS 50.69962428 -38.46535868
OS 50.6968506 -38.45518852
OS 50.69315236 -38.44224468
OS 50.68668044 -38.42930084
OS 50.6783594 -38.416357
OS 50.66726468 -38.40341316
OS 50.66541556 -38.40156404
OS 50.66079276 -38.3978658
OS 50.65432084 -38.393243
OS 50.64415068 -38.38677108
OS 50.63120684 -38.38122372
OS 50.61641388 -38.37567636
OS 50.59884724 -38.37197812
OS 50.57943148 -38.37105356
OS 50.57388412 -38.37105356
OS 50.57018588 -38.37197812
OS 50.55909116 -38.37290268
OS 50.54614732 -38.37567636
OS 50.53227892 -38.3793746
OS 50.5165614 -38.38584652
OS 50.50176844 -38.39416756
OS 50.48790004 -38.40526228
OS 50.48605092 -38.4071114
OS 50.48235268 -38.4117342
OS 50.47680532 -38.41913068
OS 50.47125796 -38.4302254
OS 50.46478604 -38.44316924
OS 50.45923868 -38.45981132
OS 50.45554044 -38.47830252
OS 50.45369132 -38.4995674
OS 50.3732546 -38.49124636
OS 50.3732546 -38.4903218
OS 50.37417916 -38.48754812
OS 50.37417916 -38.48292532
OS 50.37510372 -38.4764534
OS 50.37695284 -38.46905692
OS 50.37880196 -38.46073588
OS 50.38157564 -38.45056572
OS 50.38434932 -38.44039556
OS 50.3917458 -38.41820612
OS 50.40284052 -38.39601668
OS 50.40931244 -38.38492196
OS 50.41763348 -38.37382724
OS 50.42595452 -38.36365708
OS 50.43520012 -38.35441148
OS 50.43612468 -38.35348692
OS 50.4379738 -38.35256236
OS 50.44074748 -38.34978868
OS 50.44537028 -38.347015
OS 50.45091764 -38.34331676
OS 50.45738956 -38.33961852
OS 50.46478604 -38.33499572
OS 50.47403164 -38.33037292
OS 50.4842018 -38.32575012
OS 50.49529652 -38.32112732
OS 50.5073158 -38.31742908
OS 50.52025964 -38.31373084
OS 50.53412804 -38.31095716
OS 50.548921 -38.30818348
OS 50.56463852 -38.30725892
OS 50.5812806 -38.30633436
OS 50.5905262 -38.30633436
OS 50.59699812 -38.30725892
OE
OB 48.67576244 -38.94890356 I
OS 48.59717484 -38.94890356
OS 48.59717484 -38.4487166
OS 48.59625028 -38.44964116
OS 48.59162748 -38.4533394
OS 48.58608012 -38.45888676
OS 48.57683452 -38.46535868
OS 48.56666436 -38.47367972
OS 48.55372052 -38.48292532
OS 48.53892756 -38.49309548
OS 48.52228548 -38.50326564
OS 48.52136092 -38.50326564
OS 48.52043636 -38.5041902
OS 48.514889 -38.50788844
OS 48.5056434 -38.51251124
OS 48.49454868 -38.5180586
OS 48.48160484 -38.52453052
OS 48.46773644 -38.53100244
OS 48.45386804 -38.53747436
OS 48.43999964 -38.54302172
OS 48.43999964 -38.4672078
OS 48.4409242 -38.4672078
OS 48.44277332 -38.46535868
OS 48.44647156 -38.46443412
OS 48.45109436 -38.46166044
OS 48.45664172 -38.45888676
OS 48.46311364 -38.45518852
OS 48.47883116 -38.44594292
OS 48.49732236 -38.43577276
OS 48.51581356 -38.42282892
OS 48.53522932 -38.40803596
OS 48.55464508 -38.39231844
OS 48.55556964 -38.39139388
OS 48.5564942 -38.39046932
OS 48.55926788 -38.38769564
OS 48.56296612 -38.38492196
OS 48.57128716 -38.37567636
OS 48.58238188 -38.36458164
OS 48.5934766 -38.3516378
OS 48.60549588 -38.33684484
OS 48.61566604 -38.32205188
OS 48.62491164 -38.30633436
OS 48.67576244 -38.30633436
OS 48.67576244 -38.94890356
OE
OB 48.9032042 -38.95999828 I
OS 48.84033412 -38.95999828
OS 49.02617068 -38.29801332
OS 49.08904076 -38.29801332
OS 48.9032042 -38.95999828
OE
OB 49.35346492 -38.30725892 I
OS 49.3608614 -38.30818348
OS 49.370107 -38.30910804
OS 49.38027716 -38.31095716
OS 49.39044732 -38.31280628
OS 49.41448588 -38.3192782
OS 49.43852444 -38.3285238
OS 49.45054372 -38.33407116
OS 49.462563 -38.34054308
OS 49.47365772 -38.34886412
OS 49.48382788 -38.35810972
OS 49.48475244 -38.35903428
OS 49.48660156 -38.35995884
OS 49.48845068 -38.36365708
OS 49.49214892 -38.36735532
OS 49.49677172 -38.37197812
OS 49.50139452 -38.37845004
OS 49.50601732 -38.38492196
OS 49.51156468 -38.393243
OS 49.52081028 -38.41080964
OS 49.53005588 -38.43299908
OS 49.53375412 -38.4440938
OS 49.53560324 -38.45703764
OS 49.53745236 -38.46998148
OS 49.53837692 -38.48384988
OS 49.53837692 -38.485699
OS 49.53837692 -38.4903218
OS 49.53745236 -38.49771828
OS 49.5365278 -38.50788844
OS 49.53467868 -38.51898316
OS 49.53098044 -38.531927
OS 49.5272822 -38.5457954
OS 49.52173484 -38.5596638
OS 49.52081028 -38.56151292
OS 49.51896116 -38.56613572
OS 49.51526292 -38.5735322
OS 49.50971556 -38.58370236
OS 49.50231908 -38.59479708
OS 49.49307348 -38.60866548
OS 49.48197876 -38.62253388
OS 49.46903492 -38.6382514
OS 49.4671858 -38.64010052
OS 49.462563 -38.64564788
OS 49.4579402 -38.65027068
OS 49.4533174 -38.65489348
OS 49.44777004 -38.66044084
OS 49.44037356 -38.66783732
OS 49.43297708 -38.6752338
OS 49.42373148 -38.68355484
OS 49.41448588 -38.69280044
OS 49.40339116 -38.7029706
OS 49.39137188 -38.71314076
OS 49.37842804 -38.72516004
OS 49.36363508 -38.73717932
OS 49.34884212 -38.75012316
OS 49.34791756 -38.75104772
OS 49.34606844 -38.75289684
OS 49.3423702 -38.75567052
OS 49.3377474 -38.75936876
OS 49.33220004 -38.76491612
OS 49.32572812 -38.77046348
OS 49.31093516 -38.78248276
OS 49.29521764 -38.79635116
OS 49.28042468 -38.81021956
OS 49.26748084 -38.82223884
OS 49.26193348 -38.82686164
OS 49.25731068 -38.83148444
OS 49.25638612 -38.832409
OS 49.25361244 -38.83518268
OS 49.2499142 -38.83888092
OS 49.2452914 -38.84442828
OS 49.2406686 -38.8509002
OS 49.23512124 -38.85737212
OS 49.22402652 -38.87308964
OS 49.53930148 -38.87308964
OS 49.53930148 -38.94890356
OS 49.11492844 -38.94890356
OS 49.11492844 -38.947979
OS 49.11492844 -38.94428076
OS 49.11492844 -38.9387334
OS 49.115853 -38.93133692
OS 49.11677756 -38.92301588
OS 49.11862668 -38.91377028
OS 49.1204758 -38.90452468
OS 49.12417404 -38.89435452
OS 49.12417404 -38.89342996
OS 49.1250986 -38.8925054
OS 49.12694772 -38.88695804
OS 49.13064596 -38.878637
OS 49.13619332 -38.86754228
OS 49.1435898 -38.85459844
OS 49.1528354 -38.83980548
OS 49.16300556 -38.82501252
OS 49.1759494 -38.809295
OS 49.1759494 -38.80837044
OS 49.17779852 -38.80744588
OS 49.18242132 -38.80189852
OS 49.19074236 -38.79357748
OS 49.20276164 -38.7815582
OS 49.21663004 -38.7676898
OS 49.23419668 -38.75104772
OS 49.25546156 -38.73255652
OS 49.27857556 -38.71314076
OS 49.27950012 -38.7122162
OS 49.28319836 -38.70944252
OS 49.28874572 -38.70481972
OS 49.29521764 -38.69927236
OS 49.30353868 -38.69187588
OS 49.31370884 -38.68355484
OS 49.323879 -38.67430924
OS 49.33589828 -38.66413908
OS 49.35901228 -38.64194964
OS 49.38212628 -38.6197602
OS 49.393221 -38.60866548
OS 49.40339116 -38.59757076
OS 49.41263676 -38.5874006
OS 49.42003324 -38.57723044
OS 49.42003324 -38.57630588
OS 49.42188236 -38.57538132
OS 49.42373148 -38.57260764
OS 49.4255806 -38.5689094
OS 49.43205252 -38.55873924
OS 49.439449 -38.54671996
OS 49.44592092 -38.531927
OS 49.45239284 -38.51620948
OS 49.45609108 -38.49864284
OS 49.4579402 -38.48200076
OS 49.4579402 -38.4810762
OS 49.4579402 -38.48015164
OS 49.45701564 -38.47460428
OS 49.45609108 -38.46535868
OS 49.4533174 -38.45518852
OS 49.44961916 -38.44224468
OS 49.44314724 -38.42930084
OS 49.4348262 -38.416357
OS 49.42373148 -38.40341316
OS 49.42188236 -38.40156404
OS 49.41725956 -38.3978658
OS 49.41078764 -38.393243
OS 49.40061748 -38.38677108
OS 49.38767364 -38.38122372
OS 49.37288068 -38.37567636
OS 49.35531404 -38.37197812
OS 49.33589828 -38.37105356
OS 49.33035092 -38.37105356
OS 49.32665268 -38.37197812
OS 49.31555796 -38.37290268
OS 49.30261412 -38.37567636
OS 49.28874572 -38.3793746
OS 49.2730282 -38.38584652
OS 49.25823524 -38.39416756
OS 49.24436684 -38.40526228
OS 49.24251772 -38.4071114
OS 49.23881948 -38.4117342
OS 49.23327212 -38.41913068
OS 49.22772476 -38.4302254
OS 49.22125284 -38.44316924
OS 49.21570548 -38.45981132
OS 49.21200724 -38.47830252
OS 49.21015812 -38.4995674
OS 49.1297214 -38.49124636
OS 49.1297214 -38.4903218
OS 49.13064596 -38.48754812
OS 49.13064596 -38.48292532
OS 49.13157052 -38.4764534
OS 49.13341964 -38.46905692
OS 49.13526876 -38.46073588
OS 49.13804244 -38.45056572
OS 49.14081612 -38.44039556
OS 49.1482126 -38.41820612
OS 49.15930732 -38.39601668
OS 49.16577924 -38.38492196
OS 49.17410028 -38.37382724
OS 49.18242132 -38.36365708
OS 49.19166692 -38.35441148
OS 49.19259148 -38.35348692
OS 49.1944406 -38.35256236
OS 49.19721428 -38.34978868
OS 49.20183708 -38.347015
OS 49.20738444 -38.34331676
OS 49.21385636 -38.33961852
OS 49.22125284 -38.33499572
OS 49.23049844 -38.33037292
OS 49.2406686 -38.32575012
OS 49.25176332 -38.32112732
OS 49.2637826 -38.31742908
OS 49.27672644 -38.31373084
OS 49.29059484 -38.31095716
OS 49.3053878 -38.30818348
OS 49.32110532 -38.30725892
OS 49.3377474 -38.30633436
OS 49.346993 -38.30633436
OS 49.35346492 -38.30725892
OE
OB 51.0944114 -38.30725892 I
OS 51.10643068 -38.30910804
OS 51.12029908 -38.31188172
OS 51.13509204 -38.31557996
OS 51.15080956 -38.32020276
OS 51.16560252 -38.32759924
OS 51.16652708 -38.32759924
OS 51.16745164 -38.3285238
OS 51.17207444 -38.33129748
OS 51.17947092 -38.33592028
OS 51.18871652 -38.3423922
OS 51.19888668 -38.3516378
OS 51.2099814 -38.36180796
OS 51.22015156 -38.37382724
OS 51.23032172 -38.38769564
OS 51.23124628 -38.38954476
OS 51.23494452 -38.39416756
OS 51.23864276 -38.4024886
OS 51.24511468 -38.41450788
OS 51.25066204 -38.42837628
OS 51.25805852 -38.4440938
OS 51.26453044 -38.462585
OS 51.2700778 -38.48292532
OS 51.2700778 -38.48384988
OS 51.27100236 -38.485699
OS 51.27192692 -38.48847268
OS 51.27285148 -38.49309548
OS 51.27377604 -38.49864284
OS 51.2747006 -38.50511476
OS 51.27654972 -38.5134358
OS 51.27747428 -38.5226814
OS 51.2793234 -38.53285156
OS 51.28024796 -38.54394628
OS 51.28117252 -38.55689012
OS 51.28302164 -38.56983396
OS 51.2839462 -38.58462692
OS 51.2839462 -38.59941988
OS 51.28487076 -38.61606196
OS 51.28487076 -38.6336286
OS 51.28487076 -38.63455316
OS 51.28487076 -38.6382514
OS 51.28487076 -38.64472332
OS 51.28487076 -38.6521198
OS 51.2839462 -38.66228996
OS 51.2839462 -38.67338468
OS 51.28302164 -38.68540396
OS 51.28209708 -38.6983478
OS 51.2793234 -38.72793372
OS 51.2747006 -38.7584442
OS 51.26915324 -38.78803012
OS 51.265455 -38.80189852
OS 51.2608322 -38.81576692
OS 51.2608322 -38.81669148
OS 51.25990764 -38.8185406
OS 51.25805852 -38.82223884
OS 51.2562094 -38.82686164
OS 51.25436028 -38.83333356
OS 51.25066204 -38.83980548
OS 51.24326556 -38.855523
OS 51.23401996 -38.87216508
OS 51.22200068 -38.89065628
OS 51.20813228 -38.90729836
OS 51.1914902 -38.92301588
OS 51.19056564 -38.92301588
OS 51.18964108 -38.924865
OS 51.1868674 -38.92671412
OS 51.18316916 -38.92856324
OS 51.17854636 -38.93133692
OS 51.17392356 -38.93503516
OS 51.16005516 -38.94150708
OS 51.14341308 -38.947979
OS 51.12399732 -38.95445092
OS 51.10088332 -38.95814916
OS 51.0759202 -38.95999828
OS 51.0666746 -38.95999828
OS 51.06020268 -38.95907372
OS 51.0528062 -38.95814916
OS 51.0435606 -38.95630004
OS 51.03339044 -38.95445092
OS 51.02229572 -38.95167724
OS 51.011201 -38.947979
OS 50.99918172 -38.94428076
OS 50.98716244 -38.9387334
OS 50.97514316 -38.93226148
OS 50.96312388 -38.924865
OS 50.9511046 -38.9156194
OS 50.94000988 -38.90544924
OS 50.92983972 -38.89435452
OS 50.92891516 -38.89342996
OS 50.92706604 -38.89065628
OS 50.92429236 -38.88603348
OS 50.91966956 -38.878637
OS 50.91504676 -38.87031596
OS 50.91042396 -38.85922124
OS 50.90395204 -38.8462774
OS 50.89840468 -38.83148444
OS 50.89285732 -38.81484236
OS 50.88730996 -38.7954266
OS 50.8817626 -38.77416172
OS 50.8771398 -38.75012316
OS 50.872517 -38.72423548
OS 50.86974332 -38.69649868
OS 50.8678942 -38.6659882
OS 50.86696964 -38.6336286
OS 50.86696964 -38.63270404
OS 50.86696964 -38.6290058
OS 50.86696964 -38.62253388
OS 50.86696964 -38.6151374
OS 50.8678942 -38.60496724
OS 50.8678942 -38.59387252
OS 50.86881876 -38.58185324
OS 50.86974332 -38.56798484
OS 50.872517 -38.53932348
OS 50.8771398 -38.508813
OS 50.88268716 -38.47830252
OS 50.8863854 -38.46443412
OS 50.89008364 -38.45056572
OS 50.89008364 -38.44964116
OS 50.8910082 -38.44779204
OS 50.89285732 -38.4440938
OS 50.89470644 -38.439471
OS 50.89655556 -38.43299908
OS 50.9002538 -38.42652716
OS 50.90765028 -38.41080964
OS 50.91689588 -38.39416756
OS 50.92891516 -38.37660092
OS 50.94278356 -38.35903428
OS 50.95942564 -38.34424132
OS 50.9603502 -38.34424132
OS 50.96127476 -38.3423922
OS 50.96404844 -38.34054308
OS 50.96774668 -38.33869396
OS 50.97236948 -38.33499572
OS 50.97791684 -38.33222204
OS 50.99178524 -38.32482556
OS 51.00842732 -38.31835364
OS 51.02784308 -38.31188172
OS 51.05095708 -38.30818348
OS 51.0759202 -38.30633436
OS 51.08424124 -38.30633436
OS 51.0944114 -38.30725892
OE
OB 51.59182468 -38.30725892 I
OS 51.59922116 -38.30818348
OS 51.60846676 -38.30910804
OS 51.61863692 -38.31095716
OS 51.62880708 -38.31280628
OS 51.65284564 -38.3192782
OS 51.6768842 -38.3285238
OS 51.68890348 -38.33407116
OS 51.70092276 -38.34054308
OS 51.71201748 -38.34886412
OS 51.72218764 -38.35810972
OS 51.7231122 -38.35903428
OS 51.72496132 -38.35995884
OS 51.72681044 -38.36365708
OS 51.73050868 -38.36735532
OS 51.73513148 -38.37197812
OS 51.73975428 -38.37845004
OS 51.74437708 -38.38492196
OS 51.74992444 -38.393243
OS 51.75917004 -38.41080964
OS 51.76841564 -38.43299908
OS 51.77211388 -38.4440938
OS 51.773963 -38.45703764
OS 51.77581212 -38.46998148
OS 51.77673668 -38.48384988
OS 51.77673668 -38.485699
OS 51.77673668 -38.4903218
OS 51.77581212 -38.49771828
OS 51.77488756 -38.50788844
OS 51.77303844 -38.51898316
OS 51.7693402 -38.531927
OS 51.76564196 -38.5457954
OS 51.7600946 -38.5596638
OS 51.75917004 -38.56151292
OS 51.75732092 -38.56613572
OS 51.75362268 -38.5735322
OS 51.74807532 -38.58370236
OS 51.74067884 -38.59479708
OS 51.73143324 -38.60866548
OS 51.72033852 -38.62253388
OS 51.70739468 -38.6382514
OS 51.70554556 -38.64010052
OS 51.70092276 -38.64564788
OS 51.69629996 -38.65027068
OS 51.69167716 -38.65489348
OS 51.6861298 -38.66044084
OS 51.67873332 -38.66783732
OS 51.67133684 -38.6752338
OS 51.66209124 -38.68355484
OS 51.65284564 -38.69280044
OS 51.64175092 -38.7029706
OS 51.62973164 -38.71314076
OS 51.6167878 -38.72516004
OS 51.60199484 -38.73717932
OS 51.58720188 -38.75012316
OS 51.58627732 -38.75104772
OS 51.5844282 -38.75289684
OS 51.58072996 -38.75567052
OS 51.57610716 -38.75936876
OS 51.5705598 -38.76491612
OS 51.56408788 -38.77046348
OS 51.54929492 -38.78248276
OS 51.5335774 -38.79635116
OS 51.51878444 -38.81021956
OS 51.5058406 -38.82223884
OS 51.50029324 -38.82686164
OS 51.49567044 -38.83148444
OS 51.49474588 -38.832409
OS 51.4919722 -38.83518268
OS 51.48827396 -38.83888092
OS 51.48365116 -38.84442828
OS 51.47902836 -38.8509002
OS 51.473481 -38.85737212
OS 51.46238628 -38.87308964
OS 51.77766124 -38.87308964
OS 51.77766124 -38.94890356
OS 51.3532882 -38.94890356
OS 51.3532882 -38.947979
OS 51.3532882 -38.94428076
OS 51.3532882 -38.9387334
OS 51.35421276 -38.93133692
OS 51.35513732 -38.92301588
OS 51.35698644 -38.91377028
OS 51.35883556 -38.90452468
OS 51.3625338 -38.89435452
OS 51.3625338 -38.89342996
OS 51.36345836 -38.8925054
OS 51.36530748 -38.88695804
OS 51.36900572 -38.878637
OS 51.37455308 -38.86754228
OS 51.38194956 -38.85459844
OS 51.39119516 -38.83980548
OS 51.40136532 -38.82501252
OS 51.41430916 -38.809295
OS 51.41430916 -38.80837044
OS 51.41615828 -38.80744588
OS 51.42078108 -38.80189852
OS 51.42910212 -38.79357748
OS 51.4411214 -38.7815582
OS 51.4549898 -38.7676898
OS 51.47255644 -38.75104772
OS 51.49382132 -38.73255652
OS 51.51693532 -38.71314076
OS 51.51785988 -38.7122162
OS 51.52155812 -38.70944252
OS 51.52710548 -38.70481972
OS 51.5335774 -38.69927236
OS 51.54189844 -38.69187588
OS 51.5520686 -38.68355484
OS 51.56223876 -38.67430924
OS 51.57425804 -38.66413908
OS 51.59737204 -38.64194964
OS 51.62048604 -38.6197602
OS 51.63158076 -38.60866548
OS 51.64175092 -38.59757076
OS 51.65099652 -38.5874006
OS 51.658393 -38.57723044
OS 51.658393 -38.57630588
OS 51.66024212 -38.57538132
OS 51.66209124 -38.57260764
OS 51.66394036 -38.5689094
OS 51.67041228 -38.55873924
OS 51.67780876 -38.54671996
OS 51.68428068 -38.531927
OS 51.6907526 -38.51620948
OS 51.69445084 -38.49864284
OS 51.69629996 -38.48200076
OS 51.69629996 -38.4810762
OS 51.69629996 -38.48015164
OS 51.6953754 -38.47460428
OS 51.69445084 -38.46535868
OS 51.69167716 -38.45518852
OS 51.68797892 -38.44224468
OS 51.681507 -38.42930084
OS 51.67318596 -38.416357
OS 51.66209124 -38.40341316
OS 51.66024212 -38.40156404
OS 51.65561932 -38.3978658
OS 51.6491474 -38.393243
OS 51.63897724 -38.38677108
OS 51.6260334 -38.38122372
OS 51.61124044 -38.37567636
OS 51.5936738 -38.37197812
OS 51.57425804 -38.37105356
OS 51.56871068 -38.37105356
OS 51.56501244 -38.37197812
OS 51.55391772 -38.37290268
OS 51.54097388 -38.37567636
OS 51.52710548 -38.3793746
OS 51.51138796 -38.38584652
OS 51.496595 -38.39416756
OS 51.4827266 -38.40526228
OS 51.48087748 -38.4071114
OS 51.47717924 -38.4117342
OS 51.47163188 -38.41913068
OS 51.46608452 -38.4302254
OS 51.4596126 -38.44316924
OS 51.45406524 -38.45981132
OS 51.450367 -38.47830252
OS 51.44851788 -38.4995674
OS 51.36808116 -38.49124636
OS 51.36808116 -38.4903218
OS 51.36900572 -38.48754812
OS 51.36900572 -38.48292532
OS 51.36993028 -38.4764534
OS 51.3717794 -38.46905692
OS 51.37362852 -38.46073588
OS 51.3764022 -38.45056572
OS 51.37917588 -38.44039556
OS 51.38657236 -38.41820612
OS 51.39766708 -38.39601668
OS 51.404139 -38.38492196
OS 51.41246004 -38.37382724
OS 51.42078108 -38.36365708
OS 51.43002668 -38.35441148
OS 51.43095124 -38.35348692
OS 51.43280036 -38.35256236
OS 51.43557404 -38.34978868
OS 51.44019684 -38.347015
OS 51.4457442 -38.34331676
OS 51.45221612 -38.33961852
OS 51.4596126 -38.33499572
OS 51.4688582 -38.33037292
OS 51.47902836 -38.32575012
OS 51.49012308 -38.32112732
OS 51.50214236 -38.31742908
OS 51.5150862 -38.31373084
OS 51.5289546 -38.31095716
OS 51.54374756 -38.30818348
OS 51.55946508 -38.30725892
OS 51.57610716 -38.30633436
OS 51.58535276 -38.30633436
OS 51.59182468 -38.30725892
OE
OB 52.08184148 -38.30725892 I
OS 52.09386076 -38.30910804
OS 52.10865372 -38.31188172
OS 52.1252958 -38.31650452
OS 52.14193788 -38.32205188
OS 52.15857996 -38.32944836
OS 52.15950452 -38.32944836
OS 52.16042908 -38.33037292
OS 52.16597644 -38.3331466
OS 52.17429748 -38.33869396
OS 52.18354308 -38.34516588
OS 52.1946378 -38.35441148
OS 52.20573252 -38.36458164
OS 52.21682724 -38.37660092
OS 52.22607284 -38.39046932
OS 52.2269974 -38.39231844
OS 52.22977108 -38.39694124
OS 52.23346932 -38.40526228
OS 52.23809212 -38.41543244
OS 52.24271492 -38.42745172
OS 52.24641316 -38.44132012
OS 52.24918684 -38.45703764
OS 52.2501114 -38.47275516
OS 52.2501114 -38.47460428
OS 52.2501114 -38.48015164
OS 52.24918684 -38.48754812
OS 52.24733772 -38.49771828
OS 52.24456404 -38.50973756
OS 52.23994124 -38.5226814
OS 52.23439388 -38.53562524
OS 52.2269974 -38.54856908
OS 52.22607284 -38.5504182
OS 52.22329916 -38.55411644
OS 52.2177518 -38.56058836
OS 52.21035532 -38.56798484
OS 52.20110972 -38.57630588
OS 52.190015 -38.58555148
OS 52.17707116 -38.59387252
OS 52.16135364 -38.60219356
OS 52.1622782 -38.60219356
OS 52.16412732 -38.60311812
OS 52.166901 -38.60404268
OS 52.17059924 -38.60496724
OS 52.1807694 -38.60866548
OS 52.19371324 -38.61421284
OS 52.2085062 -38.62160932
OS 52.22329916 -38.63085492
OS 52.23716756 -38.6428742
OS 52.2501114 -38.6567426
OS 52.25103596 -38.65859172
OS 52.2547342 -38.66413908
OS 52.26028156 -38.67338468
OS 52.26582892 -38.68540396
OS 52.27137628 -38.70019692
OS 52.27692364 -38.71776356
OS 52.28062188 -38.73810388
OS 52.28154644 -38.76029332
OS 52.28154644 -38.76121788
OS 52.28154644 -38.76399156
OS 52.28154644 -38.76861436
OS 52.28062188 -38.77416172
OS 52.27969732 -38.7815582
OS 52.2778482 -38.78987924
OS 52.27599908 -38.79912484
OS 52.27414996 -38.809295
OS 52.26675348 -38.83148444
OS 52.26120612 -38.84350372
OS 52.25565876 -38.85459844
OS 52.24826228 -38.86661772
OS 52.23994124 -38.878637
OS 52.23069564 -38.89065628
OS 52.21960092 -38.901751
OS 52.21867636 -38.90267556
OS 52.21682724 -38.90452468
OS 52.213129 -38.90729836
OS 52.2085062 -38.9109966
OS 52.20295884 -38.9156194
OS 52.19556236 -38.9202422
OS 52.18724132 -38.92578956
OS 52.17707116 -38.93041236
OS 52.166901 -38.93595972
OS 52.15488172 -38.94150708
OS 52.14286244 -38.94612988
OS 52.12899404 -38.95075268
OS 52.11420108 -38.95445092
OS 52.09848356 -38.9572246
OS 52.08276604 -38.95907372
OS 52.0651994 -38.95999828
OS 52.05687836 -38.95999828
OS 52.051331 -38.95907372
OS 52.04393452 -38.95814916
OS 52.03561348 -38.9572246
OS 52.02636788 -38.95537548
OS 52.01619772 -38.95352636
OS 51.99400828 -38.947979
OS 51.97089428 -38.9387334
OS 51.958875 -38.93318604
OS 51.94778028 -38.92671412
OS 51.93668556 -38.91839308
OS 51.92559084 -38.91007204
OS 51.92466628 -38.90914748
OS 51.92281716 -38.90729836
OS 51.92004348 -38.90452468
OS 51.9172698 -38.90082644
OS 51.912647 -38.89620364
OS 51.9080242 -38.88973172
OS 51.90247684 -38.8832598
OS 51.89692948 -38.87493876
OS 51.89138212 -38.86569316
OS 51.88583476 -38.85644756
OS 51.8756646 -38.83425812
OS 51.86734356 -38.80837044
OS 51.86456988 -38.79450204
OS 51.86272076 -38.77970908
OS 51.94130836 -38.76953892
OS 51.94130836 -38.77046348
OS 51.94223292 -38.7723126
OS 51.94315748 -38.77601084
OS 51.94408204 -38.78063364
OS 51.9450066 -38.786181
OS 51.94685572 -38.79265292
OS 51.95147852 -38.80652132
OS 51.95795044 -38.8231634
OS 51.96627148 -38.83888092
OS 51.97551708 -38.85367388
OS 51.9866118 -38.86661772
OS 51.98846092 -38.86754228
OS 51.99215916 -38.87124052
OS 51.99955564 -38.87586332
OS 52.00880124 -38.88048612
OS 52.01989596 -38.88603348
OS 52.03376436 -38.89065628
OS 52.04948188 -38.89435452
OS 52.06612396 -38.89527908
OS 52.07167132 -38.89527908
OS 52.07536956 -38.89435452
OS 52.08553972 -38.89342996
OS 52.09848356 -38.89065628
OS 52.11327652 -38.88603348
OS 52.12899404 -38.87956156
OS 52.14471156 -38.87031596
OS 52.15950452 -38.85737212
OS 52.16135364 -38.855523
OS 52.16597644 -38.84997564
OS 52.1715238 -38.8416546
OS 52.17892028 -38.83055988
OS 52.18631676 -38.81669148
OS 52.19186412 -38.80097396
OS 52.19648692 -38.78248276
OS 52.19833604 -38.76214244
OS 52.19833604 -38.76121788
OS 52.19833604 -38.75936876
OS 52.19833604 -38.75659508
OS 52.19741148 -38.75289684
OS 52.19648692 -38.74272668
OS 52.19371324 -38.7307074
OS 52.190015 -38.71591444
OS 52.18354308 -38.70112148
OS 52.17429748 -38.68632852
OS 52.1622782 -38.67246012
OS 52.16042908 -38.670611
OS 52.15580628 -38.66691276
OS 52.1484098 -38.6613654
OS 52.13823964 -38.65489348
OS 52.1252958 -38.64842156
OS 52.10957828 -38.6428742
OS 52.09201164 -38.63917596
OS 52.07259588 -38.63732684
OS 52.06427484 -38.63732684
OS 52.05780292 -38.6382514
OS 52.04948188 -38.63917596
OS 52.04023628 -38.64102508
OS 52.02914156 -38.6428742
OS 52.01712228 -38.64564788
OS 52.02636788 -38.57630588
OS 52.03099068 -38.57630588
OS 52.03468892 -38.57723044
OS 52.0467082 -38.57723044
OS 52.05687836 -38.57538132
OS 52.06889764 -38.5735322
OS 52.08276604 -38.57075852
OS 52.09848356 -38.56613572
OS 52.11327652 -38.5596638
OS 52.12899404 -38.55134276
OS 52.1299186 -38.55134276
OS 52.13084316 -38.5504182
OS 52.13546596 -38.54671996
OS 52.14193788 -38.54024804
OS 52.14933436 -38.531927
OS 52.15673084 -38.51990772
OS 52.16320276 -38.50603932
OS 52.16782556 -38.4903218
OS 52.16967468 -38.4810762
OS 52.16967468 -38.47090604
OS 52.16967468 -38.46998148
OS 52.16967468 -38.46905692
OS 52.16967468 -38.46350956
OS 52.16782556 -38.45611308
OS 52.16597644 -38.44594292
OS 52.1622782 -38.4348482
OS 52.1576554 -38.42282892
OS 52.15025892 -38.41080964
OS 52.14008876 -38.39971492
OS 52.1391642 -38.39879036
OS 52.1345414 -38.39509212
OS 52.12806948 -38.39046932
OS 52.11974844 -38.38492196
OS 52.10865372 -38.38029916
OS 52.09570988 -38.37567636
OS 52.08091692 -38.37197812
OS 52.06427484 -38.37105356
OS 52.05687836 -38.37105356
OS 52.04855732 -38.37290268
OS 52.0374626 -38.3747518
OS 52.02544332 -38.37845004
OS 52.01342404 -38.38307284
OS 52.0004802 -38.39046932
OS 51.98846092 -38.39971492
OS 51.98753636 -38.40063948
OS 51.98383812 -38.40526228
OS 51.97829076 -38.4117342
OS 51.97181884 -38.4209798
OS 51.96534692 -38.43299908
OS 51.958875 -38.44779204
OS 51.95332764 -38.46535868
OS 51.9496294 -38.485699
OS 51.8710418 -38.4718306
OS 51.8710418 -38.47090604
OS 51.87196636 -38.46813236
OS 51.87289092 -38.46443412
OS 51.87381548 -38.45888676
OS 51.8756646 -38.45241484
OS 51.87843828 -38.44501836
OS 51.88398564 -38.42745172
OS 51.89323124 -38.4071114
OS 51.90432596 -38.38677108
OS 51.91819436 -38.36735532
OS 51.935761 -38.34978868
OS 51.93668556 -38.34886412
OS 51.93853468 -38.34793956
OS 51.94130836 -38.34609044
OS 51.9450066 -38.34331676
OS 51.9496294 -38.33961852
OS 51.95610132 -38.33592028
OS 51.96257324 -38.33222204
OS 51.97089428 -38.32759924
OS 51.98938548 -38.32020276
OS 52.01065036 -38.31280628
OS 52.03561348 -38.30818348
OS 52.04855732 -38.30633436
OS 52.07167132 -38.30633436
OS 52.08184148 -38.30725892
OE
OB 56.14158444 -38.38492196 H
OS 55.95852156 -38.38492196
OS 55.95852156 -38.61328828
OS 56.13048972 -38.61328828
OS 56.13696164 -38.61236372
OS 56.14343356 -38.61236372
OS 56.15083004 -38.61143916
OS 56.16839668 -38.60959004
OS 56.18781244 -38.6058918
OS 56.2072282 -38.60034444
OS 56.22479484 -38.59294796
OS 56.23311588 -38.58832516
OS 56.2395878 -38.5827778
OS 56.24143692 -38.58092868
OS 56.24513516 -38.57723044
OS 56.25068252 -38.56983396
OS 56.25715444 -38.56058836
OS 56.26362636 -38.54856908
OS 56.26917372 -38.53377612
OS 56.27287196 -38.51713404
OS 56.27472108 -38.49771828
OS 56.27472108 -38.49679372
OS 56.27472108 -38.49586916
OS 56.27472108 -38.49124636
OS 56.27379652 -38.48292532
OS 56.2719474 -38.47367972
OS 56.27009828 -38.46350956
OS 56.26640004 -38.45149028
OS 56.26085268 -38.44039556
OS 56.25438076 -38.42930084
OS 56.2534562 -38.42837628
OS 56.25068252 -38.42467804
OS 56.24605972 -38.42005524
OS 56.24051236 -38.41358332
OS 56.23219132 -38.4071114
OS 56.22294572 -38.40156404
OS 56.21277556 -38.39601668
OS 56.20075628 -38.39139388
OS 56.19983172 -38.39139388
OS 56.19613348 -38.39046932
OS 56.19058612 -38.38954476
OS 56.18318964 -38.38769564
OS 56.17209492 -38.38677108
OS 56.15822652 -38.38584652
OS 56.14158444 -38.38492196
OE
OB 49.87491676 -38.43669732 H
OS 49.67336268 -38.72331092
OS 49.87491676 -38.72331092
OS 49.87491676 -38.43669732
OE
OB 54.06132444 -38.37105356 H
OS 54.05392796 -38.37105356
OS 54.04560692 -38.37290268
OS 54.0345122 -38.3747518
OS 54.02249292 -38.37845004
OS 54.00954908 -38.38307284
OS 53.9975298 -38.39046932
OS 53.98551052 -38.40063948
OS 53.98458596 -38.40156404
OS 53.98088772 -38.40526228
OS 53.97626492 -38.4117342
OS 53.97164212 -38.42005524
OS 53.96609476 -38.4302254
OS 53.96147196 -38.44224468
OS 53.95777372 -38.45518852
OS 53.95684916 -38.46998148
OS 53.95684916 -38.47090604
OS 53.95684916 -38.4718306
OS 53.95777372 -38.47737796
OS 53.95869828 -38.485699
OS 53.9605474 -38.49586916
OS 53.96424564 -38.50788844
OS 53.96886844 -38.51990772
OS 53.97626492 -38.53285156
OS 53.98551052 -38.54394628
OS 53.98643508 -38.54487084
OS 53.99105788 -38.54856908
OS 53.9975298 -38.55319188
OS 54.00585084 -38.55781468
OS 54.01694556 -38.56336204
OS 54.0298894 -38.56798484
OS 54.04468236 -38.57168308
OS 54.06132444 -38.57260764
OS 54.06317356 -38.57260764
OS 54.06872092 -38.57168308
OS 54.07704196 -38.57075852
OS 54.08813668 -38.5689094
OS 54.10015596 -38.56521116
OS 54.11217524 -38.56058836
OS 54.12511908 -38.55319188
OS 54.1362138 -38.54394628
OS 54.13713836 -38.54302172
OS 54.1408366 -38.53839892
OS 54.1454594 -38.53285156
OS 54.15100676 -38.52453052
OS 54.15655412 -38.51436036
OS 54.16117692 -38.50234108
OS 54.16487516 -38.48847268
OS 54.16579972 -38.47367972
OS 54.16579972 -38.47275516
OS 54.16579972 -38.4718306
OS 54.16579972 -38.46628324
OS 54.1639506 -38.4579622
OS 54.16210148 -38.44779204
OS 54.15840324 -38.43669732
OS 54.15285588 -38.42467804
OS 54.1454594 -38.41265876
OS 54.13528924 -38.40063948
OS 54.13436468 -38.39971492
OS 54.12974188 -38.39601668
OS 54.12326996 -38.39139388
OS 54.11494892 -38.38584652
OS 54.1038542 -38.38029916
OS 54.09183492 -38.37567636
OS 54.07704196 -38.37197812
OS 54.06132444 -38.37105356
OE
OB 54.05855076 -38.63640228 H
OS 54.0530034 -38.63640228
OS 54.04930516 -38.63732684
OS 54.039135 -38.6382514
OS 54.02619116 -38.64102508
OS 54.0113982 -38.64564788
OS 53.99660524 -38.6521198
OS 53.98088772 -38.6613654
OS 53.96701932 -38.67338468
OS 53.9651702 -38.6752338
OS 53.96147196 -38.6798566
OS 53.9559246 -38.68817764
OS 53.94945268 -38.6983478
OS 53.9420562 -38.7122162
OS 53.93650884 -38.72793372
OS 53.9328106 -38.74550036
OS 53.93096148 -38.76491612
OS 53.93096148 -38.76676524
OS 53.93096148 -38.77046348
OS 53.93188604 -38.7769354
OS 53.9328106 -38.78525644
OS 53.93465972 -38.7954266
OS 53.9374334 -38.80652132
OS 53.94113164 -38.81761604
OS 53.94575444 -38.82963532
OS 53.946679 -38.83055988
OS 53.94852812 -38.83518268
OS 53.95222636 -38.84073004
OS 53.95777372 -38.84720196
OS 53.96424564 -38.855523
OS 53.97256668 -38.86384404
OS 53.98181228 -38.87124052
OS 53.992907 -38.878637
OS 53.99475612 -38.87956156
OS 53.99845436 -38.88141068
OS 54.00492628 -38.88418436
OS 54.01324732 -38.88695804
OS 54.02341748 -38.88973172
OS 54.03543676 -38.8925054
OS 54.0483806 -38.89435452
OS 54.06132444 -38.89527908
OS 54.0668718 -38.89527908
OS 54.07057004 -38.89435452
OS 54.08166476 -38.89342996
OS 54.0946086 -38.89065628
OS 54.10940156 -38.88603348
OS 54.12511908 -38.88048612
OS 54.13991204 -38.87124052
OS 54.154705 -38.85922124
OS 54.15655412 -38.85737212
OS 54.16025236 -38.85274932
OS 54.16672428 -38.84442828
OS 54.1731962 -38.83425812
OS 54.17966812 -38.82131428
OS 54.18614004 -38.80559676
OS 54.18983828 -38.78710556
OS 54.1916874 -38.7676898
OS 54.1916874 -38.76676524
OS 54.1916874 -38.76491612
OS 54.1916874 -38.76214244
OS 54.19076284 -38.7584442
OS 54.18983828 -38.74827404
OS 54.1870646 -38.73440564
OS 54.1824418 -38.72053724
OS 54.17596988 -38.70481972
OS 54.16672428 -38.6891022
OS 54.15378044 -38.67430924
OS 54.15193132 -38.67246012
OS 54.14730852 -38.66876188
OS 54.13898748 -38.66228996
OS 54.12789276 -38.65489348
OS 54.11402436 -38.64842156
OS 54.09738228 -38.64194964
OS 54.07889108 -38.6382514
OS 54.05855076 -38.63640228
OE
OB 54.80559524 -38.37105356 H
OS 54.80004788 -38.37105356
OS 54.79634964 -38.37197812
OS 54.78617948 -38.37382724
OS 54.7741602 -38.37660092
OS 54.7602918 -38.38214828
OS 54.74549884 -38.39046932
OS 54.73810236 -38.39601668
OS 54.73070588 -38.40156404
OS 54.72423396 -38.40896052
OS 54.71776204 -38.41728156
OS 54.71776204 -38.41820612
OS 54.71591292 -38.42005524
OS 54.7140638 -38.42375348
OS 54.71129012 -38.42837628
OS 54.70851644 -38.43577276
OS 54.7048182 -38.4440938
OS 54.70204452 -38.45426396
OS 54.69834628 -38.46628324
OS 54.69464804 -38.48015164
OS 54.6909498 -38.49586916
OS 54.68725156 -38.5134358
OS 54.68447788 -38.53285156
OS 54.6817042 -38.555041
OS 54.67985508 -38.57907956
OS 54.67893052 -38.60496724
OS 54.67800596 -38.6336286
OS 54.67800596 -38.63547772
OS 54.67800596 -38.64010052
OS 54.67800596 -38.64842156
OS 54.67893052 -38.65951628
OS 54.67893052 -38.67153556
OS 54.67985508 -38.68632852
OS 54.68077964 -38.70204604
OS 54.68262876 -38.71868812
OS 54.68725156 -38.75474596
OS 54.69002524 -38.7723126
OS 54.69372348 -38.78895468
OS 54.69742172 -38.8046722
OS 54.70296908 -38.81946516
OS 54.70851644 -38.832409
OS 54.71498836 -38.84350372
OS 54.71498836 -38.84442828
OS 54.71683748 -38.84535284
OS 54.72146028 -38.85182476
OS 54.72978132 -38.8601458
OS 54.73995148 -38.8693914
OS 54.75381988 -38.878637
OS 54.7695374 -38.88695804
OS 54.78710404 -38.89342996
OS 54.79634964 -38.89435452
OS 54.8065198 -38.89527908
OS 54.81206716 -38.89527908
OS 54.8157654 -38.89435452
OS 54.825011 -38.8925054
OS 54.83795484 -38.88880716
OS 54.85182324 -38.88233524
OS 54.86754076 -38.87308964
OS 54.87493724 -38.86754228
OS 54.88233372 -38.8601458
OS 54.8897302 -38.85274932
OS 54.89712668 -38.84350372
OS 54.89712668 -38.84257916
OS 54.8989758 -38.84073004
OS 54.90082492 -38.83795636
OS 54.90267404 -38.83333356
OS 54.90637228 -38.82686164
OS 54.90914596 -38.8185406
OS 54.9128442 -38.809295
OS 54.91654244 -38.79820028
OS 54.91931612 -38.78433188
OS 54.92301436 -38.76953892
OS 54.9267126 -38.75197228
OS 54.92948628 -38.73348108
OS 54.9313354 -38.71129164
OS 54.93318452 -38.68817764
OS 54.93503364 -38.66228996
OS 54.93503364 -38.6336286
OS 54.93503364 -38.63270404
OS 54.93503364 -38.63177948
OS 54.93503364 -38.62715668
OS 54.93503364 -38.61883564
OS 54.93410908 -38.60774092
OS 54.93410908 -38.59572164
OS 54.93318452 -38.58092868
OS 54.93225996 -38.56521116
OS 54.93041084 -38.54764452
OS 54.92578804 -38.51251124
OS 54.92301436 -38.4949446
OS 54.91931612 -38.47830252
OS 54.91561788 -38.462585
OS 54.91007052 -38.44779204
OS 54.90452316 -38.4348482
OS 54.89805124 -38.42375348
OS 54.89805124 -38.42282892
OS 54.89620212 -38.42190436
OS 54.894353 -38.41913068
OS 54.89157932 -38.41543244
OS 54.88325828 -38.4071114
OS 54.87308812 -38.39694124
OS 54.85921972 -38.38769564
OS 54.8435022 -38.3793746
OS 54.83518116 -38.37567636
OS 54.82593556 -38.37290268
OS 54.8157654 -38.37197812
OS 54.80559524 -38.37105356
OE
OB 51.07499564 -38.37105356 H
OS 51.06944828 -38.37105356
OS 51.06575004 -38.37197812
OS 51.05557988 -38.37382724
OS 51.0435606 -38.37660092
OS 51.0296922 -38.38214828
OS 51.01489924 -38.39046932
OS 51.00750276 -38.39601668
OS 51.00010628 -38.40156404
OS 50.99363436 -38.40896052
OS 50.98716244 -38.41728156
OS 50.98716244 -38.41820612
OS 50.98531332 -38.42005524
OS 50.9834642 -38.42375348
OS 50.98069052 -38.42837628
OS 50.97791684 -38.43577276
OS 50.9742186 -38.4440938
OS 50.97144492 -38.45426396
OS 50.96774668 -38.46628324
OS 50.96404844 -38.48015164
OS 50.9603502 -38.49586916
OS 50.95665196 -38.5134358
OS 50.95387828 -38.53285156
OS 50.9511046 -38.555041
OS 50.94925548 -38.57907956
OS 50.94833092 -38.60496724
OS 50.94740636 -38.6336286
OS 50.94740636 -38.63547772
OS 50.94740636 -38.64010052
OS 50.94740636 -38.64842156
OS 50.94833092 -38.65951628
OS 50.94833092 -38.67153556
OS 50.94925548 -38.68632852
OS 50.95018004 -38.70204604
OS 50.95202916 -38.71868812
OS 50.95665196 -38.75474596
OS 50.95942564 -38.7723126
OS 50.96312388 -38.78895468
OS 50.96682212 -38.8046722
OS 50.97236948 -38.81946516
OS 50.97791684 -38.832409
OS 50.98438876 -38.84350372
OS 50.98438876 -38.84442828
OS 50.98623788 -38.84535284
OS 50.99086068 -38.85182476
OS 50.99918172 -38.8601458
OS 51.00935188 -38.8693914
OS 51.02322028 -38.878637
OS 51.0389378 -38.88695804
OS 51.05650444 -38.89342996
OS 51.06575004 -38.89435452
OS 51.0759202 -38.89527908
OS 51.08146756 -38.89527908
OS 51.0851658 -38.89435452
OS 51.0944114 -38.8925054
OS 51.10735524 -38.88880716
OS 51.12122364 -38.88233524
OS 51.13694116 -38.87308964
OS 51.14433764 -38.86754228
OS 51.15173412 -38.8601458
OS 51.1591306 -38.85274932
OS 51.16652708 -38.84350372
OS 51.16652708 -38.84257916
OS 51.1683762 -38.84073004
OS 51.17022532 -38.83795636
OS 51.17207444 -38.83333356
OS 51.17577268 -38.82686164
OS 51.17854636 -38.8185406
OS 51.1822446 -38.809295
OS 51.18594284 -38.79820028
OS 51.18871652 -38.78433188
OS 51.19241476 -38.76953892
OS 51.196113 -38.75197228
OS 51.19888668 -38.73348108
OS 51.2007358 -38.71129164
OS 51.20258492 -38.68817764
OS 51.20443404 -38.66228996
OS 51.20443404 -38.6336286
OS 51.20443404 -38.63270404
OS 51.20443404 -38.63177948
OS 51.20443404 -38.62715668
OS 51.20443404 -38.61883564
OS 51.20350948 -38.60774092
OS 51.20350948 -38.59572164
OS 51.20258492 -38.58092868
OS 51.20166036 -38.56521116
OS 51.19981124 -38.54764452
OS 51.19518844 -38.51251124
OS 51.19241476 -38.4949446
OS 51.18871652 -38.47830252
OS 51.18501828 -38.462585
OS 51.17947092 -38.44779204
OS 51.17392356 -38.4348482
OS 51.16745164 -38.42375348
OS 51.16745164 -38.42282892
OS 51.16560252 -38.42190436
OS 51.1637534 -38.41913068
OS 51.16097972 -38.41543244
OS 51.15265868 -38.4071114
OS 51.14248852 -38.39694124
OS 51.12862012 -38.38769564
OS 51.1129026 -38.3793746
OS 51.10458156 -38.37567636
OS 51.09533596 -38.37290268
OS 51.0851658 -38.37197812
OS 51.07499564 -38.37105356
OE
SE
P -2.99999908 16.00000102 4 P 0 0 ;0=3,1=1
P -2.99999908 17.99999956 4 P 0 0 ;0=3,1=1
P -2.99999908 20.00000064 4 P 0 0 ;0=3,1=1
P -2.99999908 21.99999918 4 P 0 0 ;0=3,1=1
P -2.99999908 24.00000026 4 P 0 0 ;0=3,1=1
P -2.99999908 25.9999988 4 P 0 0 ;0=3,1=1
P -2.99999908 27.99999988 4 P 0 0 ;0=3,1=1
P -2.99999908 30.00000096 4 P 0 0 ;0=3,1=1
P -2.99999908 31.9999995 4 P 0 0 ;0=3,1=1
P -2.99999908 34.00000058 4 P 0 0 ;0=3,1=1
P -2.99999908 35.99999912 4 P 0 0 ;0=3,1=1
P -2.99999908 38.0000002 4 P 0 0 ;0=3,1=1
P -2.99999908 39.99999874 4 P 0 0 ;0=3,1=1
P 0.50000154 -3.99999962 4 P 0 0 ;0=3,1=1
P 2.50000008 -3.99999962 4 P 0 0 ;0=3,1=1
P 4.50000116 -3.99999962 4 P 0 0 ;0=3,1=1
P 6.4999997 -3.99999962 4 P 0 0 ;0=3,1=1
P 8.50000078 -3.99999962 4 P 0 0 ;0=3,1=1
P 10.49999932 -3.99999962 4 P 0 0 ;0=3,1=1
P 12.5000004 -3.99999962 4 P 0 0 ;0=3,1=1
P 12.74500118 40.26499948 4 P 0 0 ;0=3,1=1
P 12.74500118 41.21500012 4 P 0 0 ;0=3,1=1
P 12.74500118 44.63999962 4 P 0 0 ;0=3,1=1
P 12.75500116 42.16500076 4 P 0 0 ;0=3,1=1
P 12.98999942 18.0150008 4 P 0 0 ;0=3,1=1
P 14.50000148 -3.99999962 4 P 0 0 ;0=3,1=1
P 15.88470534 21.56499878 4 P 0 0 ;0=3,1=1
P 16.30970576 23.03999964 4 P 0 0 ;0=3,1=1
P 16.50000002 -3.99999962 4 P 0 0 ;0=3,1=1
P 17.57500168 13.89000016 4 P 0 0 ;0=3,1=1
P 17.915001 15.69625258 4 P 0 0 ;0=3,1=1
P 18.8149992 15.10000028 4 P 0 0 ;0=3,1=1
P 18.8149992 15.98270108 4 P 0 0 ;0=3,1=1
P 18.8149992 16.85250122 4 P 0 0 ;0=3,1=1
P 19.01500134 7.39000046 4 P 0 0 ;0=3,1=1
P 19.01500134 8.5900006 4 P 0 0 ;0=3,1=1
P 19.01500134 9.7899982 4 P 0 0 ;0=3,1=1
P 19.01500134 11.09000068 4 P 0 0 ;0=3,1=1
P 19.01500134 12.39000062 4 P 0 0 ;0=3,1=1
P 21.11499968 6.76500044 4 P 0 0 ;0=3,1=1
P 21.11499968 7.78999966 4 P 0 0 ;0=3,1=1
P 21.11499968 8.9899998 4 P 0 0 ;0=3,1=1
P 21.11499968 10.28999974 4 P 0 0 ;0=3,1=1
P 21.11499968 11.38590052 4 P 0 0 ;0=3,1=1
P 22.05919388 12.29000082 4 P 0 0 ;0=3,1=1
P 22.45970616 20.01499934 4 P 0 0 ;0=3,1=1
P 23.29999912 38.90000094 4 P 0 0 ;0=3,1=1
P 23.33999904 44.0138312 4 P 0 0 ;0=3,1=1
P 23.4097068 20.04000056 4 P 0 0 ;0=3,1=1
P 24.35970744 20.04000056 4 P 0 0 ;0=3,1=1
P 24.49999926 -3.50000062 4 P 0 0 ;0=3,1=1
P 25.7999992 38.90000094 4 P 0 0 ;0=3,1=1
P 26.50000034 -3.50000062 4 P 0 0 ;0=3,1=1
P 28.50000142 -3.50000062 4 P 0 0 ;0=3,1=1
P 30.49999996 -3.50000062 4 P 0 0 ;0=3,1=1
P 32.50000104 -3.50000062 4 P 0 0 ;0=3,1=1
P 32.80000044 38.90000094 4 P 0 0 ;0=3,1=1
P 35.30000052 44.0000009 4 P 0 0 ;0=3,1=1
P 38.4999992 -3.50000062 4 P 0 0 ;0=3,1=1
P 39.60000208 38.91499964 4 P 0 0 ;0=3,1=1
P 40.50000028 -3.50000062 4 P 0 0 ;0=3,1=1
P 40.67999992 42.76499956 4 P 0 0 ;0=3,1=1
P 42.2249981 38.91499964 4 P 0 0 ;0=3,1=1
P 44.4999999 0.499999 4 P 0 0 ;0=3,1=1
P 44.4999999 2.50000008 4 P 0 0 ;0=3,1=1
P 44.4999999 4.49999862 4 P 0 0 ;0=3,1=1
P 44.4999999 6.4999997 4 P 0 0 ;0=3,1=1
P 44.4999999 8.49999824 4 P 0 0 ;0=3,1=1
P 44.4999999 10.49999932 4 P 0 0 ;0=3,1=1
P 44.4999999 12.49999786 4 P 0 0 ;0=3,1=1
P 44.4999999 14.49999894 4 P 0 0 ;0=3,1=1
P 44.4999999 16.50000002 4 P 0 0 ;0=3,1=1
P 44.4999999 18.49999856 4 P 0 0 ;0=3,1=1
P 44.4999999 20.49999964 4 P 0 0 ;0=3,1=1
P 44.4999999 22.49999818 4 P 0 0 ;0=3,1=1
P 44.4999999 24.49999926 4 P 0 0 ;0=3,1=1
P 44.4999999 26.4999978 4 P 0 0 ;0=3,1=1
P 44.4999999 28.49999888 4 P 0 0 ;0=3,1=1
P 44.4999999 30.49999996 4 P 0 0 ;0=3,1=1
P 44.4999999 32.4999985 4 P 0 0 ;0=3,1=1
P 44.4999999 34.49999958 4 P 0 0 ;0=3,1=1
P 44.4999999 36.49999812 4 P 0 0 ;0=3,1=1
P 44.4999999 38.4999992 4 P 0 0 ;0=3,1=1
P 44.4999999 40.49999774 4 P 0 0 ;0=3,1=1

### steps/pcb/layers/l04-bottom_layer/features
UNITS=MM
#Layer_Physical_Order=4
#Layer_Color=16711680
#
#Feature symbol names
#
$0 r185.0009
$1 r199.9996
$2 r399.9992
$3 r299.9994
$4 rect1050.00044x1749.99904
$5 rect1050.00044x900.00074
$6 rect569.99886x619.99876
$7 rect419.99916x439.99912
$8 r6200.0003
$9 rect2300.00048x3300.00102
$10 rect299.9994x1725.00036
$11 rect800.00094x1449.99964
$12 rect599.9988x299.9994
$13 rect1299.99994x1649.99924
$14 rect599.9988x619.99876
$15 rect459.99908x419.99916
$16 rect419.99916x459.99908
$17 rect619.99876x599.9988
$18 rect619.99876x569.99886
$19 r1000.00054
$20 r349.9993
$21 r99.9998
$22 r2090.0009
$23 r5299.99956
$24 r1524
$25 r1562.00094
$26 r1799.99894
$27 r599.9988

#
#Feature attribute names
#
@0 .geometry
@1 .pad_usage
@2 .smd
@3 .nomenclature
@4 .string
@5 .string_angle

#
#Feature attribute text strings
#
&0 SMD_RectX1050.0004Y1749.9990
&1 SMD_RectX1050.0004Y900.0007
&2 SMD_RectX569.9989Y619.9988
&3 SMD_RectX419.9992Y439.9991
&4 SMD_RoundX6200.0003Y6200.0003
&5 SMD_RectX2300.0005Y3300.0010
&6 SMD_RectX299.9994Y1725.0004
&7 SMD_RectX800.0009Y1449.9996
&8 SMD_RectX599.9988Y299.9994
&9 SMD_RectX1299.9999Y1649.9992
&10 SMD_RectX599.9988Y619.9988
&11 SMD_RectX459.9991Y419.9992
&12 SMD_RectX419.9992Y459.9991
&13 SMD_RectX619.9988Y599.9988
&14 SMD_RectX619.9988Y569.9989
&15 SMD_RoundX1000.0005Y1000.0005
&16 Pad_Simple_X2090.0009Y2090.0009H1090.0004C2106.0004
&17 Pad_Simple_X5299.9996Y5299.9996H2999.9991C4015.9991
&18 Pad_Simple_X1524.0000Y1524.0000H762.0000C1778.0000
&19 Pad_Simple_X1562.0009Y1562.0009H961.9996C1977.9996
&20 Pad_Simple_X1799.9989Y1799.9989H1200.0001C2216.0001
&21 VIA_RoundD599.9988H299.9994C1315.9994

#
#Layer features
#
A 15.36500102 18.0150008 15.56500062 18.2150004 15.36500102 18.2150004 1 P 0 N
A 15.84000134 18.49000112 15.56500062 18.2150004 15.84000134 18.2150004 1 P 0 N
A 16.40249958 17.869662 16.3439221 18.01108412 16.20249998 17.869662 1 P 0 N
A 18.22000166 19.96000072 18.44000122 19.74000116 18.44000122 19.96000072 3 P 0 N
A 18.43000124 18.49000112 18.68000074 18.74000062 18.43000124 18.74000062 1 P 0 N
A 18.68000074 19.50000164 18.44000122 19.74000116 18.44000122 19.50000164 3 P 0 N
A 19.13999982 20.26500138 19.51500034 19.89000086 19.51500034 20.26500138 2 P 0 N
A 39.78999916 17.36499956 39.35499876 17.79999996 39.35499876 17.36499956 1 P 0 N
A 39.89605178 35.08605124 40.64 36.88210302 38.1 36.88210302 0 P 0 N
L -9.5600012 -24.45999934 40.4400004 -24.45999934 21 P 0
L -9.5600012 -35.9599992 -9.5600012 -24.45999934 21 P 0
L -9.5600012 -35.9599992 28.439999 -35.9599992 21 P 0
L -9.5600012 -39.45999982 -9.5600012 -35.9599992 21 P 0
L -9.5600012 -39.45999982 28.439999 -39.45999982 21 P 0
L -9.5600012 -42.96000044 -9.5600012 -39.45999982 21 P 0
L -9.5600012 -42.96000044 28.439999 -42.96000044 21 P 0
L -10.0600002 -23.96000034 62.93999858 -23.96000034 21 P 0
L -10.0600002 -43.45999944 -10.0600002 -23.96000034 21 P 0
L -10.0600002 -43.45999944 62.93999858 -43.45999944 21 P 0
L 14.86499948 18.0150008 14.86499948 19.16500104 1 P 0
L 14.86499948 18.0150008 15.36500102 18.0150008 1 P 0
L 14.86499948 19.16500104 14.86499948 20.21500148 1 P 0
L 15.84000134 18.49000112 16.31500166 18.49000112 1 P 0
L 15.86500002 20.21500148 16.95499784 20.21500148 1 P 0
L 16.31500166 18.04000202 16.34391956 18.01108158 1 P 0
L 16.31500166 18.94000276 16.46500136 18.94000276 1 P 0
L 16.40249958 17.00250346 16.40249958 17.869662 1 P 0
L 16.46500136 18.94000276 16.95499784 19.42999924 1 P 0
L 16.95499784 19.42999924 16.95499784 20.21500148 1 P 0
L 16.95499784 21.17499956 16.95499784 22.29000114 1 P 0
L 17.1650025 16.09000084 17.1650025 16.85250122 20 P 0
L 17.1650025 16.85250122 17.1650025 17.83497576 20 P 0
L 17.1650025 17.83497576 17.37002876 18.04000202 20 P 0
L 17.37002876 18.04000202 18.0150008 18.04000202 20 P 0
L 18.0150008 18.04000202 20.36500118 18.04000202 20 P 0
L 18.0150008 18.49000112 18.43000124 18.49000112 1 P 0
L 18.22000166 19.96000072 18.22000166 21.17499956 3 P 0
L 18.68000074 18.74000062 18.68000074 19.50000164 3 P 0
L 19.13999982 20.26500138 19.13999982 21.17499956 2 P 0
L 20.36500118 18.04000202 21.11500222 17.29000098 20 P 0
L 21.11500222 16.79000198 21.11500222 17.29000098 20 P 0
L 28.439999 -35.96000174 45.44000056 -35.9599992 21 P 0
L 28.439999 -39.45999982 28.439999 -35.9599992 21 P 0
L 28.439999 -39.46000236 45.44000056 -39.45999982 21 P 0
L 28.439999 -42.96000044 28.439999 -39.45999982 21 P 0
L 28.439999 -42.96000298 45.44000056 -42.96000044 21 P 0
L 37.8500005 17.79999996 39.35499876 17.79999996 1 P 0
L 37.8500005 33.03999996 39.89605178 35.08605124 0 P 0
L 39.78999916 15.96499982 39.78999916 17.36499956 1 P 0
L 40.4400004 -24.45999934 62.43999958 -24.45999934 21 P 0
L 40.4400004 -35.9599992 40.4400004 -24.45999934 21 P 0
L 40.64 36.88210302 40.64 40.64 0 P 0
L 45.44000056 -35.9599992 62.43999958 -35.9599992 21 P 0
L 45.44000056 -39.45999982 62.43999958 -39.45999982 21 P 0
L 45.44000056 -42.96000044 45.44000056 -35.9599992 21 P 0
L 45.44000056 -42.96000044 62.43999958 -42.96000044 21 P 0
L 62.43999958 -35.9599992 62.43999958 -24.45999934 21 P 0
L 62.43999958 -42.96000044 62.43999958 -35.9599992 21 P 0
L 62.93999858 -43.45999944 62.93999858 -23.96000034 21 P 0
P -2.38499904 43.5150006 19 P 0 0 ;0=15,1=0,2
P 0 0 22 P 0 0 ;0=16,1=0
P 0 40.64 22 P 0 0 ;0=16,1=0
P 2.0779994 43.3299997 22 P 0 0 ;0=16,1=0
P 4.39999882 2.00000108 8 P 0 0 ;0=4,1=0,2
P 4.39999882 38.599999 8 P 0 0 ;0=4,1=0,2
P 4.8300005 7.63999996 26 P 0 0 ;0=20,1=0
P 4.8300005 7.63999996 24 P 0 0 ;0=18,1=0
P 4.8300005 12.71999996 26 P 0 0 ;0=20,1=0
P 4.8300005 12.71999996 24 P 0 0 ;0=18,1=0
P 4.8300005 17.79999996 26 P 0 0 ;0=20,1=0
P 4.8300005 17.79999996 24 P 0 0 ;0=18,1=0
P 4.8300005 33.03999996 24 P 0 0 ;0=18,1=0
P 4.8300005 33.03999996 26 P 0 0 ;0=20,1=0
P 5.1259994 43.3299997 22 P 0 0 ;0=16,1=0
P 8.1739994 43.3299997 22 P 0 0 ;0=16,1=0
P 11.2219994 43.3299997 22 P 0 0 ;0=16,1=0
P 13.9050014 18.0150008 6 P 0 0 ;0=2,1=0,2
P 13.9050014 19.16500104 6 P 0 0 ;0=2,1=0,2
P 14.2699994 43.3299997 22 P 0 0 ;0=16,1=0
P 14.86499948 18.0150008 6 P 0 0 ;0=2,1=0,2
P 14.86499948 19.16500104 6 P 0 0 ;0=2,1=0,2
P 14.86499948 20.21500148 16 P 0 0 ;0=12,1=0,2
P 14.86499948 20.87500016 16 P 0 0 ;0=12,1=0,2
P 15.86500002 20.21500148 7 P 0 0 ;0=3,1=0,2
P 15.86500002 20.89500012 7 P 0 0 ;0=3,1=0,2
P 15.91499992 7.38999792 13 P 0 0 ;0=9,1=0,2
P 15.91499992 9.7899982 13 P 0 0 ;0=9,1=0,2
P 15.91499992 12.39000062 13 P 0 0 ;0=9,1=0,2
P 16.29499916 22.29000114 15 P 0 0 ;0=11,1=0,2
P 16.31500166 18.04000202 12 P 0 0 ;0=8,1=0,2
P 16.31500166 18.49000112 12 P 0 0 ;0=8,1=0,2
P 16.31500166 18.94000276 12 P 0 0 ;0=8,1=0,2
P 16.41500146 16.99000158 11 P 0 0 ;0=7,1=0,2
P 16.65500352 14.7900009 14 P 0 0 ;0=10,1=0,2
P 16.95499784 20.21500148 18 P 0 0 ;0=14,1=0,2
P 16.95499784 21.17499956 18 P 0 0 ;0=14,1=0,2
P 16.95499784 22.29000114 15 P 0 0 ;0=11,1=0,2
P 17.1650025 16.85250122 10 P 0 0 ;0=6,1=0,2
P 17.57500168 14.7900009 14 P 0 0 ;0=10,1=0,2
P 17.7150014 7.38999792 13 P 0 0 ;0=9,1=0,2
P 17.7150014 9.7899982 13 P 0 0 ;0=9,1=0,2
P 17.7150014 12.39000062 13 P 0 0 ;0=9,1=0,2
P 17.915001 16.99000158 11 P 0 0 ;0=7,1=0,2
P 18.0150008 18.04000202 12 P 0 0 ;0=8,1=0,2
P 18.0150008 18.49000112 12 P 0 0 ;0=8,1=0,2
P 18.0150008 18.94000276 12 P 0 0 ;0=8,1=0,2
P 18.22000166 21.17499956 14 P 0 0 ;0=10,1=0,2
P 19.13999982 21.17499956 14 P 0 0 ;0=10,1=0,2
P 20.24000016 42.13999954 23 P 0 0 ;0=17,1=0
P 20.43999976 -1.26000002 23 P 0 0 ;0=17,1=0
P 20.76500038 16.85250122 9 P 0 0 ;0=5,1=0,2
P 22.41500216 7.7900022 13 P 0 0 ;0=9,1=0,2
P 22.41500216 10.29000228 13 P 0 0 ;0=9,1=0,2
P 22.95500362 12.29000082 14 P 0 0 ;0=10,1=0,2
P 23.87500178 12.29000082 14 P 0 0 ;0=10,1=0,2
P 24.21500364 7.7900022 13 P 0 0 ;0=9,1=0,2
P 24.21500364 10.29000228 13 P 0 0 ;0=9,1=0,2
P 26.06499994 16.85250122 9 P 0 0 ;0=5,1=0,2
P 32.24000156 7.63999996 4 P 0 0 ;0=0,1=0,2
P 35.24000064 7.63999996 4 P 0 0 ;0=0,1=0,2
P 35.50000012 -1.00000054 8 P 0 0 ;0=4,1=0,2
P 36.20000126 40.10000108 8 P 0 0 ;0=4,1=0,2
P 37.8500005 7.63999996 26 P 0 0 ;0=20,1=0
P 37.8500005 7.63999996 25 P 0 0 ;0=19,1=0
P 37.8500005 9.94000044 14 P 0 0 ;0=10,1=0,2
P 37.8500005 12.71999996 26 P 0 0 ;0=20,1=0
P 37.8500005 12.71999996 25 P 0 0 ;0=19,1=0
P 37.8500005 17.79999996 26 P 0 0 ;0=20,1=0
P 37.8500005 17.79999996 25 P 0 0 ;0=19,1=0
P 37.8500005 22.87999996 25 P 0 0 ;0=19,1=0
P 37.8500005 22.87999996 26 P 0 0 ;0=20,1=0
P 37.8500005 33.03999996 25 P 0 0 ;0=19,1=0
P 37.8500005 33.03999996 26 P 0 0 ;0=20,1=0
P 38.76999866 9.94000044 14 P 0 0 ;0=10,1=0,2
P 39.78999916 14.51500018 5 P 0 0 ;0=1,1=0,2
P 39.78999916 15.96499982 5 P 0 0 ;0=1,1=0,2
P 40.0900011 7.63999996 17 P 0 0 ;0=13,1=0,2
P 40.0900011 8.55999812 17 P 0 0 ;0=13,1=0,2
P 40.64 0 22 P 0 0 ;0=16,1=0
P 40.64 40.64 22 P 0 0 ;0=16,1=0
P 40.67999992 20.33999996 22 P 0 0 ;0=16,1=0
P 43.11499886 43.5150006 19 P 0 0 ;0=15,1=0,2
P 43.18999998 -2.80999946 19 P 0 0 ;0=15,1=0,2
S P 0
OB 16.8150032 17.00366932 I
OS 16.81176216 16.99881792
OS 16.78265884 16.85250122
OS 16.78265884 16.09000084
OS 16.81176216 15.94368414
OS 16.8150032 15.93883274
OS 16.8150032 15.42999708
OS 16.78200352 15.40595852
OS 16.78200352 14.7900009
OS 16.78200352 14.22600152
OS 16.95499784 14.22600152
OS 16.95499784 14.02999734
OS 16.95500038 14.00214878
OS 16.93368724 13.95069346
OS 16.92867582 13.94568204
OS 16.81501082 13.89000524
OS 16.81499812 13.8900027
OS 16.81499304 13.89000524
OS 16.81499304 13.89000016
OS 16.76623012 13.88519702
OS 16.67610838 13.84786664
OS 16.60713214 13.7788904
OS 16.5698043 13.68876866
OS 16.56500116 13.63999812
OS 16.56500116 -2.10999832
OS 16.56500116 -2.22474282
OS 16.52022858 -2.4498173
OS 16.43240808 -2.66183364
OS 16.30491532 -2.85264352
OS 16.14264234 -3.0149165
OS 15.95183246 -3.14240926
OS 15.73981612 -3.23022976
OS 15.51474164 -3.2749998
OS 15.39999968 -3.2749998
OS -2.42500658 -3.27500234
OS -2.54812292 -3.27500488
OS -2.78962104 -3.22697094
OS -3.01710852 -3.13274456
OS -3.22184268 -2.99594778
OS -3.39595206 -2.82183586
OS -3.53274884 -2.6171017
OS -3.62697268 -2.38961168
OS -3.67500408 -2.14811356
OS -3.674999 -2.02499722
OS -3.674999 12.835001
OS -3.674999 13.08516814
OS -3.57738934 13.57588852
OS -3.38591906 14.03813804
OS -3.10794908 14.4541494
OS -2.75415756 14.80794092
OS -2.33814366 15.0859109
OS -1.87589414 15.27738118
OS -1.38517376 15.37499084
OS -1.13500662 15.3749883
OS -1.134999 15.375001
OS 15.33374886 15.375001
OS 15.39642082 15.3811732
OS 15.5122245 15.4291411
OS 15.6008578 15.5177744
OS 15.6488257 15.63357808
OS 15.65500044 15.69625258
OS 15.65500044 17.35499958
OS 15.6549979 17.42660726
OS 15.70980602 17.55892094
OS 15.78688994 17.63600232
OS 16.19858076 17.63600232
OS 16.19858076 17.00250346
OS 16.2141027 16.92446704
OS 16.25830632 16.8583102
OS 16.32446316 16.81410658
OS 16.40249958 16.79858464
OS 16.480536 16.81410658
OS 16.54669284 16.8583102
OS 16.59089646 16.92446704
OS 16.6064184 17.00250346
OS 16.6064184 17.63600232
OS 16.8150032 17.63600232
OS 16.8150032 17.00366932
OE
OB 16.52800352 15.35400028 H
OS 16.10100412 15.35400028
OS 16.10100412 14.9170009
OS 16.52800352 14.9170009
OS 16.52800352 15.35400028
OE
OB 16.52800352 14.6630009 H
OS 16.10100412 14.6630009
OS 16.10100412 14.22600152
OS 16.52800352 14.22600152
OS 16.52800352 14.6630009
OE
OB 4.9748186 13.81999776 H
OS 4.6851824 13.81999776
OS 4.40541664 13.74503474
OS 4.15458656 13.60021664
OS 3.94978382 13.3954139
OS 3.80496572 13.14458382
OS 3.7300027 12.86481806
OS 3.7300027 12.57518186
OS 3.80496572 12.2954161
OS 3.94978382 12.04458602
OS 4.15458656 11.83978328
OS 4.40541664 11.69496518
OS 4.6851824 11.62000216
OS 4.9748186 11.62000216
OS 5.25458436 11.69496518
OS 5.50541444 11.83978328
OS 5.71021718 12.04458602
OS 5.85503528 12.2954161
OS 5.9299983 12.57518186
OS 5.9299983 12.86481806
OS 5.85503528 13.14458382
OS 5.71021718 13.3954139
OS 5.50541444 13.60021664
OS 5.25458436 13.74503474
OS 4.9748186 13.81999776
OE
OB 4.9748186 8.73999776 H
OS 4.6851824 8.73999776
OS 4.40541664 8.66503474
OS 4.15458656 8.52021664
OS 3.94978382 8.3154139
OS 3.80496572 8.06458382
OS 3.7300027 7.78481806
OS 3.7300027 7.49518186
OS 3.80496572 7.2154161
OS 3.94978382 6.96458602
OS 4.15458656 6.75978328
OS 4.40541664 6.61496518
OS 4.6851824 6.54000216
OS 4.9748186 6.54000216
OS 5.25458436 6.61496518
OS 5.50541444 6.75978328
OS 5.71021718 6.96458602
OS 5.85503528 7.2154161
OS 5.9299983 7.49518186
OS 5.9299983 7.78481806
OS 5.85503528 8.06458382
OS 5.71021718 8.3154139
OS 5.50541444 8.52021664
OS 5.25458436 8.66503474
OS 4.9748186 8.73999776
OE
OB 0.24999442 1.2778359 H
OS 0.24999442 0.25000966
OS 1.27783336 0.25000966
OS 1.2104751 0.501396
OS 1.0394569 0.79760318
OS 0.79760318 1.0394569
OS 0.501396 1.2104751
OS 0.24999442 1.2778359
OE
OB -0.25000458 1.27783336 H
OS -0.501396 1.2104751
OS -0.79760318 1.0394569
OS -1.0394569 0.79760318
OS -1.2104751 0.501396
OS -1.27783336 0.25000966
OS -0.25000458 0.25000966
OS -0.25000458 1.27783336
OE
OB -0.25000458 -0.24998934 H
OS -1.27783844 -0.24998934
OS -1.2104751 -0.501396
OS -1.0394569 -0.79760318
OS -0.79760318 -1.0394569
OS -0.501396 -1.2104751
OS -0.25000458 -1.27783336
OS -0.25000458 -0.24998934
OE
OB 1.27783844 -0.24998934 H
OS 0.24999442 -0.24998934
OS 0.24999442 -1.2778359
OS 0.501396 -1.2104751
OS 0.79760318 -1.0394569
OS 1.0394569 -0.79760318
OS 1.2104751 -0.501396
OS 1.27783844 -0.24998934
OE
OB 4.65971382 5.29999956 H
OS 4.14028382 5.29999956
OS 3.627247 5.21874242
OS 3.13323986 5.05822966
OS 2.67042392 4.82241098
OS 2.25019362 4.5170979
OS 1.882902 4.14980628
OS 1.57758892 3.72957598
OS 1.34177024 3.26676004
OS 1.18125748 2.7727529
OS 1.10000034 2.25971608
OS 1.10000034 1.74028608
OS 1.18125748 1.22724926
OS 1.34177024 0.73324212
OS 1.57758892 0.27042618
OS 1.882902 -0.14980412
OS 2.25019362 -0.51709574
OS 2.67042392 -0.82240882
OS 3.13323986 -1.0582275
OS 3.627247 -1.21874026
OS 4.14028382 -1.2999974
OS 4.65971382 -1.2999974
OS 5.17275064 -1.21874026
OS 5.66675778 -1.0582275
OS 6.12957372 -0.82240882
OS 6.54980402 -0.51709574
OS 6.91709564 -0.14980412
OS 7.22240872 0.27042618
OS 7.4582274 0.73324212
OS 7.61874016 1.22724926
OS 7.6999973 1.74028608
OS 7.6999973 2.25971608
OS 7.61874016 2.7727529
OS 7.4582274 3.26676004
OS 7.22240872 3.72957598
OS 6.91709564 4.14980628
OS 6.54980402 4.5170979
OS 6.12957372 4.82241098
OS 5.66675778 5.05822966
OS 5.17275064 5.21874242
OS 4.65971382 5.29999956
OE
SE
S P 0
OB 21.91500062 20.19000026 I
OS 21.91500062 13.89000016
OS 19.78128632 13.89000016
OS 19.31500074 14.35628828
OS 19.31500074 17.11865766
OS 18.5690002 17.8646582
OS 18.5690002 17.91300202
OS 18.0150008 17.91300202
OS 18.0150008 18.16700202
OS 18.5690002 18.16700202
OS 18.5690002 18.18999918
OS 18.59000346 18.18999918
OS 18.80874826 18.40875414
OS 18.81656384 18.41030862
OS 18.93233704 18.48766432
OS 19.00969274 18.60343752
OS 19.01124976 18.61126326
OS 19.04000002 18.64001606
OS 19.04000002 19.50000164
OS 19.04155958 19.50000164
OS 19.04000002 19.50784262
OS 19.04000002 20.01500188
OS 19.21500094 20.1900028
OS 21.91500062 20.19000026
OE
SE
S P 0
OB 32.17499788 24.54999408 I
OS 32.42516502 24.54999662
OS 32.9158854 24.4523895
OS 33.37813492 24.26092176
OS 33.79415136 23.98295178
OS 34.14794034 23.6291628
OS 34.42591286 23.2131489
OS 34.61738314 22.75089938
OS 34.7149928 22.260179
OS 34.71499026 22.01001186
OS 34.71498772 22.01001186
OS 34.71499534 22.01000678
OS 34.7149928 11.55441428
OS 34.66050726 11.49992874
OS 34.61630364 11.43377444
OS 34.55159968 11.27757206
OS 34.53607774 11.19953564
OS 34.53608028 11.11499174
OS 34.53608028 8.71499908
OS 34.51500082 8.71499908
OS 34.51500082 6.56500084
OS 34.53608028 6.56500084
OS 34.53608028 3.9650035
OS 34.53607774 3.8812851
OS 34.53999442 3.86158994
OS 34.53999442 3.84149854
OS 34.57266136 3.67727992
OS 34.5803474 3.65872268
OS 34.58426662 3.63902244
OS 34.6483432 3.4843339
OS 34.65949888 3.46763594
OS 34.66718492 3.44908378
OS 34.6695395 3.44555826
OS 34.57602686 3.315589
OS 34.45428466 3.21088004
OS 34.3113741 3.13765184
OS 34.15527586 3.0999938
OS 34.07498646 3.09999888
OS 24.53412416 3.09999888
OS 24.32643598 3.14130944
OS 24.13079756 3.2223456
OS 23.95472984 3.33999078
OS 23.8049943 3.48972632
OS 23.68734912 3.66579404
OS 23.60631296 3.86143246
OS 23.5650024 4.06912064
OS 23.5650024 4.17500054
OS 23.5650024 11.72600144
OS 23.74798146 11.72600144
OS 23.74798146 12.29001606
OS 23.74798146 12.8540002
OS 23.5650024 12.8540002
OS 23.5650024 13.04249868
OS 23.56499986 13.10416226
OS 23.6121956 13.21809904
OS 23.69939888 13.30530232
OS 23.81333566 13.35249806
OS 23.87499924 13.35249552
OS 23.87500178 13.3525006
OS 24.51749986 13.3525006
OS 24.59504606 13.36013838
OS 24.73833762 13.41949056
OS 24.8480072 13.52916014
OS 24.90735938 13.6724517
OS 24.9149997 13.75000044
OS 24.91500224 13.89000016
OS 24.91500478 13.8900027
OS 24.9149997 13.89000524
OS 24.9149997 19.69000126
OS 24.91499716 19.69000126
OS 24.91499462 23.10999696
OS 24.9105928 23.19968436
OS 24.87560176 23.37560984
OS 24.8069608 23.54132706
OS 24.70730644 23.69047078
OS 24.58047154 23.81730568
OS 24.43132782 23.91696004
OS 24.2656106 23.985601
OS 24.11693424 24.01517168
OS 24.08968512 24.02059458
OS 24.00006376 24.02499132
OS 24.0000028 24.0249964
OS 24.00000026 24.02500148
OS 23.99999772 24.02499894
OS 15.54999684 24.02499894
OS 15.45732748 24.01587018
OS 15.286101 23.94494576
OS 15.1550497 23.81389446
OS 15.08412528 23.64266798
OS 15.07499906 23.55000116
OS 15.07499906 21.3589997
OS 14.99199694 21.3589997
OS 14.99199694 20.87500778
OS 14.86499694 20.87500778
OS 14.86499694 20.74800778
OS 14.4009999 20.74800778
OS 14.4009999 20.64500062
OS 14.40000168 20.64500062
OS 14.35903148 20.64096456
OS 14.28333186 20.60960826
OS 14.22539192 20.55166832
OS 14.19403562 20.4759687
OS 14.1900021 20.43500104
OS 14.1900021 19.72900042
OS 14.0320014 19.72900042
OS 14.0320014 19.16500104
OS 13.9050014 19.16500104
OS 13.9050014 19.03800104
OS 13.36600324 19.03800104
OS 13.36600324 18.85500166
OS 12.81999468 18.85500166
OS 12.79115298 18.85499912
OS 12.7378587 18.87707172
OS 12.69706884 18.91786158
OS 12.67499624 18.97115586
OS 12.67499878 18.99999756
OS 12.67499878 19.8999983
OS 12.67499624 19.96265502
OS 12.72295398 20.07843076
OS 12.81156442 20.1670412
OS 12.92734016 20.21499894
OS 12.98999688 20.2149964
OS 12.98999942 20.21500148
OS 13.15999908 20.21500148
OS 13.24974236 20.22383814
OS 13.41556118 20.29252228
OS 13.54247482 20.41943592
OS 13.61115896 20.58525474
OS 13.61999562 20.67499802
OS 13.6200007 20.67500056
OS 13.6200007 23.64398116
OS 13.6586214 23.83814384
OS 13.73437944 24.02104162
OS 13.84436398 24.18564632
OS 13.98434846 24.3256308
OS 14.14895316 24.43561534
OS 14.33185094 24.51137338
OS 14.52601362 24.54999408
OS 14.62499742 24.54999408
OS 14.62499996 24.54999916
OS 32.17499788 24.54999408
OE
OB 14.73799694 21.3589997 H
OS 14.4009999 21.3589997
OS 14.4009999 21.00200778
OS 14.73799694 21.00200778
OS 14.73799694 21.3589997
OE
OB 13.7780014 19.72900042 H
OS 13.36600324 19.72900042
OS 13.36600324 19.29200104
OS 13.7780014 19.29200104
OS 13.7780014 19.72900042
OE
OB 24.42900118 12.8540002 H
OS 24.00198146 12.8540002
OS 24.00198146 12.41701606
OS 24.42900118 12.41701606
OS 24.42900118 12.8540002
OE
OB 24.42900118 12.16301606 H
OS 24.00198146 12.16301606
OS 24.00198146 11.72600144
OS 24.42900118 11.72600144
OS 24.42900118 12.16301606
OE
SE
S P 0
OB 37.9830838 11.48138674 I
OS 38.09138686 11.37308368
OS 38.1499999 11.23158028
OS 38.1499999 9.52999872
OS 38.15845302 9.44415688
OS 38.22415266 9.28554658
OS 38.34554688 9.16415236
OS 38.50415718 9.09845272
OS 38.58999902 9.0899996
OS 39.08999802 9.08999452
OS 39.13972614 9.08999706
OS 39.23161318 9.0519377
OS 39.30193816 8.98161272
OS 39.31267728 8.95568694
OS 39.33999498 8.8400128
OS 39.33999498 8.83999756
OS 39.33999244 8.83999756
OS 39.34000006 8.83999248
OS 39.34000006 8.41499968
OS 39.34912628 8.32233032
OS 39.4200507 8.1511013
OS 39.551102 8.02005
OS 39.72233102 7.94912558
OS 39.81500038 7.93999936
OS 42.0399972 7.93999428
OS 42.14442676 7.93999682
OS 42.33738802 7.86007064
OS 42.48507124 7.71238742
OS 42.55968628 7.53225062
OS 42.56499488 7.41506518
OS 42.56499488 7.4149966
OS 42.56499234 7.4149966
OS 42.56499996 7.41499152
OS 42.56499996 3.81366776
OS 42.53521592 3.66393984
OS 42.47679592 3.52289872
OS 42.39198024 3.39596476
OS 42.28403278 3.2880173
OS 42.15709882 3.20320162
OS 42.0160577 3.14478162
OS 41.86632978 3.11500012
OS 35.5899974 3.11500012
OS 35.506279 3.11499758
OS 35.34206038 3.14766198
OS 35.18737184 3.21173856
OS 35.04815444 3.30475844
OS 34.92975742 3.42315546
OS 34.83673754 3.56237286
OS 34.77266096 3.7170614
OS 34.73999656 3.88128002
OS 34.7399991 3.96499842
OS 34.7399991 11.11499682
OS 34.73999656 11.1995331
OS 34.80470052 11.35573802
OS 34.92425324 11.47529328
OS 35.0804607 11.5399947
OS 35.16499698 11.53999216
OS 35.16499952 11.53999978
OS 37.8415804 11.53999978
OS 37.9830838 11.48138674
OE
SE
S P 0
OB 43.2467766 45.28782662 I
OS 43.5750081 45.19987658
OS 43.8889648 45.06983112
OS 44.18321872 44.89994068
OS 44.45280162 44.69308308
OS 44.693078 44.45280924
OS 44.89994068 44.18322126
OS 45.06983112 43.8889648
OS 45.19986896 43.57502842
OS 45.28782408 43.24677914
OS 45.33217502 42.90990402
OS 45.33217756 42.7399958
OS 45.33217502 -2.06000096
OS 45.33217502 -2.22990918
OS 45.28782662 -2.56677922
OS 45.19987658 -2.89501072
OS 45.06983112 -3.20896742
OS 44.89994068 -3.50322134
OS 44.69308308 -3.77280424
OS 44.45280924 -4.01308062
OS 44.18322126 -4.2199433
OS 43.8889648 -4.38983374
OS 43.57502842 -4.51987158
OS 43.24677914 -4.6078267
OS 42.90989132 -4.6521751
OS 42.7399958 -4.65217764
OS -2.06000096 -4.65218272
OS -2.22990918 -4.65218272
OS -2.56678938 -4.60783178
OS -2.89502088 -4.51988428
OS -3.20895472 -4.38984644
OS -3.50322388 -4.21994838
OS -3.77279916 -4.0130984
OS -4.0130984 -3.77279916
OS -4.21994584 -3.50322642
OS -4.38984136 -3.2089598
OS -4.51988174 -2.89502088
OS -4.60782924 -2.56679192
OS -4.65218018 -2.22991172
OS -4.65217764 -2.06000604
OS -4.65218526 42.73999834
OS -4.65218526 42.90990656
OS -4.60783432 43.24678422
OS -4.51988682 43.57501318
OS -4.38984644 43.88895464
OS -4.21995092 44.18321872
OS -4.01310094 44.452794
OS -3.77280932 44.69308562
OS -3.50323404 44.89993814
OS -3.20894964 45.06984128
OS -2.89502342 45.19987658
OS -2.56679192 45.28782408
OS -2.22992188 45.33217248
OS -2.07798416 45.33216486
OS -2.07795622 45.33216994
OS 42.74000088 45.33217502
OS 42.90990656 45.33217502
OS 43.2467766 45.28782662
OE
OB 14.42216826 44.87499788 H
OS 14.11783054 44.87499788
OS 13.8193399 44.81562538
OS 13.53816952 44.69915876
OS 13.28511948 44.53007858
OS 13.06992052 44.31487962
OS 12.90084034 44.06182958
OS 12.8147318 43.85394836
OS 12.677267 43.85394836
OS 12.59115846 44.06182958
OS 12.42207828 44.31487962
OS 12.20687932 44.53007858
OS 11.95382928 44.69915876
OS 11.6726589 44.81562538
OS 11.37416826 44.87499788
OS 11.06983054 44.87499788
OS 10.7713399 44.81562538
OS 10.49016952 44.69915876
OS 10.23711948 44.53007858
OS 10.02192052 44.31487962
OS 9.85284034 44.06182958
OS 9.73637372 43.7806592
OS 9.67700122 43.48216856
OS 9.67700122 43.17783084
OS 9.73637372 42.8793402
OS 9.85284034 42.59816982
OS 10.02192052 42.34511978
OS 10.23711948 42.12992082
OS 10.49016952 41.96084064
OS 10.7713399 41.84437402
OS 11.06983054 41.78500152
OS 11.37416826 41.78500152
OS 11.6726589 41.84437402
OS 11.95382928 41.96084064
OS 12.20687932 42.12992082
OS 12.42207828 42.34511978
OS 12.59115846 42.59816982
OS 12.677267 42.80605104
OS 12.8147318 42.80605104
OS 12.90084034 42.59816982
OS 13.06992052 42.34511978
OS 13.28511948 42.12992082
OS 13.53816952 41.96084064
OS 13.8193399 41.84437402
OS 14.11783054 41.78500152
OS 14.42216826 41.78500152
OS 14.7206589 41.84437402
OS 15.00182928 41.96084064
OS 15.25487932 42.12992082
OS 15.47007828 42.34511978
OS 15.63915846 42.59816982
OS 15.75562508 42.8793402
OS 15.81499758 43.17783084
OS 15.81499758 43.48216856
OS 15.75562508 43.7806592
OS 15.63915846 44.06182958
OS 15.47007828 44.31487962
OS 15.25487932 44.53007858
OS 15.00182928 44.69915876
OS 14.7206589 44.81562538
OS 14.42216826 44.87499788
OE
OB 43.11499886 44.72535632 H
OS 42.80173558 44.68411434
OS 42.509821 44.56320018
OS 42.2591484 44.37085106
OS 42.06679928 44.12017846
OS 41.94588512 43.82826388
OS 41.90464314 43.5150006
OS 41.94588512 43.20173732
OS 42.06679928 42.90982274
OS 42.2591484 42.65915014
OS 42.509821 42.46680102
OS 42.80173558 42.34588686
OS 43.11499886 42.30464488
OS 43.42826214 42.34588686
OS 43.72017672 42.46680102
OS 43.97084932 42.65915014
OS 44.16319844 42.90982274
OS 44.2841126 43.20173732
OS 44.32535458 43.5150006
OS 44.2841126 43.82826388
OS 44.16319844 44.12017846
OS 43.97084932 44.37085106
OS 43.72017672 44.56320018
OS 43.42826214 44.68411434
OS 43.11499886 44.72535632
OE
OB -2.38499904 44.72535632 H
OS -2.69826232 44.68411434
OS -2.9901769 44.56320018
OS -3.2408495 44.37085106
OS -3.43319862 44.12017846
OS -3.55411278 43.82826388
OS -3.59535476 43.5150006
OS -3.55411278 43.20173732
OS -3.43319862 42.90982274
OS -3.2408495 42.65915014
OS -2.9901769 42.46680102
OS -2.69826232 42.34588686
OS -2.38499904 42.30464488
OS -2.07173576 42.34588686
OS -1.77982118 42.46680102
OS -1.52914858 42.65915014
OS -1.33679946 42.90982274
OS -1.2158853 43.20173732
OS -1.17464332 43.5150006
OS -1.2158853 43.82826388
OS -1.33679946 44.12017846
OS -1.52914858 44.37085106
OS -1.77982118 44.56320018
OS -2.07173576 44.68411434
OS -2.38499904 44.72535632
OE
OB 8.3379056 44.57499848 H
OS 8.0100932 44.57499848
OS 7.69344664 44.49015486
OS 7.40955084 44.32624866
OS 7.17775044 44.09444826
OS 7.01384424 43.81055246
OS 6.92900062 43.4939059
OS 6.92900062 43.1660935
OS 7.01384424 42.84944694
OS 7.17775044 42.56555114
OS 7.40955084 42.33375074
OS 7.69344664 42.16984454
OS 8.0100932 42.08500092
OS 8.3379056 42.08500092
OS 8.65455216 42.16984454
OS 8.93844796 42.33375074
OS 9.17024836 42.56555114
OS 9.33415456 42.84944694
OS 9.41899818 43.1660935
OS 9.41899818 43.4939059
OS 9.33415456 43.81055246
OS 9.17024836 44.09444826
OS 8.93844796 44.32624866
OS 8.65455216 44.49015486
OS 8.3379056 44.57499848
OE
OB 5.2899056 44.57499848 H
OS 4.9620932 44.57499848
OS 4.64544664 44.49015486
OS 4.36155084 44.32624866
OS 4.12975044 44.09444826
OS 3.96584424 43.81055246
OS 3.88100062 43.4939059
OS 3.88100062 43.1660935
OS 3.96584424 42.84944694
OS 4.12975044 42.56555114
OS 4.36155084 42.33375074
OS 4.64544664 42.16984454
OS 4.9620932 42.08500092
OS 5.2899056 42.08500092
OS 5.60655216 42.16984454
OS 5.89044796 42.33375074
OS 6.12224836 42.56555114
OS 6.28615456 42.84944694
OS 6.37099818 43.1660935
OS 6.37099818 43.4939059
OS 6.28615456 43.81055246
OS 6.12224836 44.09444826
OS 5.89044796 44.32624866
OS 5.60655216 44.49015486
OS 5.2899056 44.57499848
OE
OB 2.2419056 44.57499848 H
OS 1.9140932 44.57499848
OS 1.59744664 44.49015486
OS 1.31355084 44.32624866
OS 1.08175044 44.09444826
OS 0.91784424 43.81055246
OS 0.83300062 43.4939059
OS 0.83300062 43.1660935
OS 0.91784424 42.84944694
OS 1.08175044 42.56555114
OS 1.31355084 42.33375074
OS 1.59744664 42.16984454
OS 1.9140932 42.08500092
OS 2.2419056 42.08500092
OS 2.55855216 42.16984454
OS 2.84244796 42.33375074
OS 3.07424836 42.56555114
OS 3.23815456 42.84944694
OS 3.32299818 43.1660935
OS 3.32299818 43.4939059
OS 3.23815456 43.81055246
OS 3.07424836 44.09444826
OS 2.84244796 44.32624866
OS 2.55855216 44.49015486
OS 2.2419056 44.57499848
OE
OB 0.17101566 41.93899918 H
OS 0.12699492 41.93899918
OS 0.12699492 40.76701016
OS 1.29899918 40.76701016
OS 1.29899918 40.81101566
OS 1.2104751 41.141396
OS 1.0394569 41.43760318
OS 0.79760318 41.6794569
OS 0.501396 41.8504751
OS 0.17101566 41.93899918
OE
OB -0.12700508 41.93899918 H
OS -0.17101566 41.93899918
OS -0.501396 41.8504751
OS -0.79760318 41.6794569
OS -1.0394569 41.43760318
OS -1.2104751 41.141396
OS -1.29899918 40.81101566
OS -1.29899918 40.76701016
OS -0.12700508 40.76701016
OS -0.12700508 41.93899918
OE
OB 1.29899918 40.51301016 H
OS 0.12699492 40.51301016
OS 0.12699492 39.34100082
OS 0.17101566 39.34100082
OS 0.501396 39.4295249
OS 0.79760318 39.6005431
OS 1.0394569 39.84239682
OS 1.2104751 40.138604
OS 1.29899918 40.46898434
OS 1.29899918 40.51301016
OE
OB -0.12700508 40.51301016 H
OS -1.29899918 40.51301016
OS -1.29899918 40.46898434
OS -1.2104751 40.138604
OS -1.0394569 39.84239682
OS -0.79760318 39.6005431
OS -0.501396 39.4295249
OS -0.17101566 39.34100082
OS -0.12700508 39.34100082
OS -0.12700508 40.51301016
OE
OB 20.46429994 44.98999892 H
OS 20.01570038 44.98999892
OS 19.57262278 44.9198238
OS 19.14597898 44.78119822
OS 18.74627442 44.57753848
OS 18.38334906 44.31385854
OS 18.06614116 43.99665064
OS 17.80246122 43.63372528
OS 17.59880148 43.23402072
OS 17.4601759 42.80737692
OS 17.39000078 42.36429932
OS 17.39000078 41.91569976
OS 17.4601759 41.47262216
OS 17.59880148 41.04597836
OS 17.80246122 40.6462738
OS 18.06614116 40.28334844
OS 18.38334906 39.96614054
OS 18.74627442 39.7024606
OS 19.14597898 39.49880086
OS 19.57262278 39.36017528
OS 20.01570038 39.29000016
OS 20.46429994 39.29000016
OS 20.90737754 39.36017528
OS 21.33402134 39.49880086
OS 21.7337259 39.7024606
OS 22.09665126 39.96614054
OS 22.41385916 40.28334844
OS 22.6775391 40.6462738
OS 22.88119884 41.04597836
OS 23.01982442 41.47262216
OS 23.08999954 41.91569976
OS 23.08999954 42.36429932
OS 23.01982442 42.80737692
OS 22.88119884 43.23402072
OS 22.6775391 43.63372528
OS 22.41385916 43.99665064
OS 22.09665126 44.31385854
OS 21.7337259 44.57753848
OS 21.33402134 44.78119822
OS 20.90737754 44.9198238
OS 20.46429994 44.98999892
OE
OB 4.65971382 41.89999748 H
OS 4.14028382 41.89999748
OS 3.627247 41.81874034
OS 3.13323986 41.65822758
OS 2.67042392 41.4224089
OS 2.25019362 41.11709582
OS 1.882902 40.7498042
OS 1.57758892 40.3295739
OS 1.34177024 39.86675796
OS 1.18125748 39.37275082
OS 1.10000034 38.859714
OS 1.10000034 38.340284
OS 1.18125748 37.82724718
OS 1.34177024 37.33324004
OS 1.57758892 36.8704241
OS 1.882902 36.4501938
OS 2.25019362 36.08290218
OS 2.67042392 35.7775891
OS 3.13323986 35.54177042
OS 3.627247 35.38125766
OS 4.14028382 35.30000052
OS 4.65971382 35.30000052
OS 5.17275064 35.38125766
OS 5.66675778 35.54177042
OS 6.12957372 35.7775891
OS 6.54980402 36.08290218
OS 6.91709564 36.4501938
OS 7.22240872 36.8704241
OS 7.4582274 37.33324004
OS 7.61874016 37.82724718
OS 7.6999973 38.340284
OS 7.6999973 38.859714
OS 7.61874016 39.37275082
OS 7.4582274 39.86675796
OS 7.22240872 40.3295739
OS 6.91709564 40.7498042
OS 6.54980402 41.11709582
OS 6.12957372 41.4224089
OS 5.66675778 41.65822758
OS 5.17275064 41.81874034
OS 4.65971382 41.89999748
OE
OB 36.45971626 43.39999956 H
OS 35.94028626 43.39999956
OS 35.42724944 43.31874242
OS 34.9332423 43.15822966
OS 34.47042636 42.92241098
OS 34.05019606 42.6170979
OS 33.68290444 42.24980628
OS 33.37759136 41.82957598
OS 33.14177268 41.36676004
OS 32.98125992 40.8727529
OS 32.90000278 40.35971608
OS 32.90000278 39.84028608
OS 32.98125992 39.32724926
OS 33.14177268 38.83324212
OS 33.37759136 38.37042618
OS 33.68290444 37.95019588
OS 34.05019606 37.58290426
OS 34.47042636 37.27759118
OS 34.9332423 37.0417725
OS 35.42724944 36.88125974
OS 35.94028626 36.8000026
OS 36.45971626 36.8000026
OS 36.97275308 36.88125974
OS 37.46676022 37.0417725
OS 37.92957616 37.27759118
OS 38.34980646 37.58290426
OS 38.71709808 37.95019588
OS 39.02241116 38.37042618
OS 39.25822984 38.83324212
OS 39.4187426 39.32724926
OS 39.4445871 39.49042394
OS 39.56537172 39.52966948
OS 39.65512008 39.43992112
OS 39.90817012 39.27084094
OS 40.03589402 39.21793528
OS 40.03589402 36.88210302
OS 40.04142614 36.8542951
OS 40.00680848 36.50281498
OS 39.8961737 36.138104
OS 39.71651442 35.80198326
OS 39.49245594 35.52896882
OS 39.46888474 35.51321828
OS 38.31930106 34.3636346
OS 38.03431306 34.43999716
OS 37.66568794 34.43999716
OS 37.30962312 34.34458968
OS 36.99038322 34.16027712
OS 36.72972334 33.89961724
OS 36.54541078 33.58037734
OS 36.4500033 33.22431252
OS 36.4500033 32.8556874
OS 36.54541078 32.49962258
OS 36.72972334 32.18038268
OS 36.99038322 31.9197228
OS 37.30962312 31.73541024
OS 37.66568794 31.64000276
OS 38.03431306 31.64000276
OS 38.39037788 31.73541024
OS 38.70961778 31.9197228
OS 38.97027766 32.18038268
OS 39.15459022 32.49962258
OS 39.2499977 32.8556874
OS 39.2499977 33.22431252
OS 39.17363514 33.50930052
OS 40.32321882 34.6588842
OS 40.33227392 34.67243764
OS 40.6420828 35.0351725
OS 40.89970738 35.4555806
OS 41.08839636 35.91111436
OS 41.203499 36.39055714
OS 41.24092844 36.86612896
OS 41.24410598 36.88210302
OS 41.24410598 39.21793528
OS 41.37182988 39.27084094
OS 41.62487992 39.43992112
OS 41.84007888 39.65512008
OS 42.00915906 39.90817012
OS 42.12562568 40.1893405
OS 42.18499818 40.48783114
OS 42.18499818 40.79216886
OS 42.12562568 41.0906595
OS 42.00915906 41.37182988
OS 41.84007888 41.62487992
OS 41.62487992 41.84007888
OS 41.37182988 42.00915906
OS 41.0906595 42.12562568
OS 40.79216886 42.18499818
OS 40.48783114 42.18499818
OS 40.1893405 42.12562568
OS 39.90817012 42.00915906
OS 39.65512008 41.84007888
OS 39.43992112 41.62487992
OS 39.3430887 41.47995768
OS 39.196137 41.48862416
OS 39.02241116 41.82957598
OS 38.71709808 42.24980628
OS 38.34980646 42.6170979
OS 37.92957616 42.92241098
OS 37.46676022 43.15822966
OS 36.97275308 43.31874242
OS 36.45971626 43.39999956
OE
OB 4.9748186 34.13999776 H
OS 4.6851824 34.13999776
OS 4.40541664 34.06503474
OS 4.15458656 33.92021664
OS 3.94978382 33.7154139
OS 3.80496572 33.46458382
OS 3.7300027 33.18481806
OS 3.7300027 32.89518186
OS 3.80496572 32.6154161
OS 3.94978382 32.36458602
OS 4.15458656 32.15978328
OS 4.40541664 32.01496518
OS 4.6851824 31.94000216
OS 4.9748186 31.94000216
OS 5.25458436 32.01496518
OS 5.50541444 32.15978328
OS 5.71021718 32.36458602
OS 5.85503528 32.6154161
OS 5.9299983 32.89518186
OS 5.9299983 33.18481806
OS 5.85503528 33.46458382
OS 5.71021718 33.7154139
OS 5.50541444 33.92021664
OS 5.25458436 34.06503474
OS 4.9748186 34.13999776
OE
OB 38.03431306 24.27999716 H
OS 37.66568794 24.27999716
OS 37.30962312 24.18458968
OS 36.99038322 24.00027712
OS 36.72972334 23.73961724
OS 36.54541078 23.42037734
OS 36.4500033 23.06431252
OS 36.4500033 22.6956874
OS 36.54541078 22.33962258
OS 36.72972334 22.02038268
OS 36.99038322 21.7597228
OS 37.30962312 21.57541024
OS 37.66568794 21.48000276
OS 38.03431306 21.48000276
OS 38.39037788 21.57541024
OS 38.70961778 21.7597228
OS 38.97027766 22.02038268
OS 39.15459022 22.33962258
OS 39.2499977 22.6956874
OS 39.2499977 23.06431252
OS 39.15459022 23.42037734
OS 38.97027766 23.73961724
OS 38.70961778 24.00027712
OS 38.39037788 24.18458968
OS 38.03431306 24.27999716
OE
OB 40.85101558 21.63899914 H
OS 40.80699484 21.63899914
OS 40.80699484 20.46699996
OS 41.9789991 20.46699996
OS 41.9789991 20.51101562
OS 41.89047502 20.84139596
OS 41.71945682 21.13760314
OS 41.4776031 21.37945686
OS 41.18139592 21.55047506
OS 40.85101558 21.63899914
OE
OB 40.55299484 21.63899914 H
OS 40.50898426 21.63899914
OS 40.17860392 21.55047506
OS 39.88239674 21.37945686
OS 39.64054302 21.13760314
OS 39.46952482 20.84139596
OS 39.38100074 20.51101562
OS 39.38100074 20.46699996
OS 40.55299484 20.46699996
OS 40.55299484 21.63899914
OE
OB 14.62499996 24.75391798 H
OS 14.62497456 24.7539129
OS 14.52601362 24.7539129
OS 14.50632354 24.74999622
OS 14.48623214 24.74999622
OS 14.29206946 24.71137298
OS 14.2735173 24.70368948
OS 14.25381706 24.69977026
OS 14.07091674 24.62401222
OS 14.05421624 24.612854
OS 14.03566154 24.60516796
OS 13.87105684 24.49518342
OS 13.85685824 24.48098482
OS 13.8401552 24.46982406
OS 13.70017072 24.32983958
OS 13.68900996 24.31313654
OS 13.67481136 24.29893794
OS 13.56482682 24.13433324
OS 13.55714078 24.11577854
OS 13.54598256 24.09907804
OS 13.47022452 23.91618026
OS 13.4663053 23.89648002
OS 13.4586218 23.87792786
OS 13.4200011 23.68376264
OS 13.4200011 23.6636814
OS 13.41608188 23.64398116
OS 13.41608188 20.6850742
OS 13.41118476 20.635341
OS 13.36959988 20.53494496
OS 13.3000496 20.46539722
OS 13.1996561 20.42381234
OS 13.1499737 20.4189203
OS 12.98999942 20.4189203
OS 12.98997402 20.41891522
OS 12.92733762 20.41891776
OS 12.84931136 20.40339836
OS 12.84930374 20.40339328
OS 12.73353562 20.35544062
OS 12.733528 20.35543808
OS 12.66736862 20.31123192
OS 12.66736354 20.3112243
OS 12.57876326 20.22262656
OS 12.5345571 20.15646718
OS 12.53455456 20.15645956
OS 12.48659682 20.04068382
OS 12.47107742 19.96265756
OS 12.47107996 19.89999068
OS 12.47107996 19.00001534
OS 12.47107742 18.97116348
OS 12.48659174 18.89313722
OS 12.48659682 18.8931296
OS 12.50867196 18.83982516
OS 12.55287558 18.77366832
OS 12.59366544 18.73287846
OS 12.65982228 18.68867484
OS 12.71313434 18.66659462
OS 12.7911606 18.6510803
OS 12.82001246 18.65108284
OS 13.2688584 18.65108284
OS 13.36600324 18.57899764
OS 13.36600324 18.14201096
OS 13.90500648 18.14201096
OS 13.90500648 18.01501096
OS 14.03200648 18.01501096
OS 14.03200648 17.45100142
OS 14.44399956 17.45100142
OS 14.44399956 17.50500182
OS 15.24030988 17.50500182
OS 15.33718294 17.50499928
OS 15.42496534 17.47037908
OS 15.451074 17.42661488
OS 15.45107654 17.4266098
OS 15.45107908 17.40540588
OS 15.45108162 17.35499196
OS 15.45108162 15.7062678
OS 15.44885658 15.6836745
OS 15.4279854 15.63328852
OS 15.39671292 15.60201604
OS 15.3463244 15.58114486
OS 15.3237438 15.57891982
OS -1.134999 15.57891982
OS -1.1350625 15.57890712
OS -1.38517122 15.57890966
OS -1.40487146 15.57499044
OS -1.42495524 15.57499044
OS -1.91567562 15.47738078
OS -1.93422524 15.46969728
OS -1.95393056 15.46577806
OS -2.41618008 15.27430778
OS -2.43288312 15.26314702
OS -2.45143528 15.25546352
OS -2.86744918 14.97749354
OS -2.88164778 14.96329494
OS -2.89835082 14.95213418
OS -3.25214234 14.59834266
OS -3.2633031 14.58163962
OS -3.2775017 14.56744102
OS -3.55547168 14.15142966
OS -3.56316026 14.13287242
OS -3.57431594 14.11617446
OS -3.76578622 13.65392494
OS -3.76970544 13.63421962
OS -3.77738894 13.61567
OS -3.8749986 13.12494962
OS -3.8749986 13.10486838
OS -3.87891782 13.08516814
OS -3.87891782 12.835001
OS -3.87891782 -2.0249896
OS -3.8789229 -2.14810594
OS -3.87500622 -2.16780364
OS -3.87500622 -2.1878925
OS -3.82697482 -2.42939062
OS -3.81928624 -2.4479504
OS -3.81536956 -2.46764556
OS -3.72114572 -2.69513304
OS -3.70999004 -2.711831
OS -3.70230146 -2.73039078
OS -3.56550468 -2.93512494
OS -3.55130354 -2.94932608
OS -3.54014532 -2.96602658
OS -3.36603594 -3.1401385
OS -3.34933544 -3.15129926
OS -3.33513176 -3.1655004
OS -3.1303976 -3.30229718
OS -3.11184036 -3.30998322
OS -3.0951424 -3.32114144
OS -2.86765492 -3.41536782
OS -2.8479623 -3.4192845
OS -2.82939998 -3.42697308
OS -2.58790186 -3.47500702
OS -2.56781554 -3.47500702
OS -2.54811784 -3.4789237
OS -2.4250015 -3.47892116
OS 15.39999968 -3.47891862
OS 15.51474164 -3.47891862
OS 15.53444188 -3.4749994
OS 15.55452312 -3.4749994
OS 15.7795976 -3.43022936
OS 15.79814468 -3.42254586
OS 15.81785508 -3.41862664
OS 16.02986888 -3.33080614
OS 16.04657192 -3.31964538
OS 16.06512154 -3.31196188
OS 16.25593142 -3.18446912
OS 16.27013002 -3.17027306
OS 16.2868356 -3.15910976
OS 16.44910858 -2.99683678
OS 16.46027188 -2.9801312
OS 16.47446794 -2.9659326
OS 16.6019607 -2.77512272
OS 16.6096442 -2.75657056
OS 16.62080496 -2.73987006
OS 16.70862546 -2.52785372
OS 16.71254468 -2.50815348
OS 16.72022818 -2.48960132
OS 16.76500076 -2.26452684
OS 16.76500076 -2.24444306
OS 16.76891998 -2.22474282
OS 16.76891998 -2.10999832
OS 16.76891998 13.62999306
OS 16.76977596 13.63867986
OS 16.78000708 13.66337882
OS 16.7916225 13.67499424
OS 16.816324 13.68522536
OS 16.83498284 13.68706432
OS 16.84476946 13.69003358
OS 16.85499042 13.69004374
OS 16.85500312 13.69004628
OS 16.86680142 13.69494848
OS 16.87948364 13.69654614
OS 16.88584888 13.7001758
OS 16.89302946 13.70160328
OS 16.89842696 13.70521008
OS 16.90471346 13.70687632
OS 17.01837846 13.76255312
OS 17.04501798 13.78288074
OS 17.07286908 13.80149132
OS 17.0778805 13.8065002
OS 17.07986678 13.80947454
OS 17.08163208 13.81082074
OS 17.08739026 13.82073436
OS 17.12208412 13.87265704
OS 17.14339726 13.92411236
OS 17.1433998 13.92412252
OS 17.14340488 13.92413014
OS 17.1517183 13.9659487
OS 17.1589192 14.00214878
OS 17.15891666 14.0021564
OS 17.1589192 14.00216656
OS 17.15891666 14.03001512
OS 17.15891666 14.22600152
OS 17.44800168 14.22600152
OS 17.44800168 14.7900009
OS 17.44800168 15.35400028
OS 17.13545976 15.35400028
OS 17.09928 15.3674826
OS 17.01976022 15.42934684
OS 17.01892202 15.48013922
OS 17.01892202 15.63661592
OS 17.11709556 15.71718726
OS 17.1650025 15.70765718
OS 17.3113192 15.7367605
OS 17.4353601 15.81964324
OS 17.51824284 15.94368414
OS 17.54734616 16.09000084
OS 17.54734616 16.85250122
OS 17.51824284 16.99881792
OS 17.51499926 17.00367186
OS 17.51499926 17.7150014
OS 17.82642104 17.7150014
OS 17.8686841 17.68676168
OS 18.0150008 17.65765836
OS 18.48761352 17.65765836
OS 19.11108192 17.03418996
OS 19.11108192 14.35630098
OS 19.11107938 14.35628828
OS 19.12660386 14.27825186
OS 19.17080748 14.21209502
OS 19.1708151 14.21208994
OS 19.63708798 13.74581452
OS 19.63709306 13.7458069
OS 19.7032499 13.70160328
OS 19.78128632 13.68608134
OS 21.91500062 13.68608134
OS 21.99303704 13.70160328
OS 22.05919388 13.7458069
OS 22.1033975 13.81196374
OS 22.11891944 13.89000016
OS 24.58408342 13.89000016
OS 24.71108088 13.76299762
OS 24.71108088 13.76002074
OS 24.70739026 13.72254558
OS 24.67513226 13.64467172
OS 24.6228235 13.59236296
OS 24.54495472 13.56011004
OS 24.50749226 13.55641942
OS 23.87500178 13.55641942
OS 23.87497638 13.55641434
OS 23.81333312 13.55641688
OS 23.73530686 13.54089748
OS 23.73529924 13.5408924
OS 23.62137008 13.49370174
OS 23.62136246 13.4936992
OS 23.55520816 13.44949558
OS 23.46800234 13.3622923
OS 23.42379872 13.29613546
OS 23.42379618 13.29612784
OS 23.37660044 13.18219106
OS 23.36108104 13.1041648
OS 23.36108358 13.04249106
OS 23.36108358 12.8540002
OS 23.08200362 12.8540002
OS 23.08200362 12.29001606
OS 23.08200362 11.72600144
OS 23.36108358 11.72600144
OS 23.36108358 4.17500054
OS 23.36108358 4.06912064
OS 23.36500026 4.04943056
OS 23.36500026 4.02933916
OS 23.40631336 3.82165098
OS 23.41399686 3.80310136
OS 23.41791608 3.78339604
OS 23.49895224 3.58775762
OS 23.51011046 3.57105712
OS 23.5177965 3.55250242
OS 23.63544168 3.3764347
OS 23.6496479 3.36222848
OS 23.66080358 3.34553306
OS 23.81053658 3.19579752
OS 23.82723962 3.18463676
OS 23.84143822 3.17043816
OS 24.01750594 3.05279298
OS 24.03606318 3.04510694
OS 24.05276114 3.03394872
OS 24.24839956 2.95291256
OS 24.26810488 2.94899334
OS 24.2866545 2.94130984
OS 24.49434268 2.89999928
OS 24.51442138 2.89999928
OS 24.53412416 2.89608006
OS 34.07497376 2.89608006
OS 34.15526316 2.89607498
OS 34.17895628 2.90078668
OS 34.20309898 2.90176204
OS 34.35919722 2.93942008
OS 34.38112758 2.94955976
OS 34.40436604 2.95617138
OS 34.5472766 3.02939958
OS 34.56621992 3.04440336
OS 34.5872562 3.0562804
OS 34.7089984 3.16098682
OS 34.71555668 3.16936628
OS 34.7603318 3.19801494
OS 34.85855614 3.20597276
OS 34.90396118 3.16056518
OS 34.92066676 3.14940188
OS 34.93486536 3.13520582
OS 35.07408276 3.04218594
OS 35.09263746 3.0344999
OS 35.10933288 3.02334422
OS 35.26402142 2.95926764
OS 35.28371912 2.95534842
OS 35.30227636 2.94766238
OS 35.46649752 2.91499798
OS 35.4865813 2.91499798
OS 35.50628408 2.91107876
OS 35.59000248 2.9110813
OS 41.86632978 2.9110813
OS 41.88602494 2.91499798
OS 41.90611126 2.91499798
OS 42.05583918 2.94477948
OS 42.07439896 2.95246806
OS 42.09409158 2.95638474
OS 42.2351327 3.01480474
OS 42.2518332 3.02596296
OS 42.27039298 3.03365154
OS 42.3973244 3.11846468
OS 42.41152808 3.13266836
OS 42.4282235 3.14382404
OS 42.5361735 3.2517715
OS 42.54733426 3.26847454
OS 42.56153286 3.28267314
OS 42.64634854 3.4096071
OS 42.65403458 3.4281618
OS 42.6651928 3.4448623
OS 42.7236128 3.58590596
OS 42.72752948 3.60560112
OS 42.73521552 3.62415582
OS 42.76499956 3.77388374
OS 42.76499956 3.79396752
OS 42.76891878 3.81366776
OS 42.76891878 7.41499152
OS 42.7689137 7.41501692
OS 42.7689137 7.41506518
OS 42.7679993 7.41966004
OS 42.76870542 7.424293
OS 42.76339682 7.54147844
OS 42.75495894 7.57572272
OS 42.74808316 7.61028704
OS 42.67346812 7.79042384
OS 42.6292645 7.85658068
OS 42.62925688 7.85658576
OS 42.48158128 8.0042639
OS 42.41542444 8.04846752
OS 42.2224581 8.12839624
OS 42.14442676 8.14391564
OS 42.03999212 8.1439131
OS 40.65400048 8.14391564
OS 40.65400048 8.4330032
OS 40.09001634 8.4330032
OS 40.09001634 8.5600032
OS 39.96301634 8.5600032
OS 39.96301634 9.11399752
OS 39.52600426 9.11399752
OS 39.52600426 9.11400006
OS 39.41626356 9.15567384
OS 39.37580644 9.19613096
OS 39.3096496 9.24033458
OS 39.28872508 9.24900106
OS 39.31398538 9.37600106
OS 39.32399806 9.37600106
OS 39.32399806 9.81300044
OS 38.76999866 9.81300044
OS 38.76999866 9.94000044
OS 38.64299866 9.94000044
OS 38.64299866 10.50399982
OS 38.35391872 10.50399982
OS 38.35391872 11.23158028
OS 38.33839678 11.3096167
OS 38.27978374 11.4511201
OS 38.24699996 11.50018782
OS 38.2670304 11.63468082
OS 38.26771112 11.63721828
OS 38.2954276 11.64464524
OS 38.5585716 11.7965728
OS 38.77342766 12.01142886
OS 38.92535522 12.27457286
OS 39.0039987 12.5680724
OS 39.0039987 12.5929898
OS 37.84999034 12.5929898
OS 36.6960023 12.5929898
OS 36.6960023 12.5680724
OS 36.77464578 12.27457286
OS 36.92657334 12.01142886
OS 37.0670836 11.8709186
OS 37.01447766 11.7439186
OS 35.16499952 11.7439186
OS 35.16496142 11.74391098
OS 35.08046578 11.74391352
OS 35.04591416 11.73704282
OS 34.92099442 11.81245034
OS 34.91891162 11.81459918
OS 34.91891416 22.01000678
OS 34.91890908 22.01003218
OS 34.91891162 22.26017646
OS 34.9149924 22.2798767
OS 34.9149924 22.29996048
OS 34.81738274 22.79068086
OS 34.80969924 22.80923048
OS 34.80578002 22.8289358
OS 34.61430974 23.29118532
OS 34.60315152 23.30788582
OS 34.59546548 23.32644052
OS 34.31749296 23.74245442
OS 34.30328928 23.7566581
OS 34.2921336 23.77335352
OS 33.93834462 24.12714504
OS 33.9216365 24.13830834
OS 33.90744044 24.1525044
OS 33.491424 24.43047438
OS 33.47287184 24.43815788
OS 33.45617134 24.44931864
OS 32.99392182 24.64078638
OS 32.9742165 24.6447056
OS 32.95566688 24.6523891
OS 32.4649465 24.74999622
OS 32.44486526 24.74999622
OS 32.42516248 24.75391544
OS 32.17499534 24.7539129
OS 14.62499996 24.75391798
OE
OB 41.9789991 20.21299996 H
OS 40.80699484 20.21299996
OS 40.80699484 19.04100078
OS 40.85101558 19.04100078
OS 41.18139592 19.12952486
OS 41.4776031 19.30054306
OS 41.71945682 19.54239678
OS 41.89047502 19.83860396
OS 41.9789991 20.1689843
OS 41.9789991 20.21299996
OE
OB 40.55299484 20.21299996 H
OS 39.38100074 20.21299996
OS 39.38100074 20.1689843
OS 39.46952482 19.83860396
OS 39.64054302 19.54239678
OS 39.88239674 19.30054306
OS 40.17860392 19.12952486
OS 40.50898426 19.04100078
OS 40.55299484 19.04100078
OS 40.55299484 20.21299996
OE
OB 13.77800648 17.88801096 H
OS 13.36600324 17.88801096
OS 13.36600324 17.45100142
OS 13.77800648 17.45100142
OS 13.77800648 17.88801096
OE
OB 4.9748186 18.89999776 H
OS 4.6851824 18.89999776
OS 4.40541664 18.82503474
OS 4.15458656 18.68021664
OS 3.94978382 18.4754139
OS 3.80496572 18.22458382
OS 3.7300027 17.94481806
OS 3.7300027 17.65518186
OS 3.80496572 17.3754161
OS 3.94978382 17.12458602
OS 4.15458656 16.91978328
OS 4.40541664 16.77496518
OS 4.6851824 16.70000216
OS 4.9748186 16.70000216
OS 5.25458436 16.77496518
OS 5.50541444 16.91978328
OS 5.71021718 17.12458602
OS 5.85503528 17.3754161
OS 5.9299983 17.65518186
OS 5.9299983 17.94481806
OS 5.85503528 18.22458382
OS 5.71021718 18.4754139
OS 5.50541444 18.68021664
OS 5.25458436 18.82503474
OS 4.9748186 18.89999776
OE
OB 18.12900108 15.35400028 H
OS 17.70200168 15.35400028
OS 17.70200168 14.9170009
OS 18.12900108 14.9170009
OS 18.12900108 15.35400028
OE
OB 38.03431306 19.19999716 H
OS 37.66568794 19.19999716
OS 37.30962312 19.10458968
OS 36.99038322 18.92027712
OS 36.72972334 18.65961724
OS 36.54541078 18.34037734
OS 36.4500033 17.98431252
OS 36.4500033 17.6156874
OS 36.54541078 17.25962258
OS 36.72972334 16.94038268
OS 36.99038322 16.6797228
OS 37.30962312 16.49541024
OS 37.66568794 16.40000276
OS 38.03431306 16.40000276
OS 38.39037788 16.49541024
OS 38.55501306 16.59046212
OS 38.66500014 16.52696212
OS 38.66500014 14.91500192
OS 39.01099894 14.91500192
OS 39.01099894 14.64200018
OS 40.56899938 14.64200018
OS 40.56899938 14.91500192
OS 40.91499818 14.91500192
OS 40.91499818 17.01499772
OS 40.40175308 17.01499772
OS 40.40175308 17.36499956
OS 40.39339902 17.40699338
OS 40.36335844 17.63518952
OS 40.25906858 17.88696448
OS 40.09316848 18.10316928
OS 39.87696368 18.26906938
OS 39.62518872 18.37335924
OS 39.39699258 18.40339982
OS 39.35499876 18.41175388
OS 39.11338126 18.41175388
OS 38.97027766 18.65961724
OS 38.70961778 18.92027712
OS 38.39037788 19.10458968
OS 38.03431306 19.19999716
OE
OB 18.12900108 14.6630009 H
OS 17.70200168 14.6630009
OS 17.70200168 14.22600152
OS 18.12900108 14.22600152
OS 18.12900108 14.6630009
OE
OB 40.56899938 14.38800018 H
OS 39.91699916 14.38800018
OS 39.91699916 13.81100108
OS 40.56899938 13.81100108
OS 40.56899938 14.38800018
OE
OB 39.66299916 14.38800018 H
OS 39.01099894 14.38800018
OS 39.01099894 13.81100108
OS 39.66299916 13.81100108
OS 39.66299916 14.38800018
OE
OB 38.00192806 13.87399816 H
OS 37.97699034 13.87399816
OS 37.97699034 12.8469898
OS 39.0039987 12.8469898
OS 39.0039987 12.87192752
OS 38.92535522 13.16542706
OS 38.77342766 13.42857106
OS 38.5585716 13.64342712
OS 38.2954276 13.79535468
OS 38.00192806 13.87399816
OE
OB 37.72299034 13.87399816 H
OS 37.69807294 13.87399816
OS 37.4045734 13.79535468
OS 37.1414294 13.64342712
OS 36.92657334 13.42857106
OS 36.77464578 13.16542706
OS 36.6960023 12.87192752
OS 36.6960023 12.8469898
OS 37.72299034 12.8469898
OS 37.72299034 13.87399816
OE
OB 22.82800362 12.8540002 H
OS 22.40100422 12.8540002
OS 22.40100422 12.41701606
OS 22.82800362 12.41701606
OS 22.82800362 12.8540002
OE
OB 22.82800362 12.16301606 H
OS 22.40100422 12.16301606
OS 22.40100422 11.72600144
OS 22.82800362 11.72600144
OS 22.82800362 12.16301606
OE
OB 39.32399806 10.50399982 H
OS 38.89699866 10.50399982
OS 38.89699866 10.06700044
OS 39.32399806 10.06700044
OS 39.32399806 10.50399982
OE
OB 40.65400048 9.11399752 H
OS 40.21701634 9.11399752
OS 40.21701634 8.6870032
OS 40.65400048 8.6870032
OS 40.65400048 9.11399752
OE
OB 40.8039062 1.24499878 H
OS 40.4760938 1.24499878
OS 40.15944724 1.16015516
OS 39.87555144 0.99624896
OS 39.64375104 0.76444856
OS 39.47984484 0.48055276
OS 39.39500122 0.1639062
OS 39.39500122 -0.1639062
OS 39.47984484 -0.48055276
OS 39.64375104 -0.76444856
OS 39.87555144 -0.99624896
OS 40.15944724 -1.16015516
OS 40.4760938 -1.24499878
OS 40.8039062 -1.24499878
OS 41.12055276 -1.16015516
OS 41.40444856 -0.99624896
OS 41.63624896 -0.76444856
OS 41.80015516 -0.48055276
OS 41.88499878 -0.1639062
OS 41.88499878 0.1639062
OS 41.80015516 0.48055276
OS 41.63624896 0.76444856
OS 41.40444856 0.99624896
OS 41.12055276 1.16015516
OS 40.8039062 1.24499878
OE
OB 43.18999998 -1.59964374 H
OS 42.8767367 -1.64088572
OS 42.58482212 -1.76179988
OS 42.33414952 -1.954149
OS 42.1418004 -2.2048216
OS 42.02088624 -2.49673618
OS 41.97964426 -2.80999946
OS 42.02088624 -3.12326274
OS 42.1418004 -3.41517732
OS 42.33414952 -3.66584992
OS 42.58482212 -3.85819904
OS 42.8767367 -3.9791132
OS 43.18999998 -4.02035518
OS 43.50326326 -3.9791132
OS 43.79517784 -3.85819904
OS 44.04585044 -3.66584992
OS 44.23819956 -3.41517732
OS 44.35911372 -3.12326274
OS 44.4003557 -2.80999946
OS 44.35911372 -2.49673618
OS 44.23819956 -2.2048216
OS 44.04585044 -1.954149
OS 43.79517784 -1.76179988
OS 43.50326326 -1.64088572
OS 43.18999998 -1.59964374
OE
OB 20.66429954 1.58999936 H
OS 20.21569998 1.58999936
OS 19.77262238 1.51982424
OS 19.34597858 1.38119866
OS 18.94627402 1.17753892
OS 18.58334866 0.91385898
OS 18.26614076 0.59665108
OS 18.00246082 0.23372572
OS 17.79880108 -0.16597884
OS 17.6601755 -0.59262264
OS 17.59000038 -1.03570024
OS 17.59000038 -1.4842998
OS 17.6601755 -1.9273774
OS 17.79880108 -2.3540212
OS 18.00246082 -2.75372576
OS 18.26614076 -3.11665112
OS 18.58334866 -3.43385902
OS 18.94627402 -3.69753896
OS 19.34597858 -3.9011987
OS 19.77262238 -4.03982428
OS 20.21569998 -4.1099994
OS 20.66429954 -4.1099994
OS 21.10737714 -4.03982428
OS 21.53402094 -3.9011987
OS 21.9337255 -3.69753896
OS 22.29665086 -3.43385902
OS 22.61385876 -3.11665112
OS 22.8775387 -2.75372576
OS 23.08119844 -2.3540212
OS 23.21982402 -1.9273774
OS 23.28999914 -1.4842998
OS 23.28999914 -1.03570024
OS 23.21982402 -0.59262264
OS 23.08119844 -0.16597884
OS 22.8775387 0.23372572
OS 22.61385876 0.59665108
OS 22.29665086 0.91385898
OS 21.9337255 1.17753892
OS 21.53402094 1.38119866
OS 21.10737714 1.51982424
OS 20.66429954 1.58999936
OE
OB 35.75971512 2.29999794 H
OS 35.24028512 2.29999794
OS 34.7272483 2.2187408
OS 34.23324116 2.05822804
OS 33.77042522 1.82240936
OS 33.35019492 1.51709628
OS 32.9829033 1.14980466
OS 32.67759022 0.72957436
OS 32.44177154 0.26675842
OS 32.28125878 -0.22724872
OS 32.20000164 -0.74028554
OS 32.20000164 -1.25971554
OS 32.28125878 -1.77275236
OS 32.44177154 -2.2667595
OS 32.67759022 -2.72957544
OS 32.9829033 -3.14980574
OS 33.35019492 -3.51709736
OS 33.77042522 -3.82241044
OS 34.23324116 -4.05822912
OS 34.7272483 -4.21874188
OS 35.24028512 -4.29999902
OS 35.75971512 -4.29999902
OS 36.27275194 -4.21874188
OS 36.76675908 -4.05822912
OS 37.22957502 -3.82241044
OS 37.64980532 -3.51709736
OS 38.01709694 -3.14980574
OS 38.32241002 -2.72957544
OS 38.5582287 -2.2667595
OS 38.71874146 -1.77275236
OS 38.7999986 -1.25971554
OS 38.7999986 -0.74028554
OS 38.71874146 -0.22724872
OS 38.5582287 0.26675842
OS 38.32241002 0.72957436
OS 38.01709694 1.14980466
OS 37.64980532 1.51709628
OS 37.22957502 1.82240936
OS 36.76675908 2.05822804
OS 36.27275194 2.2187408
OS 35.75971512 2.29999794
OE
OB 24.0646585 23.8176562 I
OS 24.07713244 23.81517462
OS 24.0771426 23.81517462
OS 24.0771553 23.81516954
OS 24.20613904 23.78951554
OS 24.33473924 23.7362492
OS 24.4504845 23.65890874
OS 24.54891458 23.56047866
OS 24.62624996 23.44473594
OS 24.6795163 23.31613828
OS 24.70765696 23.17466028
OS 24.7110758 23.10501602
OS 24.71107834 19.69000126
OS 22.11891944 19.69000126
OS 22.11891944 20.19000026
OS 22.1033975 20.26803668
OS 22.05919388 20.33419352
OS 21.99303704 20.37839714
OS 21.91500062 20.39391908
OS 19.54783492 20.39392162
OS 19.54783492 20.66500058
OS 19.63999882 20.66500058
OS 19.63999882 21.68499854
OS 17.72000266 21.68499854
OS 17.72000266 21.47736624
OS 17.55649778 21.47112546
OS 17.46499682 21.55919996
OS 17.46499682 21.65999732
OS 17.2608748 21.65999732
OS 17.2608748 21.88000196
OS 17.38499698 21.88000196
OS 17.38499698 22.70000032
OS 16.7789987 22.70000032
OS 16.7789987 22.75400072
OS 16.42200424 22.75400072
OS 16.42200424 22.29001638
OS 16.42200424 21.82600156
OS 16.64912088 21.82600156
OS 16.64912088 21.65999732
OS 16.44499886 21.65999732
OS 16.44499886 21.39556046
OS 16.32899706 21.36900222
OS 16.32899706 21.36899968
OS 15.99201018 21.36899968
OS 15.99201018 20.89498996
OS 15.73801018 20.89498996
OS 15.73801018 21.36899968
OS 15.40100552 21.36899968
OS 15.40100044 21.36900476
OS 15.40100044 21.36900222
OS 15.27891788 21.38087418
OS 15.27891788 23.53997324
OS 15.28409694 23.59257664
OS 15.32792464 23.69838542
OS 15.40161258 23.77207082
OS 15.5074239 23.81590106
OS 15.56000698 23.82108012
OS 23.99488978 23.82108012
OS 24.0646585 23.8176562
OE
OB 16.16800424 22.75400072 H
OS 15.81099962 22.75400072
OS 15.81099962 22.41701638
OS 16.16800424 22.41701638
OS 16.16800424 22.75400072
OE
OB 16.16800424 22.16301638 H
OS 15.81099962 22.16301638
OS 15.81099962 21.82600156
OS 16.16800424 21.82600156
OS 16.16800424 22.16301638
OE
SE
S P 0
OB -1.8920841 -38.48662356 I
OS -1.88561218 -38.48662356
OS -1.87914026 -38.48754812
OS -1.86342274 -38.4903218
OS -1.84678066 -38.4949446
OS -1.82921402 -38.50234108
OS -1.81164738 -38.51158668
OS -1.79685442 -38.52453052
OS -1.7950053 -38.52637964
OS -1.79130706 -38.531927
OS -1.78483514 -38.54024804
OS -1.78206146 -38.54671996
OS -1.77836322 -38.55319188
OS -1.77466498 -38.56151292
OS -1.7718913 -38.56983396
OS -1.76819306 -38.57907956
OS -1.76541938 -38.59017428
OS -1.76357026 -38.601269
OS -1.76172114 -38.61421284
OS -1.75987202 -38.62715668
OS -1.75987202 -38.64194964
OS -1.75987202 -38.95999828
OS -1.83845962 -38.95999828
OS -1.83845962 -38.66876188
OS -1.83845962 -38.66783732
OS -1.83845962 -38.66691276
OS -1.83845962 -38.6613654
OS -1.83845962 -38.65304436
OS -1.83938418 -38.6428742
OS -1.84030874 -38.63177948
OS -1.8412333 -38.62068476
OS -1.84308242 -38.60959004
OS -1.8458561 -38.601269
OS -1.8458561 -38.60034444
OS -1.84770522 -38.59757076
OS -1.84955434 -38.59387252
OS -1.85232802 -38.58924972
OS -1.85602626 -38.58370236
OS -1.86064906 -38.578155
OS -1.86619642 -38.57260764
OS -1.8735929 -38.56706028
OS -1.87451746 -38.56613572
OS -1.87729114 -38.56521116
OS -1.88098938 -38.56336204
OS -1.8874613 -38.56058836
OS -1.89393322 -38.55781468
OS -1.90225426 -38.55596556
OS -1.9105753 -38.555041
OS -1.92074546 -38.55411644
OS -1.92536826 -38.55411644
OS -1.9290665 -38.555041
OS -1.9383121 -38.55596556
OS -1.94940682 -38.55781468
OS -1.96235066 -38.56243748
OS -1.97621906 -38.56798484
OS -1.99008746 -38.57630588
OS -2.0030313 -38.5874006
OS -2.00395586 -38.58924972
OS -2.0076541 -38.59387252
OS -2.01320146 -38.601269
OS -2.01874882 -38.61236372
OS -2.02522074 -38.62715668
OS -2.02984354 -38.64472332
OS -2.03354178 -38.6659882
OS -2.0353909 -38.69095132
OS -2.0353909 -38.95999828
OS -2.1139785 -38.95999828
OS -2.1139785 -38.65951628
OS -2.1139785 -38.65859172
OS -2.1139785 -38.6567426
OS -2.1139785 -38.65489348
OS -2.1139785 -38.65119524
OS -2.11490306 -38.64102508
OS -2.11675218 -38.62993036
OS -2.1186013 -38.61698652
OS -2.12229954 -38.60404268
OS -2.12692234 -38.5920234
OS -2.13339426 -38.58092868
OS -2.13431882 -38.58000412
OS -2.1370925 -38.57630588
OS -2.1417153 -38.57260764
OS -2.14818722 -38.56706028
OS -2.15650826 -38.56243748
OS -2.16760298 -38.55781468
OS -2.18054682 -38.555041
OS -2.19626434 -38.55411644
OS -2.2018117 -38.55411644
OS -2.20828362 -38.555041
OS -2.2156801 -38.55596556
OS -2.2249257 -38.55873924
OS -2.23602042 -38.56151292
OS -2.24619058 -38.56613572
OS -2.2572853 -38.57168308
OS -2.25820986 -38.57260764
OS -2.2619081 -38.57538132
OS -2.2665309 -38.57907956
OS -2.27300282 -38.58462692
OS -2.27947474 -38.5920234
OS -2.28594666 -38.601269
OS -2.29241858 -38.61143916
OS -2.29796594 -38.62345844
OS -2.2988905 -38.62530756
OS -2.29981506 -38.62993036
OS -2.30166418 -38.63732684
OS -2.30443786 -38.647497
OS -2.30721154 -38.6613654
OS -2.30906066 -38.67800748
OS -2.30998522 -38.69742324
OS -2.31090978 -38.71961268
OS -2.31090978 -38.95999828
OS -2.38949738 -38.95999828
OS -2.38949738 -38.49586916
OS -2.31923082 -38.49586916
OS -2.31923082 -38.56243748
OS -2.31830626 -38.56058836
OS -2.31553258 -38.55689012
OS -2.30998522 -38.5504182
OS -2.3035133 -38.54302172
OS -2.29519226 -38.53377612
OS -2.2850221 -38.52453052
OS -2.27392738 -38.51528492
OS -2.26098354 -38.50696388
OS -2.25913442 -38.50603932
OS -2.25451162 -38.50326564
OS -2.24711514 -38.50049196
OS -2.23694498 -38.49586916
OS -2.2249257 -38.49217092
OS -2.2110573 -38.48939724
OS -2.19533978 -38.48662356
OS -2.1786977 -38.485699
OS -2.17037666 -38.485699
OS -2.1602065 -38.48662356
OS -2.14911178 -38.48847268
OS -2.13524338 -38.49124636
OS -2.12137498 -38.4949446
OS -2.10750658 -38.50049196
OS -2.09456274 -38.50788844
OS -2.09271362 -38.508813
OS -2.08901538 -38.51158668
OS -2.08346802 -38.51620948
OS -2.07607154 -38.52360596
OS -2.06867506 -38.531927
OS -2.06035402 -38.54209716
OS -2.05295754 -38.55411644
OS -2.04741018 -38.56798484
OS -2.04648562 -38.56706028
OS -2.0446365 -38.5642866
OS -2.04186282 -38.56058836
OS -2.03724002 -38.555041
OS -2.03169266 -38.54856908
OS -2.02522074 -38.54209716
OS -2.01782426 -38.53470068
OS -2.00857866 -38.52637964
OS -1.9984085 -38.51898316
OS -1.98823834 -38.51158668
OS -1.97621906 -38.50511476
OS -1.96327522 -38.49864284
OS -1.94940682 -38.49309548
OS -1.93461386 -38.48939724
OS -1.9198209 -38.48662356
OS -1.90317882 -38.485699
OS -1.8967069 -38.485699
OS -1.8920841 -38.48662356
OE
OB -1.19589042 -39.1375138 I
OS -1.7164177 -39.1375138
OS -1.7164177 -39.08111564
OS -1.19589042 -39.08111564
OS -1.19589042 -39.1375138
OE
OB -2.6825829 -38.48662356 I
OS -2.67426186 -38.48754812
OS -2.66501626 -38.48939724
OS -2.6548461 -38.49124636
OS -2.64282682 -38.49309548
OS -2.6178637 -38.50141652
OS -2.60491986 -38.50603932
OS -2.59197602 -38.51251124
OS -2.57903218 -38.51898316
OS -2.56608834 -38.52822876
OS -2.55406906 -38.53747436
OS -2.54204978 -38.54856908
OS -2.54112522 -38.54949364
OS -2.5392761 -38.55134276
OS -2.53650242 -38.555041
OS -2.53280418 -38.5596638
OS -2.52818138 -38.56613572
OS -2.52263402 -38.57445676
OS -2.51708666 -38.58370236
OS -2.5115393 -38.59387252
OS -2.50599194 -38.60496724
OS -2.50044458 -38.61883564
OS -2.49489722 -38.63270404
OS -2.49027442 -38.64842156
OS -2.48657618 -38.66506364
OS -2.4838025 -38.68263028
OS -2.48195338 -38.70112148
OS -2.48102882 -38.7214618
OS -2.48102882 -38.72238636
OS -2.48102882 -38.72516004
OS -2.48102882 -38.72978284
OS -2.48102882 -38.73625476
OS -2.48195338 -38.74365124
OS -2.48287794 -38.75289684
OS -2.48287794 -38.76214244
OS -2.48472706 -38.7723126
OS -2.48750074 -38.7954266
OS -2.4930481 -38.8185406
OS -2.49952002 -38.8416546
OS -2.50876562 -38.86291948
OS -2.50876562 -38.86384404
OS -2.50969018 -38.8647686
OS -2.5115393 -38.86754228
OS -2.51338842 -38.87124052
OS -2.51986034 -38.88048612
OS -2.52818138 -38.89158084
OS -2.5392761 -38.90452468
OS -2.5531445 -38.91746852
OS -2.56886202 -38.93041236
OS -2.58735322 -38.94243164
OS -2.58827778 -38.94243164
OS -2.58920234 -38.9433562
OS -2.59197602 -38.94520532
OS -2.59659882 -38.94705444
OS -2.60122162 -38.94890356
OS -2.60676898 -38.95075268
OS -2.62063738 -38.95630004
OS -2.6363549 -38.96092284
OS -2.65577066 -38.96554564
OS -2.67611098 -38.96924388
OS -2.69830042 -38.97016844
OS -2.70754602 -38.97016844
OS -2.7149425 -38.96924388
OS -2.72326354 -38.96831932
OS -2.73250914 -38.9664702
OS -2.74360386 -38.96462108
OS -2.75469858 -38.96277196
OS -2.7796617 -38.95537548
OS -2.7935301 -38.94982812
OS -2.80647394 -38.94428076
OS -2.81941778 -38.93688428
OS -2.83236162 -38.92856324
OS -2.8443809 -38.91931764
OS -2.85640018 -38.90822292
OS -2.85732474 -38.90729836
OS -2.85917386 -38.90544924
OS -2.86194754 -38.901751
OS -2.86564578 -38.89620364
OS -2.87026858 -38.88973172
OS -2.87489138 -38.88233524
OS -2.88043874 -38.87308964
OS -2.8859861 -38.86199492
OS -2.89153346 -38.84997564
OS -2.89708082 -38.83610724
OS -2.90170362 -38.82131428
OS -2.90632642 -38.80559676
OS -2.91002466 -38.78803012
OS -2.91279834 -38.76953892
OS -2.91464746 -38.7491986
OS -2.91557202 -38.72793372
OS -2.91557202 -38.7260846
OS -2.91557202 -38.72238636
OS -2.91464746 -38.71591444
OS -2.91464746 -38.70666884
OS -2.9137229 -38.69649868
OS -2.91187378 -38.68355484
OS -2.91002466 -38.670611
OS -2.90632642 -38.65581804
OS -2.90262818 -38.64102508
OS -2.89800538 -38.62530756
OS -2.89245802 -38.60866548
OS -2.88506154 -38.59294796
OS -2.87766506 -38.578155
OS -2.8674949 -38.56336204
OS -2.85732474 -38.54949364
OS -2.8443809 -38.53747436
OS -2.84345634 -38.5365498
OS -2.84160722 -38.53562524
OS -2.83790898 -38.53285156
OS -2.83328618 -38.52915332
OS -2.82773882 -38.52545508
OS -2.82034234 -38.52083228
OS -2.81294586 -38.51620948
OS -2.80370026 -38.51158668
OS -2.7935301 -38.50696388
OS -2.78243538 -38.50234108
OS -2.75747226 -38.49402004
OS -2.7288109 -38.48754812
OS -2.71401794 -38.48662356
OS -2.69830042 -38.485699
OS -2.68905482 -38.485699
OS -2.6825829 -38.48662356
OE
OB -3.29186794 -38.49586916 I
OS -3.21235578 -38.49586916
OS -3.21235578 -38.55689012
OS -3.29186794 -38.55689012
OS -3.29186794 -38.82963532
OS -3.29186794 -38.83148444
OS -3.29186794 -38.83518268
OS -3.29186794 -38.84073004
OS -3.29094338 -38.84720196
OS -3.29001882 -38.86199492
OS -3.28909426 -38.86846684
OS -3.2881697 -38.87308964
OS -3.28724514 -38.87493876
OS -3.28447146 -38.878637
OS -3.28077322 -38.8832598
OS -3.2743013 -38.8878826
OS -3.27245218 -38.88880716
OS -3.26782938 -38.89065628
OS -3.25950834 -38.8925054
OS -3.24748906 -38.89342996
OS -3.23824346 -38.89342996
OS -3.23362066 -38.8925054
OS -3.22714874 -38.8925054
OS -3.21975226 -38.89158084
OS -3.21235578 -38.89065628
OS -3.20218562 -38.95999828
OS -3.20403474 -38.95999828
OS -3.20773298 -38.96092284
OS -3.2142049 -38.9618474
OS -3.22252594 -38.96277196
OS -3.23177154 -38.96462108
OS -3.2419417 -38.96554564
OS -3.26228202 -38.9664702
OS -3.2696785 -38.9664702
OS -3.27707498 -38.96554564
OS -3.28632058 -38.96462108
OS -3.2974153 -38.96369652
OS -3.30851002 -38.96092284
OS -3.31868018 -38.95814916
OS -3.32885034 -38.95352636
OS -3.3297749 -38.9526018
OS -3.33254858 -38.95075268
OS -3.33624682 -38.947979
OS -3.34179418 -38.9433562
OS -3.34641698 -38.9387334
OS -3.35196434 -38.93226148
OS -3.3575117 -38.92578956
OS -3.36120994 -38.91746852
OS -3.36120994 -38.91654396
OS -3.36305906 -38.91284572
OS -3.36398362 -38.9063738
OS -3.36583274 -38.8971282
OS -3.36768186 -38.88510892
OS -3.36860642 -38.87771244
OS -3.36860642 -38.8693914
OS -3.36953098 -38.85922124
OS -3.37045554 -38.84905108
OS -3.37045554 -38.83795636
OS -3.37045554 -38.82501252
OS -3.37045554 -38.55689012
OS -3.42870282 -38.55689012
OS -3.42870282 -38.49586916
OS -3.37045554 -38.49586916
OS -3.37045554 -38.38122372
OS -3.29186794 -38.33407116
OS -3.29186794 -38.49586916
OE
OB -3.0431613 -38.49586916 I
OS -2.96364914 -38.49586916
OS -2.96364914 -38.55689012
OS -3.0431613 -38.55689012
OS -3.0431613 -38.82963532
OS -3.0431613 -38.83148444
OS -3.0431613 -38.83518268
OS -3.0431613 -38.84073004
OS -3.04223674 -38.84720196
OS -3.04131218 -38.86199492
OS -3.04038762 -38.86846684
OS -3.03946306 -38.87308964
OS -3.0385385 -38.87493876
OS -3.03576482 -38.878637
OS -3.03206658 -38.8832598
OS -3.02559466 -38.8878826
OS -3.02374554 -38.88880716
OS -3.01912274 -38.89065628
OS -3.0108017 -38.8925054
OS -2.99878242 -38.89342996
OS -2.98953682 -38.89342996
OS -2.98491402 -38.8925054
OS -2.9784421 -38.8925054
OS -2.97104562 -38.89158084
OS -2.96364914 -38.89065628
OS -2.95347898 -38.95999828
OS -2.9553281 -38.95999828
OS -2.95902634 -38.96092284
OS -2.96549826 -38.9618474
OS -2.9738193 -38.96277196
OS -2.9830649 -38.96462108
OS -2.99323506 -38.96554564
OS -3.01357538 -38.9664702
OS -3.02097186 -38.9664702
OS -3.02836834 -38.96554564
OS -3.03761394 -38.96462108
OS -3.04870866 -38.96369652
OS -3.05980338 -38.96092284
OS -3.06997354 -38.95814916
OS -3.0801437 -38.95352636
OS -3.08106826 -38.9526018
OS -3.08384194 -38.95075268
OS -3.08754018 -38.947979
OS -3.09308754 -38.9433562
OS -3.09771034 -38.9387334
OS -3.1032577 -38.93226148
OS -3.10880506 -38.92578956
OS -3.1125033 -38.91746852
OS -3.1125033 -38.91654396
OS -3.11435242 -38.91284572
OS -3.11527698 -38.9063738
OS -3.1171261 -38.8971282
OS -3.11897522 -38.88510892
OS -3.11989978 -38.87771244
OS -3.11989978 -38.8693914
OS -3.12082434 -38.85922124
OS -3.1217489 -38.84905108
OS -3.1217489 -38.83795636
OS -3.1217489 -38.82501252
OS -3.1217489 -38.55689012
OS -3.17999618 -38.55689012
OS -3.17999618 -38.49586916
OS -3.1217489 -38.49586916
OS -3.1217489 -38.38122372
OS -3.0431613 -38.33407116
OS -3.0431613 -38.49586916
OE
OB -0.73083674 -38.48662356 I
OS -0.71696834 -38.48754812
OS -0.70125082 -38.48939724
OS -0.6855333 -38.49217092
OS -0.66981578 -38.49586916
OS -0.65502282 -38.50049196
OS -0.6531737 -38.50141652
OS -0.6485509 -38.50326564
OS -0.64207898 -38.50603932
OS -0.63375794 -38.50973756
OS -0.62451234 -38.51528492
OS -0.61526674 -38.52083228
OS -0.6069457 -38.52822876
OS -0.59954922 -38.53562524
OS -0.59862466 -38.5365498
OS -0.59677554 -38.53932348
OS -0.59400186 -38.54394628
OS -0.59030362 -38.54949364
OS -0.58568082 -38.55781468
OS -0.58198258 -38.56613572
OS -0.57828434 -38.57630588
OS -0.57551066 -38.58832516
OS -0.57551066 -38.58924972
OS -0.5745861 -38.5920234
OS -0.57366154 -38.59757076
OS -0.57273698 -38.60496724
OS -0.57273698 -38.6151374
OS -0.57181242 -38.62715668
OS -0.57088786 -38.6428742
OS -0.57088786 -38.66044084
OS -0.57088786 -38.76584068
OS -0.57088786 -38.76676524
OS -0.57088786 -38.77046348
OS -0.57088786 -38.77601084
OS -0.57088786 -38.78340732
OS -0.57088786 -38.79172836
OS -0.57088786 -38.80189852
OS -0.5699633 -38.82408796
OS -0.5699633 -38.84720196
OS -0.56903874 -38.87031596
OS -0.56811418 -38.88048612
OS -0.56811418 -38.88973172
OS -0.56718962 -38.89805276
OS -0.56626506 -38.90452468
OS -0.56626506 -38.90544924
OS -0.5653405 -38.90914748
OS -0.56441594 -38.91469484
OS -0.56164226 -38.92209132
OS -0.55979314 -38.93041236
OS -0.5560949 -38.93965796
OS -0.5514721 -38.94982812
OS -0.5468493 -38.95999828
OS -0.62913514 -38.95999828
OS -0.6300597 -38.95907372
OS -0.63098426 -38.95537548
OS -0.63283338 -38.95075268
OS -0.63560706 -38.9433562
OS -0.63838074 -38.93503516
OS -0.64022986 -38.924865
OS -0.64207898 -38.91377028
OS -0.6439281 -38.901751
OS -0.64485266 -38.901751
OS -0.64577722 -38.90360012
OS -0.65132458 -38.90822292
OS -0.65964562 -38.91469484
OS -0.67074034 -38.92301588
OS -0.68460874 -38.93133692
OS -0.69847714 -38.94058252
OS -0.7132701 -38.94890356
OS -0.72898762 -38.95537548
OS -0.73083674 -38.95630004
OS -0.7363841 -38.9572246
OS -0.74470514 -38.95999828
OS -0.7548753 -38.96277196
OS -0.76781914 -38.96554564
OS -0.7826121 -38.96739476
OS -0.79925418 -38.96924388
OS -0.81589626 -38.97016844
OS -0.82329274 -38.97016844
OS -0.8288401 -38.96924388
OS -0.83531202 -38.96924388
OS -0.8427085 -38.96831932
OS -0.85935058 -38.96554564
OS -0.87784178 -38.96092284
OS -0.8981821 -38.95445092
OS -0.9166733 -38.94520532
OS -0.93331538 -38.93318604
OS -0.9351645 -38.93133692
OS -0.9397873 -38.92671412
OS -0.94625922 -38.91839308
OS -0.9536557 -38.90729836
OS -0.96105218 -38.89342996
OS -0.9675241 -38.87771244
OS -0.9721469 -38.85829668
OS -0.97307146 -38.84905108
OS -0.97399602 -38.83795636
OS -0.97399602 -38.83610724
OS -0.97399602 -38.832409
OS -0.97307146 -38.82593708
OS -0.9721469 -38.81761604
OS -0.97029778 -38.80744588
OS -0.9675241 -38.79727572
OS -0.96382586 -38.786181
OS -0.95920306 -38.77601084
OS -0.9582785 -38.77508628
OS -0.95642938 -38.77138804
OS -0.95273114 -38.76584068
OS -0.94810834 -38.75936876
OS -0.94256098 -38.75197228
OS -0.9351645 -38.7445758
OS -0.92776802 -38.73717932
OS -0.91852242 -38.7307074
OS -0.91759786 -38.72978284
OS -0.91389962 -38.72793372
OS -0.90927682 -38.72423548
OS -0.90188034 -38.72053724
OS -0.8935593 -38.716839
OS -0.88338914 -38.7122162
OS -0.87321898 -38.70851796
OS -0.8611997 -38.70481972
OS -0.86027514 -38.70481972
OS -0.8565769 -38.70389516
OS -0.85102954 -38.70204604
OS -0.84363306 -38.70112148
OS -0.83438746 -38.69927236
OS -0.82236818 -38.69742324
OS -0.80849978 -38.69464956
OS -0.7918577 -38.69280044
OS -0.79093314 -38.69280044
OS -0.7872349 -38.69187588
OS -0.7826121 -38.69187588
OS -0.77614018 -38.69095132
OS -0.7687437 -38.69002676
OS -0.7594981 -38.68817764
OS -0.74932794 -38.68725308
OS -0.73823322 -38.68540396
OS -0.71604378 -38.68078116
OS -0.69200522 -38.67615836
OS -0.67074034 -38.670611
OS -0.66057018 -38.66783732
OS -0.65132458 -38.66506364
OS -0.65132458 -38.66413908
OS -0.65132458 -38.66228996
OS -0.65040002 -38.6567426
OS -0.65040002 -38.65027068
OS -0.65040002 -38.64657244
OS -0.65040002 -38.64472332
OS -0.65040002 -38.64379876
OS -0.65040002 -38.6428742
OS -0.65040002 -38.63732684
OS -0.65132458 -38.62808124
OS -0.6531737 -38.61791108
OS -0.65594738 -38.60681636
OS -0.66057018 -38.59572164
OS -0.66611754 -38.58555148
OS -0.67351402 -38.57723044
OS -0.67443858 -38.57630588
OS -0.67906138 -38.57260764
OS -0.68645786 -38.5689094
OS -0.69570346 -38.56336204
OS -0.7086473 -38.55873924
OS -0.72344026 -38.55411644
OS -0.74193146 -38.55134276
OS -0.76319634 -38.5504182
OS -0.77244194 -38.5504182
OS -0.78168754 -38.55134276
OS -0.79463138 -38.55319188
OS -0.80757522 -38.555041
OS -0.82144362 -38.55873924
OS -0.83438746 -38.56336204
OS -0.84548218 -38.56983396
OS -0.84640674 -38.57075852
OS -0.85010498 -38.5735322
OS -0.85472778 -38.578155
OS -0.86027514 -38.58555148
OS -0.8658225 -38.59479708
OS -0.87229442 -38.60681636
OS -0.87784178 -38.62160932
OS -0.88338914 -38.6382514
OS -0.96012762 -38.62808124
OS -0.96012762 -38.62715668
OS -0.95920306 -38.62623212
OS -0.95920306 -38.62345844
OS -0.9582785 -38.6197602
OS -0.95550482 -38.61143916
OS -0.95180658 -38.59941988
OS -0.94718378 -38.5874006
OS -0.94163642 -38.57445676
OS -0.93423994 -38.56151292
OS -0.9259189 -38.54949364
OS -0.92499434 -38.54856908
OS -0.9212961 -38.54487084
OS -0.91574874 -38.53932348
OS -0.90835226 -38.531927
OS -0.8981821 -38.52453052
OS -0.88616282 -38.51713404
OS -0.87229442 -38.508813
OS -0.8565769 -38.50234108
OS -0.85565234 -38.50234108
OS -0.85472778 -38.50141652
OS -0.8519541 -38.50049196
OS -0.84825586 -38.4995674
OS -0.83901026 -38.49679372
OS -0.82606642 -38.49402004
OS -0.81127346 -38.49124636
OS -0.79278226 -38.48847268
OS -0.7733665 -38.48662356
OS -0.75117706 -38.485699
OS -0.7410069 -38.485699
OS -0.73083674 -38.48662356
OE
OB 0.68004182 -38.48662356 I
OS 0.69021198 -38.48847268
OS 0.70223126 -38.49217092
OS 0.7151751 -38.49679372
OS 0.72996806 -38.50326564
OS 0.74568558 -38.51158668
OS 0.71702422 -38.58370236
OS 0.71609966 -38.5827778
OS 0.71240142 -38.58092868
OS 0.70685406 -38.578155
OS 0.69945758 -38.57538132
OS 0.69113654 -38.57260764
OS 0.68096638 -38.56983396
OS 0.67079622 -38.56798484
OS 0.66062606 -38.56706028
OS 0.65600326 -38.56706028
OS 0.65138046 -38.56798484
OS 0.64490854 -38.5689094
OS 0.63843662 -38.57075852
OS 0.63011558 -38.5735322
OS 0.62179454 -38.57723044
OS 0.61439806 -38.5827778
OS 0.6134735 -38.58370236
OS 0.61069982 -38.58555148
OS 0.60792614 -38.58924972
OS 0.60330334 -38.59387252
OS 0.59868054 -38.60034444
OS 0.59405774 -38.60774092
OS 0.58943494 -38.61606196
OS 0.5857367 -38.62623212
OS 0.58481214 -38.62808124
OS 0.58388758 -38.6336286
OS 0.58203846 -38.64194964
OS 0.57926478 -38.65304436
OS 0.5764911 -38.66691276
OS 0.57464198 -38.68263028
OS 0.57371742 -38.69927236
OS 0.57279286 -38.71776356
OS 0.57279286 -38.95999828
OS 0.49420526 -38.95999828
OS 0.49420526 -38.49586916
OS 0.56539638 -38.49586916
OS 0.56539638 -38.56613572
OS 0.56632094 -38.56521116
OS 0.57001918 -38.55873924
OS 0.57464198 -38.5504182
OS 0.58203846 -38.54024804
OS 0.58943494 -38.53007788
OS 0.59775598 -38.51898316
OS 0.60607702 -38.50973756
OS 0.61439806 -38.50234108
OS 0.61532262 -38.50141652
OS 0.6180963 -38.4995674
OS 0.62364366 -38.49679372
OS 0.62919102 -38.49402004
OS 0.6365875 -38.49124636
OS 0.6458331 -38.48847268
OS 0.6550787 -38.48662356
OS 0.66524886 -38.485699
OS 0.67172078 -38.485699
OS 0.68004182 -38.48662356
OE
OB 0.8631047 -38.42745172 I
OS 0.84183982 -38.54671996
OS 0.79283814 -38.54671996
OS 0.77342238 -38.42745172
OS 0.77342238 -38.32020276
OS 0.8631047 -38.32020276
OS 0.8631047 -38.42745172
OE
OB 0.20296886 -38.48662356 I
OS 0.21036534 -38.48754812
OS 0.21961094 -38.48939724
OS 0.2297811 -38.49124636
OS 0.24180038 -38.49402004
OS 0.2528951 -38.49679372
OS 0.26583894 -38.50141652
OS 0.27785822 -38.50603932
OS 0.29080206 -38.51251124
OS 0.3037459 -38.51990772
OS 0.31668974 -38.52822876
OS 0.32870902 -38.53839892
OS 0.33980374 -38.54949364
OS 0.3407283 -38.5504182
OS 0.34257742 -38.55226732
OS 0.3453511 -38.55596556
OS 0.34904934 -38.56151292
OS 0.35367214 -38.56798484
OS 0.35829494 -38.57538132
OS 0.3638423 -38.58462692
OS 0.36938966 -38.59572164
OS 0.37493702 -38.60774092
OS 0.38048438 -38.62068476
OS 0.38510718 -38.63547772
OS 0.38972998 -38.65119524
OS 0.39342822 -38.66876188
OS 0.3962019 -38.68725308
OS 0.39805102 -38.70666884
OS 0.39897558 -38.72793372
OS 0.39897558 -38.72885828
OS 0.39897558 -38.73255652
OS 0.39897558 -38.73902844
OS 0.39805102 -38.74827404
OS 0.05134102 -38.74827404
OS 0.05134102 -38.7491986
OS 0.05134102 -38.75197228
OS 0.05226558 -38.75567052
OS 0.05226558 -38.76121788
OS 0.05319014 -38.7676898
OS 0.05503926 -38.77508628
OS 0.05781294 -38.79172836
OS 0.0633603 -38.81021956
OS 0.07075678 -38.83055988
OS 0.08092694 -38.84905108
OS 0.09387078 -38.86569316
OS 0.09479534 -38.86569316
OS 0.0957199 -38.86754228
OS 0.10126726 -38.87216508
OS 0.1095883 -38.878637
OS 0.12068302 -38.88510892
OS 0.13547598 -38.8925054
OS 0.15211806 -38.89897732
OS 0.17060926 -38.90360012
OS 0.18077942 -38.90452468
OS 0.19187414 -38.90544924
OS 0.19927062 -38.90544924
OS 0.20759166 -38.90452468
OS 0.21776182 -38.90267556
OS 0.22885654 -38.89990188
OS 0.24180038 -38.89620364
OS 0.25381966 -38.89065628
OS 0.26583894 -38.8832598
OS 0.2667635 -38.88233524
OS 0.2713863 -38.878637
OS 0.27693366 -38.87308964
OS 0.28340558 -38.86569316
OS 0.29080206 -38.855523
OS 0.2991231 -38.84257916
OS 0.30744414 -38.8277862
OS 0.31484062 -38.81021956
OS 0.3962019 -38.82038972
OS 0.3962019 -38.82131428
OS 0.39527734 -38.8231634
OS 0.39435278 -38.82686164
OS 0.39250366 -38.832409
OS 0.38972998 -38.83795636
OS 0.3869563 -38.84535284
OS 0.37955982 -38.86107036
OS 0.37031422 -38.878637
OS 0.35737038 -38.8971282
OS 0.34257742 -38.91469484
OS 0.32408622 -38.93133692
OS 0.32316166 -38.93133692
OS 0.32131254 -38.93318604
OS 0.31853886 -38.93503516
OS 0.31484062 -38.93780884
OS 0.30929326 -38.94058252
OS 0.3037459 -38.9433562
OS 0.29634942 -38.94705444
OS 0.28802838 -38.95075268
OS 0.27878278 -38.95445092
OS 0.26953718 -38.95814916
OS 0.24642318 -38.96369652
OS 0.2205355 -38.96831932
OS 0.19187414 -38.97016844
OS 0.18170398 -38.97016844
OS 0.17523206 -38.96924388
OS 0.16691102 -38.96831932
OS 0.15674086 -38.9664702
OS 0.14564614 -38.96462108
OS 0.13362686 -38.96277196
OS 0.10773918 -38.95537548
OS 0.09387078 -38.94982812
OS 0.08092694 -38.94428076
OS 0.06705854 -38.93688428
OS 0.0541147 -38.92856324
OS 0.04209542 -38.91931764
OS 0.03007614 -38.90822292
OS 0.02915158 -38.90729836
OS 0.02730246 -38.90544924
OS 0.02452878 -38.901751
OS 0.02083054 -38.89620364
OS 0.01620774 -38.88973172
OS 0.01158494 -38.88233524
OS 0.00603758 -38.87308964
OS 0.00049022 -38.86291948
OS -0.00505714 -38.8509002
OS -0.0106045 -38.83795636
OS -0.0152273 -38.8231634
OS -0.0198501 -38.80744588
OS -0.02354834 -38.7908038
OS -0.02632202 -38.7723126
OS -0.02817114 -38.75289684
OS -0.0290957 -38.73255652
OS -0.0290957 -38.73163196
OS -0.0290957 -38.72700916
OS -0.0290957 -38.7214618
OS -0.02817114 -38.71314076
OS -0.02724658 -38.7029706
OS -0.02632202 -38.69187588
OS -0.0244729 -38.67893204
OS -0.02169922 -38.6659882
OS -0.01430274 -38.63640228
OS -0.00967994 -38.62160932
OS -0.00413258 -38.6058918
OS 0.0032639 -38.59109884
OS 0.01158494 -38.57723044
OS 0.02083054 -38.56336204
OS 0.0310007 -38.5504182
OS 0.03192526 -38.54949364
OS 0.03377438 -38.54764452
OS 0.03747262 -38.54487084
OS 0.04209542 -38.54024804
OS 0.04764278 -38.53562524
OS 0.05503926 -38.53007788
OS 0.0633603 -38.52360596
OS 0.07353046 -38.5180586
OS 0.08370062 -38.51158668
OS 0.0957199 -38.50603932
OS 0.10866374 -38.50049196
OS 0.12253214 -38.49586916
OS 0.1373251 -38.49124636
OS 0.15304262 -38.48847268
OS 0.1696847 -38.48662356
OS 0.18725134 -38.485699
OS 0.19649694 -38.485699
OS 0.20296886 -38.48662356
OE
OB -1.0692257 -38.95999828 I
OS -1.1478133 -38.95999828
OS -1.1478133 -38.32020276
OS -1.0692257 -38.32020276
OS -1.0692257 -38.95999828
OE
OB -0.2463673 -38.96739476 I
OS -0.2463673 -38.96831932
OS -0.24729186 -38.971093
OS -0.24914098 -38.97479124
OS -0.2509901 -38.97941404
OS -0.25376378 -38.98588596
OS -0.25653746 -38.99328244
OS -0.26300938 -39.00899996
OS -0.2694813 -39.0265666
OS -0.27687778 -39.04413324
OS -0.28427426 -39.05985076
OS -0.2879725 -39.06632268
OS -0.29074618 -39.0727946
OS -0.29167074 -39.07464372
OS -0.29444442 -39.07926652
OS -0.29906722 -39.08573844
OS -0.30461458 -39.09405948
OS -0.31201106 -39.10330508
OS -0.3203321 -39.11255068
OS -0.32865314 -39.12179628
OS -0.3388233 -39.12919276
OS -0.33974786 -39.13011732
OS -0.3434461 -39.13196644
OS -0.34899346 -39.13474012
OS -0.3573145 -39.13843836
OS -0.3665601 -39.1421366
OS -0.37765482 -39.14491028
OS -0.3896741 -39.1467594
OS -0.4035425 -39.14768396
OS -0.40724074 -39.14768396
OS -0.41186354 -39.1467594
OS -0.41833546 -39.1467594
OS -0.42573194 -39.14491028
OS -0.43405298 -39.14306116
OS -0.44329858 -39.14121204
OS -0.45346874 -39.1375138
OS -0.46178978 -39.06447356
OS -0.46086522 -39.06447356
OS -0.45716698 -39.06539812
OS -0.45254418 -39.06632268
OS -0.44699682 -39.0681718
OS -0.43220386 -39.07094548
OS -0.4174109 -39.07187004
OS -0.4127881 -39.07187004
OS -0.4081653 -39.07094548
OS -0.40261794 -39.07094548
OS -0.38874954 -39.0681718
OS -0.38227762 -39.06539812
OS -0.3758057 -39.06262444
OS -0.37488114 -39.06262444
OS -0.37303202 -39.06077532
OS -0.37025834 -39.0589262
OS -0.3665601 -39.05615252
OS -0.35823906 -39.04875604
OS -0.35084258 -39.03858588
OS -0.35084258 -39.03766132
OS -0.34899346 -39.0358122
OS -0.34714434 -39.03211396
OS -0.34529522 -39.0265666
OS -0.34159698 -39.01917012
OS -0.33789874 -39.0080754
OS -0.33235138 -38.99513156
OS -0.32680402 -38.97941404
OS -0.32680402 -38.97848948
OS -0.3249549 -38.97479124
OS -0.32310578 -38.96831932
OS -0.31940754 -38.95999828
OS -0.49507394 -38.49586916
OS -0.41186354 -38.49586916
OS -0.31478474 -38.76491612
OS -0.31478474 -38.76584068
OS -0.31386018 -38.76676524
OS -0.31293562 -38.76953892
OS -0.31201106 -38.77416172
OS -0.31016194 -38.77878452
OS -0.30831282 -38.78433188
OS -0.30369002 -38.79727572
OS -0.29814266 -38.81299324
OS -0.2925953 -38.83148444
OS -0.28704794 -38.8509002
OS -0.28150058 -38.87216508
OS -0.28150058 -38.87124052
OS -0.28057602 -38.8693914
OS -0.27965146 -38.86661772
OS -0.2787269 -38.86291948
OS -0.27780234 -38.85829668
OS -0.27595322 -38.85274932
OS -0.27225498 -38.83888092
OS -0.26763218 -38.8231634
OS -0.26116026 -38.8046722
OS -0.2556129 -38.786181
OS -0.24821642 -38.76676524
OS -0.14836394 -38.49586916
OS -0.06977634 -38.49586916
OS -0.2463673 -38.96739476
OE
OB -5.4655085 -38.31835364 I
OS -5.45348922 -38.32020276
OS -5.43962082 -38.32297644
OS -5.42482786 -38.32667468
OS -5.40911034 -38.33129748
OS -5.39431738 -38.33869396
OS -5.39339282 -38.33869396
OS -5.39246826 -38.33961852
OS -5.38784546 -38.3423922
OS -5.38044898 -38.347015
OS -5.37120338 -38.35348692
OS -5.36103322 -38.36273252
OS -5.3499385 -38.37290268
OS -5.33976834 -38.38492196
OS -5.32959818 -38.39879036
OS -5.32867362 -38.40063948
OS -5.32497538 -38.40526228
OS -5.32127714 -38.41358332
OS -5.31480522 -38.4256026
OS -5.30925786 -38.439471
OS -5.30186138 -38.45518852
OS -5.29538946 -38.47367972
OS -5.2898421 -38.49402004
OS -5.2898421 -38.4949446
OS -5.28891754 -38.49679372
OS -5.28799298 -38.4995674
OS -5.28706842 -38.5041902
OS -5.28614386 -38.50973756
OS -5.2852193 -38.51620948
OS -5.28337018 -38.52453052
OS -5.28244562 -38.53377612
OS -5.2805965 -38.54394628
OS -5.27967194 -38.555041
OS -5.27874738 -38.56798484
OS -5.27689826 -38.58092868
OS -5.2759737 -38.59572164
OS -5.2759737 -38.6105146
OS -5.27504914 -38.62715668
OS -5.27504914 -38.64472332
OS -5.27504914 -38.64564788
OS -5.27504914 -38.64934612
OS -5.27504914 -38.65581804
OS -5.27504914 -38.66321452
OS -5.2759737 -38.67338468
OS -5.2759737 -38.6844794
OS -5.27689826 -38.69649868
OS -5.27782282 -38.70944252
OS -5.2805965 -38.73902844
OS -5.2852193 -38.76953892
OS -5.29076666 -38.79912484
OS -5.2944649 -38.81299324
OS -5.2990877 -38.82686164
OS -5.2990877 -38.8277862
OS -5.30001226 -38.82963532
OS -5.30186138 -38.83333356
OS -5.3037105 -38.83795636
OS -5.30555962 -38.84442828
OS -5.30925786 -38.8509002
OS -5.31665434 -38.86661772
OS -5.32589994 -38.8832598
OS -5.33791922 -38.901751
OS -5.35178762 -38.91839308
OS -5.3684297 -38.9341106
OS -5.36935426 -38.9341106
OS -5.37027882 -38.93595972
OS -5.3730525 -38.93780884
OS -5.37675074 -38.93965796
OS -5.38137354 -38.94243164
OS -5.38599634 -38.94612988
OS -5.39986474 -38.9526018
OS -5.41650682 -38.95907372
OS -5.43592258 -38.96554564
OS -5.45903658 -38.96924388
OS -5.4839997 -38.971093
OS -5.4932453 -38.971093
OS -5.49971722 -38.97016844
OS -5.5071137 -38.96924388
OS -5.5163593 -38.96739476
OS -5.52652946 -38.96554564
OS -5.53762418 -38.96277196
OS -5.5487189 -38.95907372
OS -5.56073818 -38.95537548
OS -5.57275746 -38.94982812
OS -5.58477674 -38.9433562
OS -5.59679602 -38.93595972
OS -5.6088153 -38.92671412
OS -5.61991002 -38.91654396
OS -5.63008018 -38.90544924
OS -5.63100474 -38.90452468
OS -5.63285386 -38.901751
OS -5.63562754 -38.8971282
OS -5.64025034 -38.88973172
OS -5.64487314 -38.88141068
OS -5.64949594 -38.87031596
OS -5.65596786 -38.85737212
OS -5.66151522 -38.84257916
OS -5.66706258 -38.82593708
OS -5.67260994 -38.80652132
OS -5.6781573 -38.78525644
OS -5.6827801 -38.76121788
OS -5.6874029 -38.7353302
OS -5.69017658 -38.7075934
OS -5.6920257 -38.67708292
OS -5.69295026 -38.64472332
OS -5.69295026 -38.64379876
OS -5.69295026 -38.64010052
OS -5.69295026 -38.6336286
OS -5.69295026 -38.62623212
OS -5.6920257 -38.61606196
OS -5.6920257 -38.60496724
OS -5.69110114 -38.59294796
OS -5.69017658 -38.57907956
OS -5.6874029 -38.5504182
OS -5.6827801 -38.51990772
OS -5.67723274 -38.48939724
OS -5.6735345 -38.47552884
OS -5.66983626 -38.46166044
OS -5.66983626 -38.46073588
OS -5.6689117 -38.45888676
OS -5.66706258 -38.45518852
OS -5.66521346 -38.45056572
OS -5.66336434 -38.4440938
OS -5.6596661 -38.43762188
OS -5.65226962 -38.42190436
OS -5.64302402 -38.40526228
OS -5.63100474 -38.38769564
OS -5.61713634 -38.370129
OS -5.60049426 -38.35533604
OS -5.5995697 -38.35533604
OS -5.59864514 -38.35348692
OS -5.59587146 -38.3516378
OS -5.59217322 -38.34978868
OS -5.58755042 -38.34609044
OS -5.58200306 -38.34331676
OS -5.56813466 -38.33592028
OS -5.55149258 -38.32944836
OS -5.53207682 -38.32297644
OS -5.50896282 -38.3192782
OS -5.4839997 -38.31742908
OS -5.47567866 -38.31742908
OS -5.4655085 -38.31835364
OE
OB -4.46421002 -38.7676898 I
OS -4.7073693 -38.7676898
OS -4.7073693 -38.6891022
OS -4.46421002 -38.6891022
OS -4.46421002 -38.7676898
OE
OB -4.86546906 -38.73440564 I
OS -4.77856042 -38.73440564
OS -4.77856042 -38.80652132
OS -4.86546906 -38.80652132
OS -4.86546906 -38.95999828
OS -4.94405666 -38.95999828
OS -4.94405666 -38.80652132
OS -5.22234922 -38.80652132
OS -5.22234922 -38.73440564
OS -4.9292637 -38.32020276
OS -4.86546906 -38.32020276
OS -4.86546906 -38.73440564
OE
OB -4.30148746 -38.54856908 I
OS -4.3005629 -38.54764452
OS -4.29963834 -38.5457954
OS -4.29686466 -38.54302172
OS -4.29224186 -38.53839892
OS -4.28761906 -38.53377612
OS -4.2820717 -38.52822876
OS -4.27467522 -38.5226814
OS -4.26727874 -38.51713404
OS -4.24878754 -38.50511476
OS -4.22752266 -38.49586916
OS -4.21550338 -38.49124636
OS -4.20255954 -38.48847268
OS -4.18869114 -38.48662356
OS -4.17482274 -38.485699
OS -4.16742626 -38.485699
OS -4.15910522 -38.48662356
OS -4.14893506 -38.48754812
OS -4.13691578 -38.4903218
OS -4.12304738 -38.49309548
OS -4.10825442 -38.49771828
OS -4.09438602 -38.50326564
OS -4.0925369 -38.5041902
OS -4.0879141 -38.50603932
OS -4.08051762 -38.51066212
OS -4.07219658 -38.51620948
OS -4.06202642 -38.5226814
OS -4.05185626 -38.53100244
OS -4.04076154 -38.5411726
OS -4.03151594 -38.55226732
OS -4.03059138 -38.55319188
OS -4.0278177 -38.55781468
OS -4.0231949 -38.5642866
OS -4.01764754 -38.57260764
OS -4.01117562 -38.58370236
OS -4.0047037 -38.5966462
OS -3.99823178 -38.61143916
OS -3.99268442 -38.62715668
OS -3.99268442 -38.62808124
OS -3.99175986 -38.6290058
OS -3.9908353 -38.63177948
OS -3.98991074 -38.63455316
OS -3.98806162 -38.64379876
OS -3.98528794 -38.65581804
OS -3.98251426 -38.66968644
OS -3.97974058 -38.68540396
OS -3.97881602 -38.7029706
OS -3.97789146 -38.7214618
OS -3.97789146 -38.72238636
OS -3.97789146 -38.72700916
OS -3.97789146 -38.73255652
OS -3.97881602 -38.74087756
OS -3.97974058 -38.75104772
OS -3.98066514 -38.76214244
OS -3.98251426 -38.77508628
OS -3.98528794 -38.78895468
OS -3.99268442 -38.8185406
OS -3.99730722 -38.83425812
OS -4.00285458 -38.84905108
OS -4.0093265 -38.8647686
OS -4.01764754 -38.878637
OS -4.02689314 -38.8925054
OS -4.0370633 -38.90544924
OS -4.03798786 -38.9063738
OS -4.03983698 -38.90822292
OS -4.04261066 -38.9109966
OS -4.04723346 -38.9156194
OS -4.05370538 -38.9202422
OS -4.0601773 -38.92578956
OS -4.06757378 -38.93133692
OS -4.07681938 -38.93780884
OS -4.08698954 -38.9433562
OS -4.0971597 -38.94982812
OS -4.12212282 -38.95999828
OS -4.13506666 -38.96462108
OS -4.14893506 -38.96739476
OS -4.16372802 -38.96924388
OS -4.17852098 -38.97016844
OS -4.18221922 -38.97016844
OS -4.18684202 -38.96924388
OS -4.19238938 -38.96924388
OS -4.1988613 -38.96831932
OS -4.20718234 -38.9664702
OS -4.22567354 -38.9618474
OS -4.2358437 -38.95814916
OS -4.24601386 -38.95352636
OS -4.25710858 -38.947979
OS -4.26727874 -38.94150708
OS -4.27837346 -38.93318604
OS -4.28854362 -38.92394044
OS -4.29778922 -38.91377028
OS -4.30703482 -38.901751
OS -4.30703482 -38.95999828
OS -4.38007506 -38.95999828
OS -4.38007506 -38.32020276
OS -4.30148746 -38.32020276
OS -4.30148746 -38.54856908
OE
OB -3.67740946 -38.48662356 I
OS -3.66908842 -38.48754812
OS -3.65984282 -38.48939724
OS -3.64967266 -38.49124636
OS -3.63765338 -38.49309548
OS -3.61269026 -38.50141652
OS -3.59974642 -38.50603932
OS -3.58680258 -38.51251124
OS -3.57385874 -38.51898316
OS -3.5609149 -38.52822876
OS -3.54889562 -38.53747436
OS -3.53687634 -38.54856908
OS -3.53595178 -38.54949364
OS -3.53410266 -38.55134276
OS -3.53132898 -38.555041
OS -3.52763074 -38.5596638
OS -3.52300794 -38.56613572
OS -3.51746058 -38.57445676
OS -3.51191322 -38.58370236
OS -3.50636586 -38.59387252
OS -3.5008185 -38.60496724
OS -3.49527114 -38.61883564
OS -3.48972378 -38.63270404
OS -3.48510098 -38.64842156
OS -3.48140274 -38.66506364
OS -3.47862906 -38.68263028
OS -3.47677994 -38.70112148
OS -3.47585538 -38.7214618
OS -3.47585538 -38.72238636
OS -3.47585538 -38.72516004
OS -3.47585538 -38.72978284
OS -3.47585538 -38.73625476
OS -3.47677994 -38.74365124
OS -3.4777045 -38.75289684
OS -3.4777045 -38.76214244
OS -3.47955362 -38.7723126
OS -3.4823273 -38.7954266
OS -3.48787466 -38.8185406
OS -3.49434658 -38.8416546
OS -3.50359218 -38.86291948
OS -3.50359218 -38.86384404
OS -3.50451674 -38.8647686
OS -3.50636586 -38.86754228
OS -3.50821498 -38.87124052
OS -3.5146869 -38.88048612
OS -3.52300794 -38.89158084
OS -3.53410266 -38.90452468
OS -3.54797106 -38.91746852
OS -3.56368858 -38.93041236
OS -3.58217978 -38.94243164
OS -3.58310434 -38.94243164
OS -3.5840289 -38.9433562
OS -3.58680258 -38.94520532
OS -3.59142538 -38.94705444
OS -3.59604818 -38.94890356
OS -3.60159554 -38.95075268
OS -3.61546394 -38.95630004
OS -3.63118146 -38.96092284
OS -3.65059722 -38.96554564
OS -3.67093754 -38.96924388
OS -3.69312698 -38.97016844
OS -3.70237258 -38.97016844
OS -3.70976906 -38.96924388
OS -3.7180901 -38.96831932
OS -3.7273357 -38.9664702
OS -3.73843042 -38.96462108
OS -3.74952514 -38.96277196
OS -3.77448826 -38.95537548
OS -3.78835666 -38.94982812
OS -3.8013005 -38.94428076
OS -3.81424434 -38.93688428
OS -3.82718818 -38.92856324
OS -3.83920746 -38.91931764
OS -3.85122674 -38.90822292
OS -3.8521513 -38.90729836
OS -3.85400042 -38.90544924
OS -3.8567741 -38.901751
OS -3.86047234 -38.89620364
OS -3.86509514 -38.88973172
OS -3.86971794 -38.88233524
OS -3.8752653 -38.87308964
OS -3.88081266 -38.86199492
OS -3.88636002 -38.84997564
OS -3.89190738 -38.83610724
OS -3.89653018 -38.82131428
OS -3.90115298 -38.80559676
OS -3.90485122 -38.78803012
OS -3.9076249 -38.76953892
OS -3.90947402 -38.7491986
OS -3.91039858 -38.72793372
OS -3.91039858 -38.7260846
OS -3.91039858 -38.72238636
OS -3.90947402 -38.71591444
OS -3.90947402 -38.70666884
OS -3.90854946 -38.69649868
OS -3.90670034 -38.68355484
OS -3.90485122 -38.670611
OS -3.90115298 -38.65581804
OS -3.89745474 -38.64102508
OS -3.89283194 -38.62530756
OS -3.88728458 -38.60866548
OS -3.8798881 -38.59294796
OS -3.87249162 -38.578155
OS -3.86232146 -38.56336204
OS -3.8521513 -38.54949364
OS -3.83920746 -38.53747436
OS -3.8382829 -38.5365498
OS -3.83643378 -38.53562524
OS -3.83273554 -38.53285156
OS -3.82811274 -38.52915332
OS -3.82256538 -38.52545508
OS -3.8151689 -38.52083228
OS -3.80777242 -38.51620948
OS -3.79852682 -38.51158668
OS -3.78835666 -38.50696388
OS -3.77726194 -38.50234108
OS -3.75229882 -38.49402004
OS -3.72363746 -38.48754812
OS -3.7088445 -38.48662356
OS -3.69312698 -38.485699
OS -3.68388138 -38.485699
OS -3.67740946 -38.48662356
OE
OB -5.79280274 -38.95999828 I
OS -5.87139034 -38.95999828
OS -5.87139034 -38.32020276
OS -5.79280274 -38.32020276
OS -5.79280274 -38.95999828
OE
OB -5.97031826 -38.42745172 I
OS -5.99158314 -38.54671996
OS -6.04058482 -38.54671996
OS -6.06000058 -38.42745172
OS -6.06000058 -38.32020276
OS -5.97031826 -38.32020276
OS -5.97031826 -38.42745172
OE
OB -5.48492426 -38.38214828 H
OS -5.49047162 -38.38214828
OS -5.49416986 -38.38307284
OS -5.50434002 -38.38492196
OS -5.5163593 -38.38769564
OS -5.5302277 -38.393243
OS -5.54502066 -38.40156404
OS -5.55241714 -38.4071114
OS -5.55981362 -38.41265876
OS -5.56628554 -38.42005524
OS -5.57275746 -38.42837628
OS -5.57275746 -38.42930084
OS -5.57460658 -38.43114996
OS -5.5764557 -38.4348482
OS -5.57922938 -38.439471
OS -5.58200306 -38.44686748
OS -5.5857013 -38.45518852
OS -5.58847498 -38.46535868
OS -5.59217322 -38.47737796
OS -5.59587146 -38.49124636
OS -5.5995697 -38.50696388
OS -5.60326794 -38.52453052
OS -5.60604162 -38.54394628
OS -5.6088153 -38.56613572
OS -5.61066442 -38.59017428
OS -5.61158898 -38.61606196
OS -5.61251354 -38.64472332
OS -5.61251354 -38.64657244
OS -5.61251354 -38.65119524
OS -5.61251354 -38.65951628
OS -5.61158898 -38.670611
OS -5.61158898 -38.68263028
OS -5.61066442 -38.69742324
OS -5.60973986 -38.71314076
OS -5.60789074 -38.72978284
OS -5.60326794 -38.76584068
OS -5.60049426 -38.78340732
OS -5.59679602 -38.8000494
OS -5.59309778 -38.81576692
OS -5.58755042 -38.83055988
OS -5.58200306 -38.84350372
OS -5.57553114 -38.85459844
OS -5.57553114 -38.855523
OS -5.57368202 -38.85644756
OS -5.56905922 -38.86291948
OS -5.56073818 -38.87124052
OS -5.55056802 -38.88048612
OS -5.53669962 -38.88973172
OS -5.5209821 -38.89805276
OS -5.50341546 -38.90452468
OS -5.49416986 -38.90544924
OS -5.4839997 -38.9063738
OS -5.47845234 -38.9063738
OS -5.4747541 -38.90544924
OS -5.4655085 -38.90360012
OS -5.45256466 -38.89990188
OS -5.43869626 -38.89342996
OS -5.42297874 -38.88418436
OS -5.41558226 -38.878637
OS -5.40818578 -38.87124052
OS -5.4007893 -38.86384404
OS -5.39339282 -38.85459844
OS -5.39339282 -38.85367388
OS -5.3915437 -38.85182476
OS -5.38969458 -38.84905108
OS -5.38784546 -38.84442828
OS -5.38414722 -38.83795636
OS -5.38137354 -38.82963532
OS -5.3776753 -38.82038972
OS -5.37397706 -38.809295
OS -5.37120338 -38.7954266
OS -5.36750514 -38.78063364
OS -5.3638069 -38.763067
OS -5.36103322 -38.7445758
OS -5.3591841 -38.72238636
OS -5.35733498 -38.69927236
OS -5.35548586 -38.67338468
OS -5.35548586 -38.64472332
OS -5.35548586 -38.64379876
OS -5.35548586 -38.6428742
OS -5.35548586 -38.6382514
OS -5.35548586 -38.62993036
OS -5.35641042 -38.61883564
OS -5.35641042 -38.60681636
OS -5.35733498 -38.5920234
OS -5.35825954 -38.57630588
OS -5.36010866 -38.55873924
OS -5.36473146 -38.52360596
OS -5.36750514 -38.50603932
OS -5.37120338 -38.48939724
OS -5.37490162 -38.47367972
OS -5.38044898 -38.45888676
OS -5.38599634 -38.44594292
OS -5.39246826 -38.4348482
OS -5.39246826 -38.43392364
OS -5.39431738 -38.43299908
OS -5.3961665 -38.4302254
OS -5.39894018 -38.42652716
OS -5.40726122 -38.41820612
OS -5.41743138 -38.40803596
OS -5.43129978 -38.39879036
OS -5.4470173 -38.39046932
OS -5.45533834 -38.38677108
OS -5.46458394 -38.3839974
OS -5.4747541 -38.38307284
OS -5.48492426 -38.38214828
OE
OB 0.1881759 -38.5504182 H
OS 0.18262854 -38.5504182
OS 0.1789303 -38.55134276
OS 0.16876014 -38.55226732
OS 0.15674086 -38.555041
OS 0.1419479 -38.5596638
OS 0.12623038 -38.56613572
OS 0.11143742 -38.57538132
OS 0.09664446 -38.5874006
OS 0.09479534 -38.58924972
OS 0.0910971 -38.59387252
OS 0.08462518 -38.60219356
OS 0.07815326 -38.61328828
OS 0.07075678 -38.62623212
OS 0.06428486 -38.6428742
OS 0.0587375 -38.66228996
OS 0.05596382 -38.68355484
OS 0.31576518 -38.68355484
OS 0.31576518 -38.68263028
OS 0.31576518 -38.68078116
OS 0.31484062 -38.67800748
OS 0.31484062 -38.67430924
OS 0.3129915 -38.66321452
OS 0.31021782 -38.65119524
OS 0.30559502 -38.63640228
OS 0.30097222 -38.62253388
OS 0.29357574 -38.60866548
OS 0.2852547 -38.5966462
OS 0.2852547 -38.59572164
OS 0.28340558 -38.59479708
OS 0.27878278 -38.58924972
OS 0.27046174 -38.58185324
OS 0.25936702 -38.5735322
OS 0.24549862 -38.56521116
OS 0.22885654 -38.55781468
OS 0.20944078 -38.55226732
OS 0.19927062 -38.55134276
OS 0.1881759 -38.5504182
OE
OB -2.69830042 -38.5504182 H
OS -2.70384778 -38.5504182
OS -2.70847058 -38.55134276
OS -2.71864074 -38.55226732
OS -2.73250914 -38.55596556
OS -2.74822666 -38.56151292
OS -2.76486874 -38.5689094
OS -2.78058626 -38.58000412
OS -2.7889073 -38.5874006
OS -2.79630378 -38.59479708
OS -2.79630378 -38.59572164
OS -2.7981529 -38.5966462
OS -2.80000202 -38.59941988
OS -2.8027757 -38.60311812
OS -2.80554938 -38.60774092
OS -2.80832306 -38.61328828
OS -2.8120213 -38.62068476
OS -2.81571954 -38.62808124
OS -2.81941778 -38.63732684
OS -2.82311602 -38.64657244
OS -2.8258897 -38.65766716
OS -2.82866338 -38.66968644
OS -2.83143706 -38.68263028
OS -2.83328618 -38.69649868
OS -2.83421074 -38.7122162
OS -2.8351353 -38.72793372
OS -2.8351353 -38.72885828
OS -2.8351353 -38.73163196
OS -2.8351353 -38.73625476
OS -2.83421074 -38.74272668
OS -2.83421074 -38.75012316
OS -2.83328618 -38.7584442
OS -2.8305125 -38.77785996
OS -2.8258897 -38.8000494
OS -2.81849322 -38.82223884
OS -2.80924762 -38.84350372
OS -2.8027757 -38.85274932
OS -2.79630378 -38.86199492
OS -2.79537922 -38.86199492
OS -2.79445466 -38.86384404
OS -2.7889073 -38.86846684
OS -2.78058626 -38.87586332
OS -2.76949154 -38.8832598
OS -2.75562314 -38.89158084
OS -2.73898106 -38.89897732
OS -2.7195653 -38.90360012
OS -2.70939514 -38.90452468
OS -2.69830042 -38.90544924
OS -2.69275306 -38.90544924
OS -2.68813026 -38.90452468
OS -2.6779601 -38.90267556
OS -2.6640917 -38.89990188
OS -2.64929874 -38.89435452
OS -2.63265666 -38.88695804
OS -2.61693914 -38.87586332
OS -2.6086181 -38.86846684
OS -2.60122162 -38.86107036
OS -2.60029706 -38.8601458
OS -2.5993725 -38.85922124
OS -2.59752338 -38.85644756
OS -2.5947497 -38.85274932
OS -2.59197602 -38.84812652
OS -2.58827778 -38.84257916
OS -2.58457954 -38.83518268
OS -2.5808813 -38.8277862
OS -2.57718306 -38.8185406
OS -2.57440938 -38.80837044
OS -2.57071114 -38.79727572
OS -2.56793746 -38.78525644
OS -2.56516378 -38.77138804
OS -2.56331466 -38.75751964
OS -2.56146554 -38.74180212
OS -2.56146554 -38.72516004
OS -2.56146554 -38.72423548
OS -2.56146554 -38.7214618
OS -2.56146554 -38.716839
OS -2.5623901 -38.71129164
OS -2.5623901 -38.70389516
OS -2.56331466 -38.69557412
OS -2.56608834 -38.67615836
OS -2.57071114 -38.65581804
OS -2.57810762 -38.6336286
OS -2.58827778 -38.61328828
OS -2.59382514 -38.60311812
OS -2.60122162 -38.59479708
OS -2.60122162 -38.59387252
OS -2.60307074 -38.59294796
OS -2.6086181 -38.5874006
OS -2.61693914 -38.58092868
OS -2.62803386 -38.57260764
OS -2.64190226 -38.5642866
OS -2.65854434 -38.55689012
OS -2.67703554 -38.55226732
OS -2.6872057 -38.55134276
OS -2.69830042 -38.5504182
OE
OB -3.69312698 -38.5504182 H
OS -3.69867434 -38.5504182
OS -3.70329714 -38.55134276
OS -3.7134673 -38.55226732
OS -3.7273357 -38.55596556
OS -3.74305322 -38.56151292
OS -3.7596953 -38.5689094
OS -3.77541282 -38.58000412
OS -3.78373386 -38.5874006
OS -3.79113034 -38.59479708
OS -3.79113034 -38.59572164
OS -3.79297946 -38.5966462
OS -3.79482858 -38.59941988
OS -3.79760226 -38.60311812
OS -3.80037594 -38.60774092
OS -3.80314962 -38.61328828
OS -3.80684786 -38.62068476
OS -3.8105461 -38.62808124
OS -3.81424434 -38.63732684
OS -3.81794258 -38.64657244
OS -3.82071626 -38.65766716
OS -3.82348994 -38.66968644
OS -3.82626362 -38.68263028
OS -3.82811274 -38.69649868
OS -3.8290373 -38.7122162
OS -3.82996186 -38.72793372
OS -3.82996186 -38.72885828
OS -3.82996186 -38.73163196
OS -3.82996186 -38.73625476
OS -3.8290373 -38.74272668
OS -3.8290373 -38.75012316
OS -3.82811274 -38.7584442
OS -3.82533906 -38.77785996
OS -3.82071626 -38.8000494
OS -3.81331978 -38.82223884
OS -3.80407418 -38.84350372
OS -3.79760226 -38.85274932
OS -3.79113034 -38.86199492
OS -3.79020578 -38.86199492
OS -3.78928122 -38.86384404
OS -3.78373386 -38.86846684
OS -3.77541282 -38.87586332
OS -3.7643181 -38.8832598
OS -3.7504497 -38.89158084
OS -3.73380762 -38.89897732
OS -3.71439186 -38.90360012
OS -3.7042217 -38.90452468
OS -3.69312698 -38.90544924
OS -3.68757962 -38.90544924
OS -3.68295682 -38.90452468
OS -3.67278666 -38.90267556
OS -3.65891826 -38.89990188
OS -3.6441253 -38.89435452
OS -3.62748322 -38.88695804
OS -3.6117657 -38.87586332
OS -3.60344466 -38.86846684
OS -3.59604818 -38.86107036
OS -3.59512362 -38.8601458
OS -3.59419906 -38.85922124
OS -3.59234994 -38.85644756
OS -3.58957626 -38.85274932
OS -3.58680258 -38.84812652
OS -3.58310434 -38.84257916
OS -3.5794061 -38.83518268
OS -3.57570786 -38.8277862
OS -3.57200962 -38.8185406
OS -3.56923594 -38.80837044
OS -3.5655377 -38.79727572
OS -3.56276402 -38.78525644
OS -3.55999034 -38.77138804
OS -3.55814122 -38.75751964
OS -3.5562921 -38.74180212
OS -3.5562921 -38.72516004
OS -3.5562921 -38.72423548
OS -3.5562921 -38.7214618
OS -3.5562921 -38.716839
OS -3.55721666 -38.71129164
OS -3.55721666 -38.70389516
OS -3.55814122 -38.69557412
OS -3.5609149 -38.67615836
OS -3.5655377 -38.65581804
OS -3.57293418 -38.6336286
OS -3.58310434 -38.61328828
OS -3.5886517 -38.60311812
OS -3.59604818 -38.59479708
OS -3.59604818 -38.59387252
OS -3.5978973 -38.59294796
OS -3.60344466 -38.5874006
OS -3.6117657 -38.58092868
OS -3.62286042 -38.57260764
OS -3.63672882 -38.5642866
OS -3.6533709 -38.55689012
OS -3.6718621 -38.55226732
OS -3.68203226 -38.55134276
OS -3.69312698 -38.5504182
OE
OB -4.17297362 -38.5504182 H
OS -4.18684202 -38.5504182
OS -4.19054026 -38.55134276
OS -4.20071042 -38.55319188
OS -4.2127297 -38.55596556
OS -4.2265981 -38.56151292
OS -4.24139106 -38.56983396
OS -4.24878754 -38.57445676
OS -4.25618402 -38.58092868
OS -4.2635805 -38.5874006
OS -4.27097698 -38.59572164
OS -4.27097698 -38.5966462
OS -4.2728261 -38.59757076
OS -4.27467522 -38.60034444
OS -4.27652434 -38.60404268
OS -4.27929802 -38.60866548
OS -4.28299626 -38.61421284
OS -4.28576994 -38.62068476
OS -4.28946818 -38.62808124
OS -4.29316642 -38.63732684
OS -4.2959401 -38.64657244
OS -4.29963834 -38.65766716
OS -4.30241202 -38.66876188
OS -4.30426114 -38.68170572
OS -4.30611026 -38.69557412
OS -4.30795938 -38.70944252
OS -4.30795938 -38.72516004
OS -4.30795938 -38.7260846
OS -4.30795938 -38.72885828
OS -4.30795938 -38.73348108
OS -4.30795938 -38.73902844
OS -4.30703482 -38.74550036
OS -4.30703482 -38.7538214
OS -4.3051857 -38.77138804
OS -4.30241202 -38.7908038
OS -4.29871378 -38.81114412
OS -4.29316642 -38.82963532
OS -4.28946818 -38.83795636
OS -4.28576994 -38.84535284
OS -4.28576994 -38.8462774
OS -4.28392082 -38.84812652
OS -4.2820717 -38.8509002
OS -4.27929802 -38.85459844
OS -4.27097698 -38.8647686
OS -4.2589577 -38.87493876
OS -4.2450893 -38.88603348
OS -4.22752266 -38.89620364
OS -4.21827706 -38.89990188
OS -4.20718234 -38.90267556
OS -4.19701218 -38.90452468
OS -4.1849929 -38.90544924
OS -4.1803701 -38.90544924
OS -4.17667186 -38.90452468
OS -4.1665017 -38.90267556
OS -4.15448242 -38.89990188
OS -4.14061402 -38.89435452
OS -4.12582106 -38.88695804
OS -4.1110281 -38.87586332
OS -4.10363162 -38.86846684
OS -4.09623514 -38.86107036
OS -4.09623514 -38.8601458
OS -4.09438602 -38.85922124
OS -4.0925369 -38.85644756
OS -4.09068778 -38.85274932
OS -4.08698954 -38.84812652
OS -4.08421586 -38.84257916
OS -4.08051762 -38.83518268
OS -4.07681938 -38.8277862
OS -4.0740457 -38.8185406
OS -4.07034746 -38.809295
OS -4.06664922 -38.79820028
OS -4.06387554 -38.786181
OS -4.06202642 -38.77323716
OS -4.0601773 -38.75936876
OS -4.05832818 -38.74365124
OS -4.05832818 -38.72793372
OS -4.05832818 -38.72700916
OS -4.05832818 -38.72423548
OS -4.05832818 -38.71961268
OS -4.05925274 -38.71314076
OS -4.05925274 -38.70574428
OS -4.0601773 -38.69649868
OS -4.06295098 -38.67708292
OS -4.06664922 -38.65581804
OS -4.07312114 -38.63270404
OS -4.08236674 -38.61236372
OS -4.0879141 -38.60219356
OS -4.09438602 -38.59387252
OS -4.09438602 -38.59294796
OS -4.09623514 -38.5920234
OS -4.10085794 -38.5874006
OS -4.10825442 -38.58000412
OS -4.11842458 -38.57168308
OS -4.13136842 -38.5642866
OS -4.14616138 -38.55689012
OS -4.16372802 -38.55226732
OS -4.17297362 -38.5504182
OE
OB -4.94405666 -38.44779204 H
OS -5.14561074 -38.73440564
OS -4.94405666 -38.73440564
OS -4.94405666 -38.44779204
OE
OB -0.65040002 -38.72700916 H
OS -0.65132458 -38.72700916
OS -0.65224914 -38.72793372
OS -0.65502282 -38.72885828
OS -0.65872106 -38.72978284
OS -0.66334386 -38.73163196
OS -0.66889122 -38.73348108
OS -0.67536314 -38.7353302
OS -0.68275962 -38.73717932
OS -0.69108066 -38.739953
OS -0.70125082 -38.74180212
OS -0.71142098 -38.7445758
OS -0.72344026 -38.74734948
OS -0.7363841 -38.75012316
OS -0.74932794 -38.75289684
OS -0.7641209 -38.75474596
OS -0.77983842 -38.75751964
OS -0.78168754 -38.75751964
OS -0.7872349 -38.7584442
OS -0.7964805 -38.76029332
OS -0.80665066 -38.76214244
OS -0.81774538 -38.76399156
OS -0.8288401 -38.76676524
OS -0.83901026 -38.76953892
OS -0.84825586 -38.77323716
OS -0.84918042 -38.77323716
OS -0.8519541 -38.77508628
OS -0.85565234 -38.7769354
OS -0.85935058 -38.77970908
OS -0.8704453 -38.78710556
OS -0.8796909 -38.79820028
OS -0.8796909 -38.79912484
OS -0.88154002 -38.80097396
OS -0.88246458 -38.8046722
OS -0.8843137 -38.809295
OS -0.88616282 -38.81484236
OS -0.88801194 -38.82038972
OS -0.8889365 -38.8277862
OS -0.88986106 -38.83518268
OS -0.88986106 -38.83610724
OS -0.88986106 -38.84073004
OS -0.8889365 -38.8462774
OS -0.88708738 -38.85367388
OS -0.8843137 -38.86199492
OS -0.8796909 -38.87031596
OS -0.87414354 -38.87956156
OS -0.86674706 -38.8878826
OS -0.8658225 -38.88880716
OS -0.86212426 -38.89065628
OS -0.8565769 -38.89435452
OS -0.84918042 -38.89805276
OS -0.83901026 -38.901751
OS -0.82699098 -38.90544924
OS -0.81312258 -38.90729836
OS -0.7964805 -38.90822292
OS -0.78908402 -38.90822292
OS -0.77983842 -38.90729836
OS -0.76966826 -38.90544924
OS -0.75672442 -38.90360012
OS -0.74378058 -38.89990188
OS -0.72991218 -38.89527908
OS -0.71604378 -38.88880716
OS -0.71419466 -38.8878826
OS -0.71049642 -38.88510892
OS -0.7040245 -38.88048612
OS -0.69662802 -38.8740142
OS -0.68830698 -38.86661772
OS -0.67906138 -38.85737212
OS -0.6716649 -38.8462774
OS -0.66426842 -38.83425812
OS -0.66334386 -38.83333356
OS -0.6624193 -38.82963532
OS -0.66057018 -38.8231634
OS -0.6577965 -38.81484236
OS -0.65502282 -38.80374764
OS -0.6531737 -38.7908038
OS -0.65224914 -38.77508628
OS -0.65132458 -38.75659508
OS -0.65040002 -38.72700916
OE
SE
S P 0
OB -4.66714078 -36.5016923 I
OS -4.65465922 -36.5016923
OS -4.62553558 -36.50307914
OS -4.5950251 -36.50723966
OS -4.56174094 -36.51140018
OS -4.53123046 -36.51833438
OS -4.51597522 -36.5224949
OS -4.50349366 -36.52665542
OS -4.50210682 -36.52665542
OS -4.50071998 -36.52804226
OS -4.49239894 -36.53220278
OS -4.47991738 -36.53775014
OS -4.46466214 -36.54745802
OS -4.44802006 -36.55993958
OS -4.42999114 -36.57658166
OS -4.41334906 -36.59599742
OS -4.39670698 -36.61818686
OS -4.39670698 -36.6195737
OS -4.39532014 -36.62096054
OS -4.38977278 -36.62928158
OS -4.38422542 -36.64314998
OS -4.37590438 -36.6611789
OS -4.36897018 -36.6819815
OS -4.36203598 -36.70694462
OS -4.35787546 -36.73329458
OS -4.35648862 -36.76241822
OS -4.35648862 -36.76380506
OS -4.35648862 -36.76657874
OS -4.35648862 -36.7721261
OS -4.35787546 -36.7790603
OS -4.35787546 -36.78876818
OS -4.3592623 -36.79847606
OS -4.36480966 -36.82205234
OS -4.3731307 -36.84978914
OS -4.38422542 -36.87891278
OS -4.4008675 -36.90803642
OS -4.41196222 -36.92190482
OS -4.42305694 -36.93577322
OS -4.42444378 -36.93716006
OS -4.42583062 -36.9385469
OS -4.42999114 -36.94270742
OS -4.4355385 -36.94686794
OS -4.4424727 -36.9524153
OS -4.45079374 -36.95796266
OS -4.46188846 -36.96489686
OS -4.47298318 -36.9732179
OS -4.48685158 -36.9801521
OS -4.50210682 -36.9870863
OS -4.5187489 -36.99540734
OS -4.53677782 -37.00234154
OS -4.55758042 -37.0078889
OS -4.57838302 -37.0148231
OS -4.6019593 -37.01898362
OS -4.62692242 -37.02314414
OS -4.62414874 -37.02453098
OS -4.61860138 -37.02730466
OS -4.61028034 -37.03285202
OS -4.59918562 -37.03839938
OS -4.5742225 -37.05365462
OS -4.56174094 -37.0633625
OS -4.55064622 -37.07168354
OS -4.54787254 -37.07445722
OS -4.54093834 -37.08139142
OS -4.52984362 -37.09248614
OS -4.51597522 -37.10635454
OS -4.50071998 -37.1257703
OS -4.48269106 -37.1465729
OS -4.46466214 -37.17153602
OS -4.44524638 -37.19927282
OS -4.28021242 -37.45999874
OS -4.43831218 -37.45999874
OS -4.56451462 -37.26029378
OS -4.56451462 -37.25890694
OS -4.5672883 -37.25613326
OS -4.57006198 -37.25197274
OS -4.5742225 -37.24642538
OS -4.58393038 -37.23117014
OS -4.59641194 -37.21175438
OS -4.61166718 -37.19095178
OS -4.62692242 -37.16876234
OS -4.64217766 -37.14795974
OS -4.65604606 -37.12854398
OS -4.6574329 -37.12715714
OS -4.66159342 -37.12160978
OS -4.66852762 -37.11328874
OS -4.6782355 -37.10358086
OS -4.6990381 -37.08277826
OS -4.71013282 -37.07307038
OS -4.72122754 -37.06474934
OS -4.72261438 -37.0633625
OS -4.72538806 -37.06197566
OS -4.73093542 -37.05920198
OS -4.73925646 -37.05504146
OS -4.7475775 -37.05088094
OS -4.75728538 -37.04672042
OS -4.77947482 -37.03978622
OS -4.78086166 -37.03978622
OS -4.78363534 -37.03839938
OS -4.7891827 -37.03839938
OS -4.7961169 -37.03701254
OS -4.80582478 -37.0356257
OS -4.8169195 -37.0356257
OS -4.83217474 -37.03423886
OS -4.99582186 -37.03423886
OS -4.99582186 -37.45999874
OS -5.12341114 -37.45999874
OS -5.12341114 -36.50030546
OS -4.6782355 -36.50030546
OS -4.66714078 -36.5016923
OE
OB -1.0100437 -37.45999874 I
OS -1.13208562 -37.45999874
OS -1.13208562 -36.65701838
OS -1.4122273 -37.45999874
OS -1.52594818 -37.45999874
OS -1.80331618 -36.64314998
OS -1.80331618 -37.45999874
OS -1.9253581 -37.45999874
OS -1.9253581 -36.50030546
OS -1.73536102 -36.50030546
OS -1.50791926 -37.1812439
OS -1.50791926 -37.18263074
OS -1.50653242 -37.18540442
OS -1.50514558 -37.18956494
OS -1.5023719 -37.19649914
OS -1.49682454 -37.21314122
OS -1.48989034 -37.23394382
OS -1.48295614 -37.2575201
OS -1.4746351 -37.28109638
OS -1.4677009 -37.30328582
OS -1.46215354 -37.32270158
OS -1.4607667 -37.3199279
OS -1.45937986 -37.3129937
OS -1.45521934 -37.30051214
OS -1.44967198 -37.28387006
OS -1.44273778 -37.26168062
OS -1.4330299 -37.23533066
OS -1.42332202 -37.20482018
OS -1.41084046 -37.16876234
OS -1.18062502 -36.50030546
OS -1.0100437 -36.50030546
OS -1.0100437 -37.45999874
OE
OB -2.02382374 -37.45999874 I
OS -2.1680551 -37.45999874
OS -2.28038914 -37.16876234
OS -2.68257274 -37.16876234
OS -2.78658574 -37.45999874
OS -2.92110922 -37.45999874
OS -2.55498346 -36.50030546
OS -2.41629946 -36.50030546
OS -2.02382374 -37.45999874
OE
OB -3.02928274 -37.45999874 I
OS -3.16103254 -37.45999874
OS -3.66306862 -36.70694462
OS -3.66306862 -37.45999874
OS -3.78511054 -37.45999874
OS -3.78511054 -36.50030546
OS -3.65474758 -36.50030546
OS -3.15132466 -37.25474642
OS -3.15132466 -36.50030546
OS -3.02928274 -36.50030546
OS -3.02928274 -37.45999874
OE
OB -5.3231161 -36.61402634 I
OS -5.89033366 -36.61402634
OS -5.89033366 -36.90664958
OS -5.35917394 -36.90664958
OS -5.35917394 -37.02037046
OS -5.89033366 -37.02037046
OS -5.89033366 -37.34627786
OS -5.30092666 -37.34627786
OS -5.30092666 -37.45999874
OS -6.01792294 -37.45999874
OS -6.01792294 -36.50030546
OS -5.3231161 -36.50030546
OS -5.3231161 -36.61402634
OE
OB -0.10721086 -36.61402634 I
OS -0.67442842 -36.61402634
OS -0.67442842 -36.90664958
OS -0.1432687 -36.90664958
OS -0.1432687 -37.02037046
OS -0.67442842 -37.02037046
OS -0.67442842 -37.34627786
OS -0.08502142 -37.34627786
OS -0.08502142 -37.45999874
OS -0.8020177 -37.45999874
OS -0.8020177 -36.50030546
OS -0.10721086 -36.50030546
OS -0.10721086 -36.61402634
OE
OB -8.43241138 -37.34627786 I
OS -7.95949894 -37.34627786
OS -7.95949894 -37.45999874
OS -8.56000066 -37.45999874
OS -8.56000066 -36.50030546
OS -8.43241138 -36.50030546
OS -8.43241138 -37.34627786
OE
OB -6.51718534 -37.05365462 I
OS -6.51718534 -37.45999874
OS -6.64477462 -37.45999874
OS -6.64477462 -37.05365462
OS -7.0150609 -36.50030546
OS -6.86112166 -36.50030546
OS -6.67251142 -36.79154186
OS -6.67251142 -36.7929287
OS -6.66973774 -36.79570238
OS -6.66696406 -36.7998629
OS -6.66419038 -36.80541026
OS -6.65864302 -36.81234446
OS -6.65309566 -36.8206655
OS -6.6406141 -36.8414681
OS -6.62535886 -36.86643122
OS -6.60871678 -36.89416802
OS -6.59068786 -36.92329166
OS -6.57404578 -36.95380214
OS -6.57404578 -36.9524153
OS -6.57265894 -36.94964162
OS -6.56988526 -36.9454811
OS -6.56572474 -36.93993374
OS -6.56156422 -36.93299954
OS -6.55601686 -36.9246785
OS -6.5435353 -36.9038759
OS -6.52828006 -36.87891278
OS -6.51025114 -36.84978914
OS -6.48944854 -36.81789182
OS -6.4672591 -36.78322082
OS -6.28280938 -36.50030546
OS -6.1344175 -36.50030546
OS -6.51718534 -37.05365462
OE
OB -7.01644774 -37.45999874 I
OS -7.1606791 -37.45999874
OS -7.27301314 -37.16876234
OS -7.67519674 -37.16876234
OS -7.77920974 -37.45999874
OS -7.91373322 -37.45999874
OS -7.54760746 -36.50030546
OS -7.40892346 -36.50030546
OS -7.01644774 -37.45999874
OE
OB -7.48103914 -36.60015794 H
OS -7.48103914 -36.60154478
OS -7.48242598 -36.60431846
OS -7.48242598 -36.60986582
OS -7.48519966 -36.61541318
OS -7.4865865 -36.62512106
OS -7.48936018 -36.63482894
OS -7.49490754 -36.65840522
OS -7.50184174 -36.68614202
OS -7.51154962 -36.7166525
OS -7.5212575 -36.74993666
OS -7.53373906 -36.78460766
OS -7.63775206 -37.06474934
OS -7.3132315 -37.06474934
OS -7.41308398 -36.80124974
OS -7.41308398 -36.7998629
OS -7.41447082 -36.79570238
OS -7.4172445 -36.78876818
OS -7.42001818 -36.78044714
OS -7.4241787 -36.77073926
OS -7.42833922 -36.7582577
OS -7.43249974 -36.7443893
OS -7.4380471 -36.7305209
OS -7.44914182 -36.69862358
OS -7.46023654 -36.66533942
OS -7.47133126 -36.63205526
OS -7.48103914 -36.60015794
OE
OB -4.69349074 -36.60709214 H
OS -4.99582186 -36.60709214
OS -4.99582186 -36.9246785
OS -4.71013282 -36.9246785
OS -4.69349074 -36.92329166
OS -4.67407498 -36.92190482
OS -4.65188554 -36.92051798
OS -4.6296961 -36.9177443
OS -4.60750666 -36.91358378
OS -4.5880909 -36.90803642
OS -4.58531722 -36.90664958
OS -4.57976986 -36.9038759
OS -4.57144882 -36.89971538
OS -4.5603541 -36.89416802
OS -4.54787254 -36.88584698
OS -4.53539098 -36.8761391
OS -4.52290942 -36.86365754
OS -4.51320154 -36.84978914
OS -4.5118147 -36.8484023
OS -4.50904102 -36.84285494
OS -4.5048805 -36.8345339
OS -4.49933314 -36.82343918
OS -4.49517262 -36.81095762
OS -4.4910121 -36.79708922
OS -4.48823842 -36.78044714
OS -4.48685158 -36.76380506
OS -4.48685158 -36.76241822
OS -4.48685158 -36.76103138
OS -4.48823842 -36.75271034
OS -4.48962526 -36.74022878
OS -4.49239894 -36.7235867
OS -4.49933314 -36.70694462
OS -4.50765418 -36.68752886
OS -4.52013574 -36.66949994
OS -4.53677782 -36.65147102
OS -4.5395515 -36.65008418
OS -4.5464857 -36.64453682
OS -4.55758042 -36.63760262
OS -4.57560934 -36.62928158
OS -4.59641194 -36.62096054
OS -4.62414874 -36.61402634
OS -4.65604606 -36.60847898
OS -4.69349074 -36.60709214
OE
OB -2.48841514 -36.60015794 H
OS -2.48841514 -36.60154478
OS -2.48980198 -36.60431846
OS -2.48980198 -36.60986582
OS -2.49257566 -36.61541318
OS -2.4939625 -36.62512106
OS -2.49673618 -36.63482894
OS -2.50228354 -36.65840522
OS -2.50921774 -36.68614202
OS -2.51892562 -36.7166525
OS -2.5286335 -36.74993666
OS -2.54111506 -36.78460766
OS -2.64512806 -37.06474934
OS -2.3206075 -37.06474934
OS -2.42045998 -36.80124974
OS -2.42045998 -36.7998629
OS -2.42184682 -36.79570238
OS -2.4246205 -36.78876818
OS -2.42739418 -36.78044714
OS -2.4315547 -36.77073926
OS -2.43571522 -36.7582577
OS -2.43987574 -36.7443893
OS -2.4454231 -36.7305209
OS -2.45651782 -36.69862358
OS -2.46761254 -36.66533942
OS -2.47870726 -36.63205526
OS -2.48841514 -36.60015794
OE
SE
S P 0
OB 35.73690338 -37.45999874 I
OS 35.61486146 -37.45999874
OS 35.61486146 -36.65701838
OS 35.33471978 -37.45999874
OS 35.2209989 -37.45999874
OS 34.9436309 -36.64314998
OS 34.9436309 -37.45999874
OS 34.82158898 -37.45999874
OS 34.82158898 -36.50030546
OS 35.01158606 -36.50030546
OS 35.23902782 -37.1812439
OS 35.23902782 -37.18263074
OS 35.24041466 -37.18540442
OS 35.2418015 -37.18956494
OS 35.24457518 -37.19649914
OS 35.25012254 -37.21314122
OS 35.25705674 -37.23394382
OS 35.26399094 -37.2575201
OS 35.27231198 -37.28109638
OS 35.27924618 -37.30328582
OS 35.28479354 -37.32270158
OS 35.28618038 -37.3199279
OS 35.28756722 -37.3129937
OS 35.29172774 -37.30051214
OS 35.2972751 -37.28387006
OS 35.3042093 -37.26168062
OS 35.31391718 -37.23533066
OS 35.32362506 -37.20482018
OS 35.33610662 -37.16876234
OS 35.56632206 -36.50030546
OS 35.73690338 -36.50030546
OS 35.73690338 -37.45999874
OE
OB 34.61356298 -37.05504146 I
OS 34.61356298 -37.0564283
OS 34.61356298 -37.06197566
OS 34.61356298 -37.06890986
OS 34.61356298 -37.07861774
OS 34.61217614 -37.0910993
OS 34.61217614 -37.1049677
OS 34.6107893 -37.12160978
OS 34.60940246 -37.13825186
OS 34.60524194 -37.17569654
OS 34.59969458 -37.21452806
OS 34.59137354 -37.25197274
OS 34.58582618 -37.27000166
OS 34.58027882 -37.28664374
OS 34.58027882 -37.28803058
OS 34.57889198 -37.29080426
OS 34.5761183 -37.29496478
OS 34.57334462 -37.30051214
OS 34.56502358 -37.31576738
OS 34.55254202 -37.33518314
OS 34.53589994 -37.35737258
OS 34.51648418 -37.37956202
OS 34.49152106 -37.4031383
OS 34.46101058 -37.4239409
OS 34.45962374 -37.4239409
OS 34.45685006 -37.42671458
OS 34.45268954 -37.42810142
OS 34.44575534 -37.43226194
OS 34.4374343 -37.43642246
OS 34.42633958 -37.44058298
OS 34.41524486 -37.4447435
OS 34.40137646 -37.45029086
OS 34.38612122 -37.45583822
OS 34.36947914 -37.45999874
OS 34.35145022 -37.46415926
OS 34.33064762 -37.46831978
OS 34.30984502 -37.47109346
OS 34.28765558 -37.47386714
OS 34.23772934 -37.47664082
OS 34.22524778 -37.47664082
OS 34.2155399 -37.47525398
OS 34.20444518 -37.47525398
OS 34.19057678 -37.47386714
OS 34.17532154 -37.4724803
OS 34.1600663 -37.47109346
OS 34.1253953 -37.4655461
OS 34.08795062 -37.45722506
OS 34.05189278 -37.44613034
OS 34.01722178 -37.4308751
OS 34.01583494 -37.4308751
OS 34.01306126 -37.42810142
OS 34.00890074 -37.42532774
OS 34.00335338 -37.42255406
OS 33.98809814 -37.41145934
OS 33.97006922 -37.3962041
OS 33.94926662 -37.37678834
OS 33.92985086 -37.3545989
OS 33.9104351 -37.3268621
OS 33.89517986 -37.29635162
OS 33.89517986 -37.29496478
OS 33.89379302 -37.2921911
OS 33.89240618 -37.28664374
OS 33.8896325 -37.27970954
OS 33.88685882 -37.2713885
OS 33.88408514 -37.26029378
OS 33.87992462 -37.24781222
OS 33.87715094 -37.23255698
OS 33.87437726 -37.2159149
OS 33.87021674 -37.19788598
OS 33.86744306 -37.17847022
OS 33.86466938 -37.15766762
OS 33.8618957 -37.13409134
OS 33.86050886 -37.10912822
OS 33.85912202 -37.08277826
OS 33.85912202 -37.05504146
OS 33.85912202 -36.50030546
OS 33.9867113 -36.50030546
OS 33.9867113 -37.05504146
OS 33.9867113 -37.0564283
OS 33.9867113 -37.06058882
OS 33.9867113 -37.06752302
OS 33.9867113 -37.07584406
OS 33.98809814 -37.08555194
OS 33.98809814 -37.0980335
OS 33.98948498 -37.12438346
OS 33.99225866 -37.15489394
OS 33.99641918 -37.18540442
OS 34.00196654 -37.21452806
OS 34.00474022 -37.22700962
OS 34.00890074 -37.23949118
OS 34.01028758 -37.24226486
OS 34.01306126 -37.24919906
OS 34.01999546 -37.25890694
OS 34.0283165 -37.27277534
OS 34.03802438 -37.28664374
OS 34.05189278 -37.30189898
OS 34.06853486 -37.31715422
OS 34.08795062 -37.32963578
OS 34.0907243 -37.33102262
OS 34.0976585 -37.33518314
OS 34.11014006 -37.33934366
OS 34.12678214 -37.34489102
OS 34.1461979 -37.35182522
OS 34.17116102 -37.35598574
OS 34.19751098 -37.36014626
OS 34.22663462 -37.3615331
OS 34.24050302 -37.3615331
OS 34.24882406 -37.36014626
OS 34.26130562 -37.36014626
OS 34.27378718 -37.35875942
OS 34.30429766 -37.35321206
OS 34.33758182 -37.34627786
OS 34.36947914 -37.33518314
OS 34.39998962 -37.3199279
OS 34.41385802 -37.31022002
OS 34.42633958 -37.2991253
OS 34.42772642 -37.29773846
OS 34.42911326 -37.29635162
OS 34.43188694 -37.2921911
OS 34.43604746 -37.28664374
OS 34.44020798 -37.2783227
OS 34.44575534 -37.27000166
OS 34.4513027 -37.2575201
OS 34.45685006 -37.24503854
OS 34.46239742 -37.2297833
OS 34.46655794 -37.21175438
OS 34.4721053 -37.19095178
OS 34.47626582 -37.16876234
OS 34.48042634 -37.14379922
OS 34.48320002 -37.11744926
OS 34.4859737 -37.08693878
OS 34.4859737 -37.05504146
OS 34.4859737 -36.50030546
OS 34.61356298 -36.50030546
OS 34.61356298 -37.05504146
OE
OB 33.64416182 -37.45999874 I
OS 33.51241202 -37.45999874
OS 33.01037594 -36.70694462
OS 33.01037594 -37.45999874
OS 32.88833402 -37.45999874
OS 32.88833402 -36.50030546
OS 33.01869698 -36.50030546
OS 33.5221199 -37.25474642
OS 33.5221199 -36.50030546
OS 33.64416182 -36.50030546
OS 33.64416182 -37.45999874
OE
OB 38.19022334 -36.5016923 I
OS 38.2027049 -36.5016923
OS 38.23182854 -36.50307914
OS 38.26233902 -36.50723966
OS 38.29562318 -36.51140018
OS 38.32613366 -36.51833438
OS 38.3413889 -36.5224949
OS 38.35387046 -36.52665542
OS 38.3552573 -36.52665542
OS 38.35664414 -36.52804226
OS 38.36496518 -36.53220278
OS 38.37744674 -36.53775014
OS 38.39270198 -36.54745802
OS 38.40934406 -36.55993958
OS 38.42737298 -36.57658166
OS 38.44401506 -36.59599742
OS 38.46065714 -36.61818686
OS 38.46065714 -36.6195737
OS 38.46204398 -36.62096054
OS 38.46759134 -36.62928158
OS 38.4731387 -36.64314998
OS 38.48145974 -36.6611789
OS 38.48839394 -36.6819815
OS 38.49532814 -36.70694462
OS 38.49948866 -36.73329458
OS 38.5008755 -36.76241822
OS 38.5008755 -36.76380506
OS 38.5008755 -36.76657874
OS 38.5008755 -36.7721261
OS 38.49948866 -36.7790603
OS 38.49948866 -36.78876818
OS 38.49810182 -36.79847606
OS 38.49255446 -36.82205234
OS 38.48423342 -36.84978914
OS 38.4731387 -36.87891278
OS 38.45649662 -36.90803642
OS 38.4454019 -36.92190482
OS 38.43430718 -36.93577322
OS 38.43292034 -36.93716006
OS 38.4315335 -36.9385469
OS 38.42737298 -36.94270742
OS 38.42182562 -36.94686794
OS 38.41489142 -36.9524153
OS 38.40657038 -36.95796266
OS 38.39547566 -36.96489686
OS 38.38438094 -36.9732179
OS 38.37051254 -36.9801521
OS 38.3552573 -36.9870863
OS 38.33861522 -36.99540734
OS 38.3205863 -37.00234154
OS 38.2997837 -37.0078889
OS 38.2789811 -37.0148231
OS 38.25540482 -37.01898362
OS 38.2304417 -37.02314414
OS 38.23321538 -37.02453098
OS 38.23876274 -37.02730466
OS 38.24708378 -37.03285202
OS 38.2581785 -37.03839938
OS 38.28314162 -37.05365462
OS 38.29562318 -37.0633625
OS 38.3067179 -37.07168354
OS 38.30949158 -37.07445722
OS 38.31642578 -37.08139142
OS 38.3275205 -37.09248614
OS 38.3413889 -37.10635454
OS 38.35664414 -37.1257703
OS 38.37467306 -37.1465729
OS 38.39270198 -37.17153602
OS 38.41211774 -37.19927282
OS 38.5771517 -37.45999874
OS 38.41905194 -37.45999874
OS 38.2928495 -37.26029378
OS 38.2928495 -37.25890694
OS 38.29007582 -37.25613326
OS 38.28730214 -37.25197274
OS 38.28314162 -37.24642538
OS 38.27343374 -37.23117014
OS 38.26095218 -37.21175438
OS 38.24569694 -37.19095178
OS 38.2304417 -37.16876234
OS 38.21518646 -37.14795974
OS 38.20131806 -37.12854398
OS 38.19993122 -37.12715714
OS 38.1957707 -37.12160978
OS 38.1888365 -37.11328874
OS 38.17912862 -37.10358086
OS 38.15832602 -37.08277826
OS 38.1472313 -37.07307038
OS 38.13613658 -37.06474934
OS 38.13474974 -37.0633625
OS 38.13197606 -37.06197566
OS 38.1264287 -37.05920198
OS 38.11810766 -37.05504146
OS 38.10978662 -37.05088094
OS 38.10007874 -37.04672042
OS 38.0778893 -37.03978622
OS 38.07650246 -37.03978622
OS 38.07372878 -37.03839938
OS 38.06818142 -37.03839938
OS 38.06124722 -37.03701254
OS 38.05153934 -37.0356257
OS 38.04044462 -37.0356257
OS 38.02518938 -37.03423886
OS 37.86154226 -37.03423886
OS 37.86154226 -37.45999874
OS 37.73395298 -37.45999874
OS 37.73395298 -36.50030546
OS 38.17912862 -36.50030546
OS 38.19022334 -36.5016923
OE
OB 37.53424802 -36.61402634 I
OS 36.96703046 -36.61402634
OS 36.96703046 -36.90664958
OS 37.49819018 -36.90664958
OS 37.49819018 -37.02037046
OS 36.96703046 -37.02037046
OS 36.96703046 -37.34627786
OS 37.55643746 -37.34627786
OS 37.55643746 -37.45999874
OS 36.83944118 -37.45999874
OS 36.83944118 -36.50030546
OS 37.53424802 -36.50030546
OS 37.53424802 -36.61402634
OE
OB 36.32492354 -36.5016923 I
OS 36.33601826 -36.5016923
OS 36.36098138 -36.50446598
OS 36.38871818 -36.50723966
OS 36.41784182 -36.51278702
OS 36.44696546 -36.51972122
OS 36.47331542 -36.5294291
OS 36.47470226 -36.5294291
OS 36.4760891 -36.53081594
OS 36.48441014 -36.53497646
OS 36.4968917 -36.54191066
OS 36.5107601 -36.55161854
OS 36.52740218 -36.5641001
OS 36.5454311 -36.57935534
OS 36.56207318 -36.5987711
OS 36.57732842 -36.6195737
OS 36.57871526 -36.62234738
OS 36.58287578 -36.63066842
OS 36.58980998 -36.64176314
OS 36.59674418 -36.65840522
OS 36.60367838 -36.67782098
OS 36.61061258 -36.69862358
OS 36.6147731 -36.72219986
OS 36.61615994 -36.74577614
OS 36.61615994 -36.74854982
OS 36.61615994 -36.75548402
OS 36.6147731 -36.76796558
OS 36.61199942 -36.78322082
OS 36.6078389 -36.80124974
OS 36.6009047 -36.8206655
OS 36.59258366 -36.84008126
OS 36.58148894 -36.86088386
OS 36.5801021 -36.86365754
OS 36.57594158 -36.8692049
OS 36.56762054 -36.88029962
OS 36.55652582 -36.89139434
OS 36.54265742 -36.90526274
OS 36.52601534 -36.92051798
OS 36.50521274 -36.93438638
OS 36.48163646 -36.94825478
OS 36.4830233 -36.94825478
OS 36.48579698 -36.94964162
OS 36.4899575 -36.95102846
OS 36.49550486 -36.95380214
OS 36.51214694 -36.9593495
OS 36.5315627 -36.96905738
OS 36.5523653 -36.98153894
OS 36.57594158 -36.99679418
OS 36.59674418 -37.0148231
OS 36.61615994 -37.03701254
OS 36.61754678 -37.03978622
OS 36.62309414 -37.04810726
OS 36.63141518 -37.06058882
OS 36.63973622 -37.0772309
OS 36.64805726 -37.09942034
OS 36.6563783 -37.12299662
OS 36.66192566 -37.15073342
OS 36.6633125 -37.1812439
OS 36.6633125 -37.18263074
OS 36.6633125 -37.18401758
OS 36.6633125 -37.19233862
OS 36.66192566 -37.20620702
OS 36.65915198 -37.2228491
OS 36.6563783 -37.24226486
OS 36.65083094 -37.26306746
OS 36.64389674 -37.2852569
OS 36.63418886 -37.30744634
OS 36.63280202 -37.31022002
OS 36.6286415 -37.31715422
OS 36.62309414 -37.3268621
OS 36.6147731 -37.3407305
OS 36.60367838 -37.3545989
OS 36.59258366 -37.36985414
OS 36.57871526 -37.38510938
OS 36.56346002 -37.39759094
OS 36.56207318 -37.39897778
OS 36.55652582 -37.4031383
OS 36.54681794 -37.40868566
OS 36.53433638 -37.41423302
OS 36.51908114 -37.42255406
OS 36.50105222 -37.4308751
OS 36.48163646 -37.4378093
OS 36.45806018 -37.4447435
OS 36.4552865 -37.4447435
OS 36.44696546 -37.44751718
OS 36.43309706 -37.44890402
OS 36.41506814 -37.4516777
OS 36.3928787 -37.45445138
OS 36.36652874 -37.45722506
OS 36.3374051 -37.4586119
OS 36.30412094 -37.45999874
OS 35.93799518 -37.45999874
OS 35.93799518 -36.50030546
OS 36.31521566 -36.50030546
OS 36.32492354 -36.5016923
OE
OB 32.3849111 -36.61402634 I
OS 32.06871158 -36.61402634
OS 32.06871158 -37.45999874
OS 31.9411223 -37.45999874
OS 31.9411223 -36.61402634
OS 31.62492278 -36.61402634
OS 31.62492278 -36.50030546
OS 32.3849111 -36.50030546
OS 32.3849111 -36.61402634
OE
OB 30.62639798 -37.45999874 I
OS 30.48216662 -37.45999874
OS 30.36983258 -37.16876234
OS 29.96764898 -37.16876234
OS 29.86363598 -37.45999874
OS 29.7291125 -37.45999874
OS 30.09523826 -36.50030546
OS 30.23392226 -36.50030546
OS 30.62639798 -37.45999874
OE
OB 29.3546657 -36.5016923 I
OS 29.37824198 -36.50307914
OS 29.4032051 -36.50446598
OS 29.42678138 -36.50723966
OS 29.44758398 -36.51001334
OS 29.45035766 -36.51001334
OS 29.46006554 -36.51278702
OS 29.4725471 -36.5155607
OS 29.48918918 -36.51972122
OS 29.5072181 -36.52665542
OS 29.52663386 -36.53497646
OS 29.54743646 -36.54468434
OS 29.56546538 -36.55577906
OS 29.56823906 -36.5571659
OS 29.57378642 -36.56132642
OS 29.58210746 -36.56964746
OS 29.59320218 -36.57935534
OS 29.60568374 -36.5918369
OS 29.6181653 -36.60847898
OS 29.6320337 -36.6265079
OS 29.64312842 -36.6473105
OS 29.64451526 -36.65008418
OS 29.64728894 -36.65701838
OS 29.6528363 -36.66949994
OS 29.65838366 -36.68614202
OS 29.66254418 -36.70555778
OS 29.66809154 -36.72774722
OS 29.67086522 -36.75271034
OS 29.67225206 -36.7790603
OS 29.67225206 -36.78044714
OS 29.67225206 -36.78460766
OS 29.67225206 -36.79015502
OS 29.67086522 -36.7998629
OS 29.66947838 -36.80957078
OS 29.66809154 -36.82205234
OS 29.66531786 -36.83592074
OS 29.66254418 -36.85117598
OS 29.6528363 -36.8830733
OS 29.64728894 -36.89971538
OS 29.6389679 -36.9177443
OS 29.62926002 -36.93577322
OS 29.61955214 -36.9524153
OS 29.60707058 -36.96905738
OS 29.59320218 -36.98569946
OS 29.59181534 -36.9870863
OS 29.58904166 -36.98985998
OS 29.58488114 -36.9940205
OS 29.57794694 -36.99818102
OS 29.5696259 -37.00511522
OS 29.55853118 -37.01204942
OS 29.54466278 -37.02037046
OS 29.52940754 -37.02730466
OS 29.51137862 -37.0356257
OS 29.49057602 -37.04394674
OS 29.46838658 -37.05088094
OS 29.44203662 -37.0564283
OS 29.41429982 -37.06197566
OS 29.38378934 -37.06613618
OS 29.34911834 -37.06890986
OS 29.3130605 -37.0702967
OS 29.06758982 -37.0702967
OS 29.06758982 -37.45999874
OS 28.94000054 -37.45999874
OS 28.94000054 -36.50030546
OS 29.3338631 -36.50030546
OS 29.3546657 -36.5016923
OE
OB 31.18668134 -36.5016923 I
OS 31.1991629 -36.5016923
OS 31.22828654 -36.50307914
OS 31.25879702 -36.50723966
OS 31.29208118 -36.51140018
OS 31.32259166 -36.51833438
OS 31.3378469 -36.5224949
OS 31.35032846 -36.52665542
OS 31.3517153 -36.52665542
OS 31.35310214 -36.52804226
OS 31.36142318 -36.53220278
OS 31.37390474 -36.53775014
OS 31.38915998 -36.54745802
OS 31.40580206 -36.55993958
OS 31.42383098 -36.57658166
OS 31.44047306 -36.59599742
OS 31.45711514 -36.61818686
OS 31.45711514 -36.6195737
OS 31.45850198 -36.62096054
OS 31.46404934 -36.62928158
OS 31.4695967 -36.64314998
OS 31.47791774 -36.6611789
OS 31.48485194 -36.6819815
OS 31.49178614 -36.70694462
OS 31.49594666 -36.73329458
OS 31.4973335 -36.76241822
OS 31.4973335 -36.76380506
OS 31.4973335 -36.76657874
OS 31.4973335 -36.7721261
OS 31.49594666 -36.7790603
OS 31.49594666 -36.78876818
OS 31.49455982 -36.79847606
OS 31.48901246 -36.82205234
OS 31.48069142 -36.84978914
OS 31.4695967 -36.87891278
OS 31.45295462 -36.90803642
OS 31.4418599 -36.92190482
OS 31.43076518 -36.93577322
OS 31.42937834 -36.93716006
OS 31.4279915 -36.9385469
OS 31.42383098 -36.94270742
OS 31.41828362 -36.94686794
OS 31.41134942 -36.9524153
OS 31.40302838 -36.95796266
OS 31.39193366 -36.96489686
OS 31.38083894 -36.9732179
OS 31.36697054 -36.9801521
OS 31.3517153 -36.9870863
OS 31.33507322 -36.99540734
OS 31.3170443 -37.00234154
OS 31.2962417 -37.0078889
OS 31.2754391 -37.0148231
OS 31.25186282 -37.01898362
OS 31.2268997 -37.02314414
OS 31.22967338 -37.02453098
OS 31.23522074 -37.02730466
OS 31.24354178 -37.03285202
OS 31.2546365 -37.03839938
OS 31.27959962 -37.05365462
OS 31.29208118 -37.0633625
OS 31.3031759 -37.07168354
OS 31.30594958 -37.07445722
OS 31.31288378 -37.08139142
OS 31.3239785 -37.09248614
OS 31.3378469 -37.10635454
OS 31.35310214 -37.1257703
OS 31.37113106 -37.1465729
OS 31.38915998 -37.17153602
OS 31.40857574 -37.19927282
OS 31.5736097 -37.45999874
OS 31.41550994 -37.45999874
OS 31.2893075 -37.26029378
OS 31.2893075 -37.25890694
OS 31.28653382 -37.25613326
OS 31.28376014 -37.25197274
OS 31.27959962 -37.24642538
OS 31.26989174 -37.23117014
OS 31.25741018 -37.21175438
OS 31.24215494 -37.19095178
OS 31.2268997 -37.16876234
OS 31.21164446 -37.14795974
OS 31.19777606 -37.12854398
OS 31.19638922 -37.12715714
OS 31.1922287 -37.12160978
OS 31.1852945 -37.11328874
OS 31.17558662 -37.10358086
OS 31.15478402 -37.08277826
OS 31.1436893 -37.07307038
OS 31.13259458 -37.06474934
OS 31.13120774 -37.0633625
OS 31.12843406 -37.06197566
OS 31.1228867 -37.05920198
OS 31.11456566 -37.05504146
OS 31.10624462 -37.05088094
OS 31.09653674 -37.04672042
OS 31.0743473 -37.03978622
OS 31.07296046 -37.03978622
OS 31.07018678 -37.03839938
OS 31.06463942 -37.03839938
OS 31.05770522 -37.03701254
OS 31.04799734 -37.0356257
OS 31.03690262 -37.0356257
OS 31.02164738 -37.03423886
OS 30.85800026 -37.03423886
OS 30.85800026 -37.45999874
OS 30.73041098 -37.45999874
OS 30.73041098 -36.50030546
OS 31.17558662 -36.50030546
OS 31.18668134 -36.5016923
OE
OB 38.16387338 -36.60709214 H
OS 37.86154226 -36.60709214
OS 37.86154226 -36.9246785
OS 38.1472313 -36.9246785
OS 38.16387338 -36.92329166
OS 38.18328914 -36.92190482
OS 38.20547858 -36.92051798
OS 38.22766802 -36.9177443
OS 38.24985746 -36.91358378
OS 38.26927322 -36.90803642
OS 38.2720469 -36.90664958
OS 38.27759426 -36.9038759
OS 38.2859153 -36.89971538
OS 38.29701002 -36.89416802
OS 38.30949158 -36.88584698
OS 38.32197314 -36.8761391
OS 38.3344547 -36.86365754
OS 38.34416258 -36.84978914
OS 38.34554942 -36.8484023
OS 38.3483231 -36.84285494
OS 38.35248362 -36.8345339
OS 38.35803098 -36.82343918
OS 38.3621915 -36.81095762
OS 38.36635202 -36.79708922
OS 38.3691257 -36.78044714
OS 38.37051254 -36.76380506
OS 38.37051254 -36.76241822
OS 38.37051254 -36.76103138
OS 38.3691257 -36.75271034
OS 38.36773886 -36.74022878
OS 38.36496518 -36.7235867
OS 38.35803098 -36.70694462
OS 38.34970994 -36.68752886
OS 38.33722838 -36.66949994
OS 38.3205863 -36.65147102
OS 38.31781262 -36.65008418
OS 38.31087842 -36.64453682
OS 38.2997837 -36.63760262
OS 38.28175478 -36.62928158
OS 38.26095218 -36.62096054
OS 38.23321538 -36.61402634
OS 38.20131806 -36.60847898
OS 38.16387338 -36.60709214
OE
OB 29.34218414 -36.61402634 H
OS 29.06758982 -36.61402634
OS 29.06758982 -36.95657582
OS 29.32554206 -36.95657582
OS 29.33524994 -36.95518898
OS 29.34495782 -36.95518898
OS 29.35605254 -36.95380214
OS 29.3824025 -36.95102846
OS 29.41152614 -36.9454811
OS 29.44064978 -36.93716006
OS 29.46699974 -36.92606534
OS 29.4794813 -36.91913114
OS 29.48918918 -36.9108101
OS 29.49196286 -36.90803642
OS 29.49751022 -36.90248906
OS 29.50583126 -36.89139434
OS 29.51553914 -36.87752594
OS 29.52524702 -36.85949702
OS 29.53356806 -36.83730758
OS 29.53911542 -36.81234446
OS 29.5418891 -36.78322082
OS 29.5418891 -36.78183398
OS 29.5418891 -36.78044714
OS 29.5418891 -36.77351294
OS 29.54050226 -36.76103138
OS 29.53772858 -36.74716298
OS 29.5349549 -36.73190774
OS 29.52940754 -36.71387882
OS 29.5210865 -36.69723674
OS 29.51137862 -36.68059466
OS 29.50999178 -36.67920782
OS 29.50583126 -36.67366046
OS 29.49889706 -36.66672626
OS 29.49057602 -36.65701838
OS 29.47809446 -36.6473105
OS 29.46422606 -36.63898946
OS 29.44897082 -36.63066842
OS 29.4309419 -36.62373422
OS 29.42955506 -36.62373422
OS 29.4240077 -36.62234738
OS 29.41568666 -36.62096054
OS 29.40459194 -36.61818686
OS 29.38794986 -36.61680002
OS 29.36714726 -36.61541318
OS 29.34218414 -36.61402634
OE
OB 30.16180658 -36.60015794 H
OS 30.16180658 -36.60154478
OS 30.16041974 -36.60431846
OS 30.16041974 -36.60986582
OS 30.15764606 -36.61541318
OS 30.15625922 -36.62512106
OS 30.15348554 -36.63482894
OS 30.14793818 -36.65840522
OS 30.14100398 -36.68614202
OS 30.1312961 -36.7166525
OS 30.12158822 -36.74993666
OS 30.10910666 -36.78460766
OS 30.00509366 -37.06474934
OS 30.32961422 -37.06474934
OS 30.22976174 -36.80124974
OS 30.22976174 -36.7998629
OS 30.2283749 -36.79570238
OS 30.22560122 -36.78876818
OS 30.22282754 -36.78044714
OS 30.21866702 -36.77073926
OS 30.2145065 -36.7582577
OS 30.21034598 -36.7443893
OS 30.20479862 -36.7305209
OS 30.1937039 -36.69862358
OS 30.18260918 -36.66533942
OS 30.17151446 -36.63205526
OS 30.16180658 -36.60015794
OE
OB 31.16033138 -36.60709214 H
OS 30.85800026 -36.60709214
OS 30.85800026 -36.9246785
OS 31.1436893 -36.9246785
OS 31.16033138 -36.92329166
OS 31.17974714 -36.92190482
OS 31.20193658 -36.92051798
OS 31.22412602 -36.9177443
OS 31.24631546 -36.91358378
OS 31.26573122 -36.90803642
OS 31.2685049 -36.90664958
OS 31.27405226 -36.9038759
OS 31.2823733 -36.89971538
OS 31.29346802 -36.89416802
OS 31.30594958 -36.88584698
OS 31.31843114 -36.8761391
OS 31.3309127 -36.86365754
OS 31.34062058 -36.84978914
OS 31.34200742 -36.8484023
OS 31.3447811 -36.84285494
OS 31.34894162 -36.8345339
OS 31.35448898 -36.82343918
OS 31.3586495 -36.81095762
OS 31.36281002 -36.79708922
OS 31.3655837 -36.78044714
OS 31.36697054 -36.76380506
OS 31.36697054 -36.76241822
OS 31.36697054 -36.76103138
OS 31.3655837 -36.75271034
OS 31.36419686 -36.74022878
OS 31.36142318 -36.7235867
OS 31.35448898 -36.70694462
OS 31.34616794 -36.68752886
OS 31.33368638 -36.66949994
OS 31.3170443 -36.65147102
OS 31.31427062 -36.65008418
OS 31.30733642 -36.64453682
OS 31.2962417 -36.63760262
OS 31.27821278 -36.62928158
OS 31.25741018 -36.62096054
OS 31.22967338 -36.61402634
OS 31.19777606 -36.60847898
OS 31.16033138 -36.60709214
OE
OB 36.29302622 -36.61402634 H
OS 36.06558446 -36.61402634
OS 36.06558446 -36.90248906
OS 36.30134726 -36.90248906
OS 36.31937618 -36.90110222
OS 36.33879194 -36.89971538
OS 36.3582077 -36.89832854
OS 36.37762346 -36.89555486
OS 36.3928787 -36.89278118
OS 36.39565238 -36.89139434
OS 36.40119974 -36.8900075
OS 36.40952078 -36.88584698
OS 36.4206155 -36.88029962
OS 36.43171022 -36.87475226
OS 36.44419178 -36.86643122
OS 36.45667334 -36.8553365
OS 36.46638122 -36.84424178
OS 36.46776806 -36.84285494
OS 36.47054174 -36.83869442
OS 36.47470226 -36.83037338
OS 36.47886278 -36.8206655
OS 36.4830233 -36.80957078
OS 36.48718382 -36.79570238
OS 36.4899575 -36.7790603
OS 36.49134434 -36.76103138
OS 36.49134434 -36.7582577
OS 36.49134434 -36.75271034
OS 36.4899575 -36.7443893
OS 36.48857066 -36.73329458
OS 36.48579698 -36.71942618
OS 36.48163646 -36.70555778
OS 36.4760891 -36.69168938
OS 36.46776806 -36.67782098
OS 36.46638122 -36.67643414
OS 36.46360754 -36.67227362
OS 36.45806018 -36.66533942
OS 36.45112598 -36.65840522
OS 36.4414181 -36.65008418
OS 36.43032338 -36.64176314
OS 36.41645498 -36.6334421
OS 36.40119974 -36.62789474
OS 36.3998129 -36.62789474
OS 36.3928787 -36.62512106
OS 36.38317082 -36.62373422
OS 36.36791558 -36.62096054
OS 36.34711298 -36.61818686
OS 36.3235367 -36.61680002
OS 36.29302622 -36.61402634
OE
OB 36.31798934 -37.01620994 H
OS 36.06558446 -37.01620994
OS 36.06558446 -37.34627786
OS 36.33879194 -37.34627786
OS 36.36791558 -37.34489102
OS 36.38039714 -37.34350418
OS 36.39149186 -37.34211734
OS 36.3928787 -37.34211734
OS 36.39842606 -37.3407305
OS 36.4067471 -37.33934366
OS 36.41645498 -37.33656998
OS 36.44003126 -37.32824894
OS 36.46360754 -37.31715422
OS 36.46499438 -37.31576738
OS 36.4691549 -37.3129937
OS 36.47470226 -37.30883318
OS 36.48163646 -37.30328582
OS 36.48857066 -37.29496478
OS 36.49827854 -37.28664374
OS 36.50521274 -37.27554902
OS 36.51353378 -37.26306746
OS 36.51492062 -37.26168062
OS 36.51630746 -37.2575201
OS 36.51908114 -37.24919906
OS 36.52324166 -37.23949118
OS 36.52740218 -37.22839646
OS 36.53017586 -37.21452806
OS 36.5315627 -37.19788598
OS 36.53294954 -37.1812439
OS 36.53294954 -37.17847022
OS 36.53294954 -37.17292286
OS 36.5315627 -37.16182814
OS 36.52878902 -37.14934658
OS 36.52601534 -37.13547818
OS 36.52046798 -37.12022294
OS 36.51353378 -37.1049677
OS 36.5038259 -37.08971246
OS 36.50243906 -37.08832562
OS 36.49827854 -37.08277826
OS 36.49273118 -37.07584406
OS 36.48441014 -37.06752302
OS 36.47331542 -37.05781514
OS 36.45944702 -37.04810726
OS 36.44419178 -37.03978622
OS 36.42616286 -37.03285202
OS 36.42338918 -37.03146518
OS 36.41784182 -37.03007834
OS 36.40536026 -37.02730466
OS 36.39010502 -37.02453098
OS 36.37068926 -37.0217573
OS 36.34711298 -37.01898362
OS 36.31798934 -37.01620994
OE
SE
S P 0
OB 40.9056459 -38.32112732 I
OS 40.92136342 -38.32205188
OS 40.9380055 -38.32297644
OS 40.95372302 -38.32482556
OS 40.96759142 -38.32667468
OS 40.96944054 -38.32667468
OS 40.97591246 -38.3285238
OS 40.9842335 -38.33037292
OS 40.99532822 -38.3331466
OS 41.0073475 -38.3377694
OS 41.02029134 -38.34331676
OS 41.03415974 -38.34978868
OS 41.04617902 -38.35718516
OS 41.04802814 -38.35810972
OS 41.05172638 -38.3608834
OS 41.05727374 -38.36643076
OS 41.06467022 -38.37290268
OS 41.07299126 -38.38122372
OS 41.0813123 -38.39231844
OS 41.0905579 -38.40433772
OS 41.09795438 -38.41820612
OS 41.09887894 -38.42005524
OS 41.10072806 -38.42467804
OS 41.1044263 -38.43299908
OS 41.10812454 -38.4440938
OS 41.11089822 -38.45703764
OS 41.11459646 -38.4718306
OS 41.11644558 -38.48847268
OS 41.11737014 -38.50603932
OS 41.11737014 -38.50696388
OS 41.11737014 -38.50973756
OS 41.11737014 -38.5134358
OS 41.11644558 -38.51990772
OS 41.11552102 -38.52637964
OS 41.11459646 -38.53470068
OS 41.11274734 -38.54394628
OS 41.11089822 -38.55411644
OS 41.1044263 -38.57538132
OS 41.10072806 -38.58647604
OS 41.0951807 -38.59849532
OS 41.08870878 -38.6105146
OS 41.08223686 -38.62160932
OS 41.07391582 -38.63270404
OS 41.06467022 -38.64379876
OS 41.06374566 -38.64472332
OS 41.06189654 -38.64657244
OS 41.05912286 -38.64934612
OS 41.05450006 -38.6521198
OS 41.0489527 -38.6567426
OS 41.04155622 -38.6613654
OS 41.03231062 -38.66691276
OS 41.02214046 -38.67153556
OS 41.01012118 -38.67708292
OS 40.99625278 -38.68263028
OS 40.98145982 -38.68725308
OS 40.96389318 -38.69095132
OS 40.94540198 -38.69464956
OS 40.92506166 -38.69742324
OS 40.90194766 -38.69927236
OS 40.8779091 -38.70019692
OS 40.71426198 -38.70019692
OS 40.71426198 -38.95999828
OS 40.62920246 -38.95999828
OS 40.62920246 -38.32020276
OS 40.8917775 -38.32020276
OS 40.9056459 -38.32112732
OE
OB 40.49791494 -38.98403684 I
OS 40.49791494 -38.9849614
OS 40.49791494 -38.98773508
OS 40.49791494 -38.99235788
OS 40.49791494 -38.99790524
OS 40.49699038 -39.00530172
OS 40.49699038 -39.0126982
OS 40.49514126 -39.0311894
OS 40.49236758 -39.05060516
OS 40.48866934 -39.07094548
OS 40.48312198 -39.08851212
OS 40.47942374 -39.09683316
OS 40.4757255 -39.10330508
OS 40.4757255 -39.10422964
OS 40.47480094 -39.1051542
OS 40.47017814 -39.109777
OS 40.46278166 -39.11717348
OS 40.45353606 -39.12549452
OS 40.44059222 -39.13381556
OS 40.42395014 -39.14028748
OS 40.40453438 -39.14583484
OS 40.39343966 -39.1467594
OS 40.38142038 -39.14768396
OS 40.37587302 -39.14768396
OS 40.37032566 -39.1467594
OS 40.36200462 -39.1467594
OS 40.35275902 -39.14583484
OS 40.34258886 -39.14398572
OS 40.32039942 -39.13843836
OS 40.33519238 -39.07187004
OS 40.33611694 -39.07187004
OS 40.33889062 -39.0727946
OS 40.34351342 -39.07371916
OS 40.34813622 -39.07464372
OS 40.3601555 -39.0774174
OS 40.36570286 -39.07834196
OS 40.37494846 -39.07834196
OS 40.37957126 -39.0774174
OS 40.38511862 -39.07649284
OS 40.39066598 -39.07464372
OS 40.39621334 -39.07094548
OS 40.40268526 -39.06724724
OS 40.40730806 -39.06169988
OS 40.40823262 -39.06077532
OS 40.40915718 -39.05800164
OS 40.4110063 -39.05337884
OS 40.41377998 -39.04598236
OS 40.4156291 -39.0358122
OS 40.41655366 -39.02841572
OS 40.41747822 -39.0219438
OS 40.41840278 -39.01362276
OS 40.41840278 -39.0034526
OS 40.41932734 -38.99328244
OS 40.41932734 -38.98218772
OS 40.41932734 -38.49586916
OS 40.49791494 -38.49586916
OS 40.49791494 -38.98403684
OE
OB 41.51770462 -38.3100326 I
OS 41.52602566 -38.31095716
OS 41.53619582 -38.31188172
OS 41.54636598 -38.31280628
OS 41.55838526 -38.31557996
OS 41.58334838 -38.32112732
OS 41.61108518 -38.32944836
OS 41.62495358 -38.33499572
OS 41.63789742 -38.34146764
OS 41.65084126 -38.34978868
OS 41.6637851 -38.35810972
OS 41.66470966 -38.35903428
OS 41.66655878 -38.35995884
OS 41.67025702 -38.36273252
OS 41.67487982 -38.36735532
OS 41.67950262 -38.37197812
OS 41.68597454 -38.37845004
OS 41.69244646 -38.38584652
OS 41.69984294 -38.393243
OS 41.70723942 -38.4024886
OS 41.7146359 -38.41358332
OS 41.72295694 -38.42467804
OS 41.73035342 -38.43669732
OS 41.73682534 -38.45056572
OS 41.74422182 -38.46443412
OS 41.74976918 -38.47922708
OS 41.75531654 -38.49586916
OS 41.67210614 -38.51528492
OS 41.67210614 -38.51436036
OS 41.67118158 -38.51251124
OS 41.66933246 -38.508813
OS 41.66748334 -38.5041902
OS 41.66563422 -38.49864284
OS 41.66286054 -38.49124636
OS 41.65546406 -38.4764534
OS 41.64621846 -38.45981132
OS 41.63512374 -38.44316924
OS 41.62125534 -38.42745172
OS 41.60646238 -38.41358332
OS 41.60461326 -38.4117342
OS 41.5990659 -38.40803596
OS 41.5898203 -38.40341316
OS 41.57780102 -38.39694124
OS 41.5620835 -38.39139388
OS 41.54451686 -38.38584652
OS 41.52325198 -38.38214828
OS 41.50013798 -38.38122372
OS 41.4927415 -38.38122372
OS 41.4881187 -38.38214828
OS 41.48164678 -38.38214828
OS 41.4742503 -38.38307284
OS 41.45668366 -38.38584652
OS 41.4372679 -38.38954476
OS 41.41692758 -38.39601668
OS 41.3956627 -38.40526228
OS 41.37624694 -38.41728156
OS 41.37532238 -38.41728156
OS 41.37439782 -38.41913068
OS 41.3679259 -38.42375348
OS 41.35960486 -38.43114996
OS 41.3494347 -38.44224468
OS 41.33741542 -38.45611308
OS 41.3263207 -38.4718306
OS 41.31615054 -38.49124636
OS 41.30690494 -38.51251124
OS 41.30690494 -38.5134358
OS 41.30598038 -38.51528492
OS 41.30505582 -38.5180586
OS 41.30413126 -38.5226814
OS 41.30228214 -38.52822876
OS 41.30043302 -38.53470068
OS 41.29765934 -38.5504182
OS 41.2939611 -38.5689094
OS 41.29026286 -38.58924972
OS 41.28841374 -38.61143916
OS 41.28748918 -38.63547772
OS 41.28748918 -38.63640228
OS 41.28748918 -38.63917596
OS 41.28748918 -38.64379876
OS 41.28748918 -38.64934612
OS 41.28841374 -38.65581804
OS 41.28841374 -38.66413908
OS 41.2893383 -38.67338468
OS 41.29026286 -38.68355484
OS 41.29303654 -38.70574428
OS 41.29765934 -38.72978284
OS 41.3032067 -38.7538214
OS 41.31060318 -38.77785996
OS 41.31060318 -38.77878452
OS 41.31152774 -38.78063364
OS 41.31337686 -38.78340732
OS 41.31522598 -38.78803012
OS 41.32077334 -38.79912484
OS 41.32909438 -38.81206868
OS 41.33926454 -38.82686164
OS 41.35220838 -38.84257916
OS 41.36700134 -38.85644756
OS 41.38456798 -38.8693914
OS 41.38549254 -38.8693914
OS 41.38734166 -38.87031596
OS 41.39011534 -38.87216508
OS 41.39381358 -38.8740142
OS 41.39843638 -38.87586332
OS 41.40398374 -38.878637
OS 41.41692758 -38.88418436
OS 41.43356966 -38.88973172
OS 41.45206086 -38.89435452
OS 41.47240118 -38.89805276
OS 41.49366606 -38.89897732
OS 41.50013798 -38.89897732
OS 41.50568534 -38.89805276
OS 41.51215726 -38.89805276
OS 41.51862918 -38.8971282
OS 41.53527126 -38.89342996
OS 41.55468702 -38.88880716
OS 41.57410278 -38.88141068
OS 41.5944431 -38.87124052
OS 41.60461326 -38.86569316
OS 41.61385886 -38.85829668
OS 41.61478342 -38.85737212
OS 41.61570798 -38.85644756
OS 41.61848166 -38.85367388
OS 41.6221799 -38.8509002
OS 41.62587814 -38.8462774
OS 41.63050094 -38.84073004
OS 41.6360483 -38.83518268
OS 41.6406711 -38.8277862
OS 41.64621846 -38.81946516
OS 41.65269038 -38.81021956
OS 41.65823774 -38.80097396
OS 41.6637851 -38.78987924
OS 41.6684079 -38.77785996
OS 41.6730307 -38.76491612
OS 41.6776535 -38.75104772
OS 41.68135174 -38.73625476
OS 41.76641126 -38.75751964
OS 41.76641126 -38.7584442
OS 41.7654867 -38.76214244
OS 41.76363758 -38.7676898
OS 41.7608639 -38.77508628
OS 41.75809022 -38.78340732
OS 41.75439198 -38.79357748
OS 41.74976918 -38.8046722
OS 41.74422182 -38.81669148
OS 41.73127798 -38.84257916
OS 41.7146359 -38.86846684
OS 41.70446574 -38.88141068
OS 41.69429558 -38.89435452
OS 41.68320086 -38.90544924
OS 41.67025702 -38.91654396
OS 41.66933246 -38.91746852
OS 41.66748334 -38.91931764
OS 41.66286054 -38.92116676
OS 41.65823774 -38.924865
OS 41.65084126 -38.9294878
OS 41.64344478 -38.9341106
OS 41.63327462 -38.9387334
OS 41.62310446 -38.9433562
OS 41.61108518 -38.94890356
OS 41.59814134 -38.95352636
OS 41.58427294 -38.95814916
OS 41.56947998 -38.96277196
OS 41.55376246 -38.9664702
OS 41.53712038 -38.96831932
OS 41.51955374 -38.97016844
OS 41.50106254 -38.971093
OS 41.49089238 -38.971093
OS 41.4834959 -38.97016844
OS 41.47517486 -38.97016844
OS 41.4650047 -38.96924388
OS 41.45390998 -38.96739476
OS 41.44096614 -38.96554564
OS 41.4141539 -38.96092284
OS 41.3864171 -38.95352636
OS 41.3586803 -38.9433562
OS 41.34573646 -38.93688428
OS 41.33279262 -38.9294878
OS 41.33186806 -38.92856324
OS 41.33001894 -38.92763868
OS 41.3263207 -38.924865
OS 41.32262246 -38.92116676
OS 41.3170751 -38.91746852
OS 41.31060318 -38.91192116
OS 41.3032067 -38.90544924
OS 41.29581022 -38.89805276
OS 41.28841374 -38.88973172
OS 41.2800927 -38.88141068
OS 41.26345062 -38.8601458
OS 41.2477331 -38.83518268
OS 41.2338647 -38.80744588
OS 41.2338647 -38.80652132
OS 41.23201558 -38.80374764
OS 41.23109102 -38.79912484
OS 41.22831734 -38.79357748
OS 41.22646822 -38.786181
OS 41.22369454 -38.7769354
OS 41.2199963 -38.76676524
OS 41.21722262 -38.75567052
OS 41.21444894 -38.74365124
OS 41.2107507 -38.72978284
OS 41.2061279 -38.70112148
OS 41.20242966 -38.66876188
OS 41.20058054 -38.63547772
OS 41.20058054 -38.63455316
OS 41.20058054 -38.63085492
OS 41.20058054 -38.62530756
OS 41.2015051 -38.61883564
OS 41.2015051 -38.60959004
OS 41.20242966 -38.60034444
OS 41.20335422 -38.58832516
OS 41.20520334 -38.57630588
OS 41.20982614 -38.54949364
OS 41.21629806 -38.51990772
OS 41.22554366 -38.4903218
OS 41.2384875 -38.46166044
OS 41.23941206 -38.46073588
OS 41.24033662 -38.4579622
OS 41.24218574 -38.45426396
OS 41.24588398 -38.44964116
OS 41.24958222 -38.44316924
OS 41.25420502 -38.43577276
OS 41.2662243 -38.41913068
OS 41.28194182 -38.40063948
OS 41.30043302 -38.38214828
OS 41.3216979 -38.36365708
OS 41.34666102 -38.34793956
OS 41.34758558 -38.347015
OS 41.35035926 -38.34609044
OS 41.3540575 -38.34424132
OS 41.3586803 -38.34146764
OS 41.36607678 -38.33869396
OS 41.37347326 -38.33592028
OS 41.38271886 -38.33222204
OS 41.39288902 -38.3285238
OS 41.40398374 -38.32482556
OS 41.41600302 -38.32112732
OS 41.4418907 -38.31557996
OS 41.47147662 -38.31095716
OS 41.5019871 -38.30910804
OS 41.5112327 -38.30910804
OS 41.51770462 -38.3100326
OE
OB 42.90454462 -39.1375138 I
OS 42.38401734 -39.1375138
OS 42.38401734 -39.08111564
OS 42.90454462 -39.08111564
OS 42.90454462 -39.1375138
OE
OB 42.12514054 -38.32112732 I
OS 42.13253702 -38.32112732
OS 42.1491791 -38.32297644
OS 42.1676703 -38.32482556
OS 42.18708606 -38.3285238
OS 42.20650182 -38.3331466
OS 42.22406846 -38.33961852
OS 42.22499302 -38.33961852
OS 42.22591758 -38.34054308
OS 42.23146494 -38.34331676
OS 42.23978598 -38.34793956
OS 42.24903158 -38.35441148
OS 42.2601263 -38.36273252
OS 42.27214558 -38.37290268
OS 42.2832403 -38.38584652
OS 42.29341046 -38.39971492
OS 42.29433502 -38.40156404
OS 42.2971087 -38.4071114
OS 42.3017315 -38.41450788
OS 42.3063543 -38.4256026
OS 42.3109771 -38.43854644
OS 42.3155999 -38.45241484
OS 42.31837358 -38.46813236
OS 42.31929814 -38.48384988
OS 42.31929814 -38.485699
OS 42.31929814 -38.4903218
OS 42.31837358 -38.49864284
OS 42.31652446 -38.508813
OS 42.31375078 -38.52083228
OS 42.30912798 -38.53377612
OS 42.30358062 -38.54671996
OS 42.29618414 -38.56058836
OS 42.29525958 -38.56243748
OS 42.2924859 -38.56613572
OS 42.28693854 -38.5735322
OS 42.27954206 -38.58092868
OS 42.27029646 -38.59017428
OS 42.25920174 -38.60034444
OS 42.24533334 -38.60959004
OS 42.22961582 -38.61883564
OS 42.23054038 -38.61883564
OS 42.2323895 -38.6197602
OS 42.23516318 -38.62068476
OS 42.23886142 -38.62253388
OS 42.24995614 -38.62623212
OS 42.26289998 -38.63270404
OS 42.27676838 -38.64102508
OS 42.2924859 -38.65119524
OS 42.3063543 -38.66321452
OS 42.31929814 -38.67800748
OS 42.3202227 -38.6798566
OS 42.32392094 -38.68540396
OS 42.3294683 -38.693725
OS 42.33501566 -38.70481972
OS 42.34056302 -38.71961268
OS 42.34611038 -38.7353302
OS 42.34980862 -38.7538214
OS 42.35073318 -38.77416172
OS 42.35073318 -38.77508628
OS 42.35073318 -38.77601084
OS 42.35073318 -38.7815582
OS 42.34980862 -38.7908038
OS 42.3479595 -38.80189852
OS 42.34611038 -38.81484236
OS 42.34241214 -38.82871076
OS 42.33778934 -38.84350372
OS 42.33131742 -38.85829668
OS 42.33039286 -38.8601458
OS 42.32761918 -38.8647686
OS 42.32392094 -38.87124052
OS 42.31837358 -38.88048612
OS 42.3109771 -38.88973172
OS 42.30358062 -38.89990188
OS 42.29433502 -38.91007204
OS 42.28416486 -38.91839308
OS 42.2832403 -38.91931764
OS 42.27954206 -38.92209132
OS 42.27307014 -38.92578956
OS 42.2647491 -38.9294878
OS 42.25457894 -38.93503516
OS 42.24255966 -38.94058252
OS 42.22961582 -38.94520532
OS 42.2138983 -38.94982812
OS 42.21204918 -38.94982812
OS 42.20650182 -38.95167724
OS 42.19725622 -38.9526018
OS 42.18523694 -38.95445092
OS 42.17044398 -38.95630004
OS 42.15287734 -38.95814916
OS 42.13346158 -38.95907372
OS 42.11127214 -38.95999828
OS 41.8671883 -38.95999828
OS 41.8671883 -38.32020276
OS 42.11866862 -38.32020276
OS 42.12514054 -38.32112732
OE
OB 40.30745558 -38.48662356 I
OS 40.31762574 -38.48847268
OS 40.32964502 -38.49217092
OS 40.34258886 -38.49679372
OS 40.35738182 -38.50326564
OS 40.37309934 -38.51158668
OS 40.34443798 -38.58370236
OS 40.34351342 -38.5827778
OS 40.33981518 -38.58092868
OS 40.33426782 -38.578155
OS 40.32687134 -38.57538132
OS 40.3185503 -38.57260764
OS 40.30838014 -38.56983396
OS 40.29820998 -38.56798484
OS 40.28803982 -38.56706028
OS 40.28341702 -38.56706028
OS 40.27879422 -38.56798484
OS 40.2723223 -38.5689094
OS 40.26585038 -38.57075852
OS 40.25752934 -38.5735322
OS 40.2492083 -38.57723044
OS 40.24181182 -38.5827778
OS 40.24088726 -38.58370236
OS 40.23811358 -38.58555148
OS 40.2353399 -38.58924972
OS 40.2307171 -38.59387252
OS 40.2260943 -38.60034444
OS 40.2214715 -38.60774092
OS 40.2168487 -38.61606196
OS 40.21315046 -38.62623212
OS 40.2122259 -38.62808124
OS 40.21130134 -38.6336286
OS 40.20945222 -38.64194964
OS 40.20667854 -38.65304436
OS 40.20390486 -38.66691276
OS 40.20205574 -38.68263028
OS 40.20113118 -38.69927236
OS 40.20020662 -38.71776356
OS 40.20020662 -38.95999828
OS 40.12161902 -38.95999828
OS 40.12161902 -38.49586916
OS 40.19281014 -38.49586916
OS 40.19281014 -38.56613572
OS 40.1937347 -38.56521116
OS 40.19743294 -38.55873924
OS 40.20205574 -38.5504182
OS 40.20945222 -38.54024804
OS 40.2168487 -38.53007788
OS 40.22516974 -38.51898316
OS 40.23349078 -38.50973756
OS 40.24181182 -38.50234108
OS 40.24273638 -38.50141652
OS 40.24551006 -38.4995674
OS 40.25105742 -38.49679372
OS 40.25660478 -38.49402004
OS 40.26400126 -38.49124636
OS 40.27324686 -38.48847268
OS 40.28249246 -38.48662356
OS 40.29266262 -38.485699
OS 40.29913454 -38.485699
OS 40.30745558 -38.48662356
OE
OB 39.48829542 -38.95999828 I
OS 39.3986131 -38.95999828
OS 39.3986131 -38.87031596
OS 39.48829542 -38.87031596
OS 39.48829542 -38.95999828
OE
OB 38.6404739 -38.95999828 I
OS 38.55171614 -38.95999828
OS 38.30393406 -38.32020276
OS 38.39639006 -38.32020276
OS 38.56281086 -38.78525644
OS 38.56281086 -38.786181
OS 38.56373542 -38.78803012
OS 38.56465998 -38.7908038
OS 38.5665091 -38.79450204
OS 38.56743366 -38.8000494
OS 38.56928278 -38.80559676
OS 38.57390558 -38.81946516
OS 38.57945294 -38.83518268
OS 38.5850003 -38.85274932
OS 38.59609502 -38.88973172
OS 38.59609502 -38.88880716
OS 38.59701958 -38.88695804
OS 38.59794414 -38.88418436
OS 38.5988687 -38.88048612
OS 38.60164238 -38.87031596
OS 38.60626518 -38.85644756
OS 38.61088798 -38.84073004
OS 38.61643534 -38.8231634
OS 38.62290726 -38.8046722
OS 38.63030374 -38.78525644
OS 38.80412102 -38.32020276
OS 38.8901051 -38.32020276
OS 38.6404739 -38.95999828
OE
OB 39.27564662 -38.42745172 I
OS 39.25438174 -38.54671996
OS 39.20538006 -38.54671996
OS 39.1859643 -38.42745172
OS 39.1859643 -38.32020276
OS 39.27564662 -38.32020276
OS 39.27564662 -38.42745172
OE
OB 40.49791494 -38.4117342 I
OS 40.41932734 -38.4117342
OS 40.41932734 -38.32020276
OS 40.49791494 -38.32020276
OS 40.49791494 -38.4117342
OE
OB 39.84517558 -38.48662356 I
OS 39.8516475 -38.48754812
OS 39.8655159 -38.48939724
OS 39.88215798 -38.49309548
OS 39.89972462 -38.49864284
OS 39.91729126 -38.50696388
OS 39.9348579 -38.51713404
OS 39.93578246 -38.51713404
OS 39.93670702 -38.51898316
OS 39.94225438 -38.5226814
OS 39.95057542 -38.53007788
OS 39.96074558 -38.53932348
OS 39.9718403 -38.55134276
OS 39.98293502 -38.56613572
OS 39.99402974 -38.58370236
OS 40.00327534 -38.60311812
OS 40.00327534 -38.60404268
OS 40.0041999 -38.6058918
OS 40.00512446 -38.60866548
OS 40.00697358 -38.61236372
OS 40.0088227 -38.61791108
OS 40.01067182 -38.624383
OS 40.01529462 -38.63917596
OS 40.01991742 -38.65766716
OS 40.02361566 -38.67800748
OS 40.02638934 -38.70112148
OS 40.0273139 -38.72516004
OS 40.0273139 -38.7260846
OS 40.0273139 -38.72793372
OS 40.0273139 -38.73163196
OS 40.0273139 -38.73717932
OS 40.02638934 -38.74365124
OS 40.02638934 -38.75104772
OS 40.02454022 -38.7676898
OS 40.02084198 -38.78803012
OS 40.01621918 -38.809295
OS 40.00974726 -38.83148444
OS 40.00142622 -38.85367388
OS 40.00142622 -38.85459844
OS 40.00050166 -38.85644756
OS 39.99865254 -38.85922124
OS 39.99680342 -38.86291948
OS 39.9903315 -38.87308964
OS 39.98201046 -38.88603348
OS 39.9718403 -38.89990188
OS 39.95889646 -38.91377028
OS 39.9441035 -38.92763868
OS 39.92653686 -38.94058252
OS 39.9256123 -38.94058252
OS 39.92468774 -38.94150708
OS 39.92191406 -38.9433562
OS 39.91821582 -38.94520532
OS 39.90897022 -38.94982812
OS 39.89602638 -38.95537548
OS 39.88030886 -38.96092284
OS 39.86366678 -38.96554564
OS 39.84425102 -38.96924388
OS 39.82483526 -38.97016844
OS 39.81836334 -38.97016844
OS 39.81096686 -38.96924388
OS 39.80172126 -38.96831932
OS 39.79062654 -38.9664702
OS 39.77860726 -38.96369652
OS 39.76658798 -38.95999828
OS 39.7545687 -38.95445092
OS 39.75364414 -38.95352636
OS 39.74902134 -38.95167724
OS 39.74347398 -38.947979
OS 39.7360775 -38.94243164
OS 39.72868102 -38.93688428
OS 39.71943542 -38.9294878
OS 39.71111438 -38.92116676
OS 39.7037179 -38.91192116
OS 39.7037179 -39.1375138
OS 39.6251303 -39.1375138
OS 39.6251303 -38.49586916
OS 39.69632142 -38.49586916
OS 39.69632142 -38.55689012
OS 39.69724598 -38.555041
OS 39.70094422 -38.55134276
OS 39.70556702 -38.54487084
OS 39.7129635 -38.53747436
OS 39.72128454 -38.52822876
OS 39.73053014 -38.51990772
OS 39.74162486 -38.51158668
OS 39.75271958 -38.5041902
OS 39.7545687 -38.50326564
OS 39.75826694 -38.50141652
OS 39.76566342 -38.49864284
OS 39.77490902 -38.4949446
OS 39.78600374 -38.49124636
OS 39.79894758 -38.48847268
OS 39.81374054 -38.48662356
OS 39.83038262 -38.485699
OS 39.84055278 -38.485699
OS 39.84517558 -38.48662356
OE
OB 44.92193454 -38.40988508 I
OS 44.84334694 -38.40988508
OS 44.84334694 -38.32020276
OS 44.92193454 -38.32020276
OS 44.92193454 -38.40988508
OE
OB 45.24553054 -38.48662356 I
OS 45.25385158 -38.48754812
OS 45.26309718 -38.48939724
OS 45.27326734 -38.49124636
OS 45.28528662 -38.49309548
OS 45.31024974 -38.50141652
OS 45.32319358 -38.50603932
OS 45.33613742 -38.51251124
OS 45.34908126 -38.51898316
OS 45.3620251 -38.52822876
OS 45.37404438 -38.53747436
OS 45.38606366 -38.54856908
OS 45.38698822 -38.54949364
OS 45.38883734 -38.55134276
OS 45.39161102 -38.555041
OS 45.39530926 -38.5596638
OS 45.39993206 -38.56613572
OS 45.40547942 -38.57445676
OS 45.41102678 -38.58370236
OS 45.41657414 -38.59387252
OS 45.4221215 -38.60496724
OS 45.42766886 -38.61883564
OS 45.43321622 -38.63270404
OS 45.43783902 -38.64842156
OS 45.44153726 -38.66506364
OS 45.44431094 -38.68263028
OS 45.44616006 -38.70112148
OS 45.44708462 -38.7214618
OS 45.44708462 -38.72238636
OS 45.44708462 -38.72516004
OS 45.44708462 -38.72978284
OS 45.44708462 -38.73625476
OS 45.44616006 -38.74365124
OS 45.4452355 -38.75289684
OS 45.4452355 -38.76214244
OS 45.44338638 -38.7723126
OS 45.4406127 -38.7954266
OS 45.43506534 -38.8185406
OS 45.42859342 -38.8416546
OS 45.41934782 -38.86291948
OS 45.41934782 -38.86384404
OS 45.41842326 -38.8647686
OS 45.41657414 -38.86754228
OS 45.41472502 -38.87124052
OS 45.4082531 -38.88048612
OS 45.39993206 -38.89158084
OS 45.38883734 -38.90452468
OS 45.37496894 -38.91746852
OS 45.35925142 -38.93041236
OS 45.34076022 -38.94243164
OS 45.33983566 -38.94243164
OS 45.3389111 -38.9433562
OS 45.33613742 -38.94520532
OS 45.33151462 -38.94705444
OS 45.32689182 -38.94890356
OS 45.32134446 -38.95075268
OS 45.30747606 -38.95630004
OS 45.29175854 -38.96092284
OS 45.27234278 -38.96554564
OS 45.25200246 -38.96924388
OS 45.22981302 -38.97016844
OS 45.22056742 -38.97016844
OS 45.21317094 -38.96924388
OS 45.2048499 -38.96831932
OS 45.1956043 -38.9664702
OS 45.18450958 -38.96462108
OS 45.17341486 -38.96277196
OS 45.14845174 -38.95537548
OS 45.13458334 -38.94982812
OS 45.1216395 -38.94428076
OS 45.10869566 -38.93688428
OS 45.09575182 -38.92856324
OS 45.08373254 -38.91931764
OS 45.07171326 -38.90822292
OS 45.0707887 -38.90729836
OS 45.06893958 -38.90544924
OS 45.0661659 -38.901751
OS 45.06246766 -38.89620364
OS 45.05784486 -38.88973172
OS 45.05322206 -38.88233524
OS 45.0476747 -38.87308964
OS 45.04212734 -38.86199492
OS 45.03657998 -38.84997564
OS 45.03103262 -38.83610724
OS 45.02640982 -38.82131428
OS 45.02178702 -38.80559676
OS 45.01808878 -38.78803012
OS 45.0153151 -38.76953892
OS 45.01346598 -38.7491986
OS 45.01254142 -38.72793372
OS 45.01254142 -38.7260846
OS 45.01254142 -38.72238636
OS 45.01346598 -38.71591444
OS 45.01346598 -38.70666884
OS 45.01439054 -38.69649868
OS 45.01623966 -38.68355484
OS 45.01808878 -38.670611
OS 45.02178702 -38.65581804
OS 45.02548526 -38.64102508
OS 45.03010806 -38.62530756
OS 45.03565542 -38.60866548
OS 45.0430519 -38.59294796
OS 45.05044838 -38.578155
OS 45.06061854 -38.56336204
OS 45.0707887 -38.54949364
OS 45.08373254 -38.53747436
OS 45.0846571 -38.5365498
OS 45.08650622 -38.53562524
OS 45.09020446 -38.53285156
OS 45.09482726 -38.52915332
OS 45.10037462 -38.52545508
OS 45.1077711 -38.52083228
OS 45.11516758 -38.51620948
OS 45.12441318 -38.51158668
OS 45.13458334 -38.50696388
OS 45.14567806 -38.50234108
OS 45.17064118 -38.49402004
OS 45.19930254 -38.48754812
OS 45.2140955 -38.48662356
OS 45.22981302 -38.485699
OS 45.23905862 -38.485699
OS 45.24553054 -38.48662356
OE
OB 44.92193454 -38.95999828 I
OS 44.84334694 -38.95999828
OS 44.84334694 -38.49586916
OS 44.92193454 -38.49586916
OS 44.92193454 -38.95999828
OE
OB 46.10722046 -38.42745172 I
OS 46.08595558 -38.54671996
OS 46.0369539 -38.54671996
OS 46.01753814 -38.42745172
OS 46.01753814 -38.32020276
OS 46.10722046 -38.32020276
OS 46.10722046 -38.42745172
OE
OB 45.77160518 -38.48662356 I
OS 45.78177534 -38.48754812
OS 45.79379462 -38.48939724
OS 45.80673846 -38.49217092
OS 45.82060686 -38.49586916
OS 45.8335507 -38.50141652
OS 45.83539982 -38.50234108
OS 45.83909806 -38.5041902
OS 45.84556998 -38.50696388
OS 45.85296646 -38.51158668
OS 45.86221206 -38.51713404
OS 45.8705331 -38.52453052
OS 45.87885414 -38.531927
OS 45.88625062 -38.5411726
OS 45.88717518 -38.54209716
OS 45.8890243 -38.5457954
OS 45.89179798 -38.5504182
OS 45.89642078 -38.55689012
OS 45.90011902 -38.56613572
OS 45.90381726 -38.57538132
OS 45.90844006 -38.58647604
OS 45.91121374 -38.59849532
OS 45.91121374 -38.59941988
OS 45.9121383 -38.60311812
OS 45.91306286 -38.60866548
OS 45.91398742 -38.61606196
OS 45.91398742 -38.62715668
OS 45.91491198 -38.64010052
OS 45.91583654 -38.65581804
OS 45.91583654 -38.6752338
OS 45.91583654 -38.95999828
OS 45.83724894 -38.95999828
OS 45.83724894 -38.67893204
OS 45.83724894 -38.67800748
OS 45.83724894 -38.67708292
OS 45.83724894 -38.670611
OS 45.83724894 -38.66228996
OS 45.83632438 -38.6521198
OS 45.83539982 -38.64010052
OS 45.8335507 -38.62808124
OS 45.83077702 -38.61698652
OS 45.82800334 -38.60681636
OS 45.82800334 -38.6058918
OS 45.82615422 -38.60311812
OS 45.82338054 -38.59849532
OS 45.82060686 -38.59294796
OS 45.81598406 -38.5874006
OS 45.8104367 -38.58092868
OS 45.80304022 -38.57445676
OS 45.79471918 -38.5689094
OS 45.79379462 -38.56798484
OS 45.79102094 -38.56613572
OS 45.78547358 -38.5642866
OS 45.77900166 -38.56151292
OS 45.77160518 -38.55873924
OS 45.76235958 -38.55596556
OS 45.75126486 -38.555041
OS 45.74017014 -38.55411644
OS 45.73554734 -38.55411644
OS 45.7318491 -38.555041
OS 45.7226035 -38.55596556
OS 45.71058422 -38.55781468
OS 45.69764038 -38.56243748
OS 45.68284742 -38.56798484
OS 45.66805446 -38.57538132
OS 45.65418606 -38.58647604
OS 45.65233694 -38.58832516
OS 45.6486387 -38.59294796
OS 45.64586502 -38.5966462
OS 45.64309134 -38.601269
OS 45.6393931 -38.60681636
OS 45.63661942 -38.61328828
OS 45.63292118 -38.62068476
OS 45.62922294 -38.62993036
OS 45.62644926 -38.64010052
OS 45.62367558 -38.65119524
OS 45.62182646 -38.66321452
OS 45.61997734 -38.67615836
OS 45.61812822 -38.69187588
OS 45.61812822 -38.7075934
OS 45.61812822 -38.95999828
OS 45.53954062 -38.95999828
OS 45.53954062 -38.49586916
OS 45.60980718 -38.49586916
OS 45.60980718 -38.56243748
OS 45.61073174 -38.56151292
OS 45.61258086 -38.55873924
OS 45.61535454 -38.555041
OS 45.61905278 -38.5504182
OS 45.62460014 -38.54487084
OS 45.63107206 -38.53839892
OS 45.63846854 -38.53100244
OS 45.64771414 -38.52360596
OS 45.65695974 -38.51713404
OS 45.66805446 -38.50973756
OS 45.68007374 -38.50326564
OS 45.69301758 -38.49771828
OS 45.70781054 -38.49309548
OS 45.7226035 -38.48939724
OS 45.73924558 -38.48662356
OS 45.75681222 -38.485699
OS 45.7642087 -38.485699
OS 45.77160518 -38.48662356
OE
OB 44.2756671 -38.95999828 I
OS 44.1970795 -38.95999828
OS 44.1970795 -38.49586916
OS 44.2756671 -38.49586916
OS 44.2756671 -38.95999828
OE
OB 43.4574315 -38.48662356 I
OS 43.46482798 -38.48754812
OS 43.47407358 -38.48939724
OS 43.48424374 -38.49124636
OS 43.49626302 -38.49402004
OS 43.50735774 -38.49679372
OS 43.52030158 -38.50141652
OS 43.53232086 -38.50603932
OS 43.5452647 -38.51251124
OS 43.55820854 -38.51990772
OS 43.57115238 -38.52822876
OS 43.58317166 -38.53839892
OS 43.59426638 -38.54949364
OS 43.59519094 -38.5504182
OS 43.59704006 -38.55226732
OS 43.59981374 -38.55596556
OS 43.60351198 -38.56151292
OS 43.60813478 -38.56798484
OS 43.61275758 -38.57538132
OS 43.61830494 -38.58462692
OS 43.6238523 -38.59572164
OS 43.62939966 -38.60774092
OS 43.63494702 -38.62068476
OS 43.63956982 -38.63547772
OS 43.64419262 -38.65119524
OS 43.64789086 -38.66876188
OS 43.65066454 -38.68725308
OS 43.65251366 -38.70666884
OS 43.65343822 -38.72793372
OS 43.65343822 -38.72885828
OS 43.65343822 -38.73255652
OS 43.65343822 -38.73902844
OS 43.65251366 -38.74827404
OS 43.30580366 -38.74827404
OS 43.30580366 -38.7491986
OS 43.30580366 -38.75197228
OS 43.30672822 -38.75567052
OS 43.30672822 -38.76121788
OS 43.30765278 -38.7676898
OS 43.3095019 -38.77508628
OS 43.31227558 -38.79172836
OS 43.31782294 -38.81021956
OS 43.32521942 -38.83055988
OS 43.33538958 -38.84905108
OS 43.34833342 -38.86569316
OS 43.34925798 -38.86569316
OS 43.35018254 -38.86754228
OS 43.3557299 -38.87216508
OS 43.36405094 -38.878637
OS 43.37514566 -38.88510892
OS 43.38993862 -38.8925054
OS 43.4065807 -38.89897732
OS 43.4250719 -38.90360012
OS 43.43524206 -38.90452468
OS 43.44633678 -38.90544924
OS 43.45373326 -38.90544924
OS 43.4620543 -38.90452468
OS 43.47222446 -38.90267556
OS 43.48331918 -38.89990188
OS 43.49626302 -38.89620364
OS 43.5082823 -38.89065628
OS 43.52030158 -38.8832598
OS 43.52122614 -38.88233524
OS 43.52584894 -38.878637
OS 43.5313963 -38.87308964
OS 43.53786822 -38.86569316
OS 43.5452647 -38.855523
OS 43.55358574 -38.84257916
OS 43.56190678 -38.8277862
OS 43.56930326 -38.81021956
OS 43.65066454 -38.82038972
OS 43.65066454 -38.82131428
OS 43.64973998 -38.8231634
OS 43.64881542 -38.82686164
OS 43.6469663 -38.832409
OS 43.64419262 -38.83795636
OS 43.64141894 -38.84535284
OS 43.63402246 -38.86107036
OS 43.62477686 -38.878637
OS 43.61183302 -38.8971282
OS 43.59704006 -38.91469484
OS 43.57854886 -38.93133692
OS 43.5776243 -38.93133692
OS 43.57577518 -38.93318604
OS 43.5730015 -38.93503516
OS 43.56930326 -38.93780884
OS 43.5637559 -38.94058252
OS 43.55820854 -38.9433562
OS 43.55081206 -38.94705444
OS 43.54249102 -38.95075268
OS 43.53324542 -38.95445092
OS 43.52399982 -38.95814916
OS 43.50088582 -38.96369652
OS 43.47499814 -38.96831932
OS 43.44633678 -38.97016844
OS 43.43616662 -38.97016844
OS 43.4296947 -38.96924388
OS 43.42137366 -38.96831932
OS 43.4112035 -38.9664702
OS 43.40010878 -38.96462108
OS 43.3880895 -38.96277196
OS 43.36220182 -38.95537548
OS 43.34833342 -38.94982812
OS 43.33538958 -38.94428076
OS 43.32152118 -38.93688428
OS 43.30857734 -38.92856324
OS 43.29655806 -38.91931764
OS 43.28453878 -38.90822292
OS 43.28361422 -38.90729836
OS 43.2817651 -38.90544924
OS 43.27899142 -38.901751
OS 43.27529318 -38.89620364
OS 43.27067038 -38.88973172
OS 43.26604758 -38.88233524
OS 43.26050022 -38.87308964
OS 43.25495286 -38.86291948
OS 43.2494055 -38.8509002
OS 43.24385814 -38.83795636
OS 43.23923534 -38.8231634
OS 43.23461254 -38.80744588
OS 43.2309143 -38.7908038
OS 43.22814062 -38.7723126
OS 43.2262915 -38.75289684
OS 43.22536694 -38.73255652
OS 43.22536694 -38.73163196
OS 43.22536694 -38.72700916
OS 43.22536694 -38.7214618
OS 43.2262915 -38.71314076
OS 43.22721606 -38.7029706
OS 43.22814062 -38.69187588
OS 43.22998974 -38.67893204
OS 43.23276342 -38.6659882
OS 43.2401599 -38.63640228
OS 43.2447827 -38.62160932
OS 43.25033006 -38.6058918
OS 43.25772654 -38.59109884
OS 43.26604758 -38.57723044
OS 43.27529318 -38.56336204
OS 43.28546334 -38.5504182
OS 43.2863879 -38.54949364
OS 43.28823702 -38.54764452
OS 43.29193526 -38.54487084
OS 43.29655806 -38.54024804
OS 43.30210542 -38.53562524
OS 43.3095019 -38.53007788
OS 43.31782294 -38.52360596
OS 43.3279931 -38.5180586
OS 43.33816326 -38.51158668
OS 43.35018254 -38.50603932
OS 43.36312638 -38.50049196
OS 43.37699478 -38.49586916
OS 43.39178774 -38.49124636
OS 43.40750526 -38.48847268
OS 43.42414734 -38.48662356
OS 43.44171398 -38.485699
OS 43.45095958 -38.485699
OS 43.4574315 -38.48662356
OE
OB 43.13938286 -38.48662356 I
OS 43.14955302 -38.48847268
OS 43.1615723 -38.49217092
OS 43.17451614 -38.49679372
OS 43.1893091 -38.50326564
OS 43.20502662 -38.51158668
OS 43.17636526 -38.58370236
OS 43.1754407 -38.5827778
OS 43.17174246 -38.58092868
OS 43.1661951 -38.578155
OS 43.15879862 -38.57538132
OS 43.15047758 -38.57260764
OS 43.14030742 -38.56983396
OS 43.13013726 -38.56798484
OS 43.1199671 -38.56706028
OS 43.1153443 -38.56706028
OS 43.1107215 -38.56798484
OS 43.10424958 -38.5689094
OS 43.09777766 -38.57075852
OS 43.08945662 -38.5735322
OS 43.08113558 -38.57723044
OS 43.0737391 -38.5827778
OS 43.07281454 -38.58370236
OS 43.07004086 -38.58555148
OS 43.06726718 -38.58924972
OS 43.06264438 -38.59387252
OS 43.05802158 -38.60034444
OS 43.05339878 -38.60774092
OS 43.04877598 -38.61606196
OS 43.04507774 -38.62623212
OS 43.04415318 -38.62808124
OS 43.04322862 -38.6336286
OS 43.0413795 -38.64194964
OS 43.03860582 -38.65304436
OS 43.03583214 -38.66691276
OS 43.03398302 -38.68263028
OS 43.03305846 -38.69927236
OS 43.0321339 -38.71776356
OS 43.0321339 -38.95999828
OS 42.9535463 -38.95999828
OS 42.9535463 -38.49586916
OS 43.02473742 -38.49586916
OS 43.02473742 -38.56613572
OS 43.02566198 -38.56521116
OS 43.02936022 -38.55873924
OS 43.03398302 -38.5504182
OS 43.0413795 -38.54024804
OS 43.04877598 -38.53007788
OS 43.05709702 -38.51898316
OS 43.06541806 -38.50973756
OS 43.0737391 -38.50234108
OS 43.07466366 -38.50141652
OS 43.07743734 -38.4995674
OS 43.0829847 -38.49679372
OS 43.08853206 -38.49402004
OS 43.09592854 -38.49124636
OS 43.10517414 -38.48847268
OS 43.11441974 -38.48662356
OS 43.1245899 -38.485699
OS 43.13106182 -38.485699
OS 43.13938286 -38.48662356
OE
OB 43.95022198 -38.95999828 I
OS 43.87533262 -38.95999828
OS 43.70059078 -38.49586916
OS 43.78380118 -38.49586916
OS 43.88365366 -38.77416172
OS 43.88365366 -38.77508628
OS 43.88457822 -38.77601084
OS 43.88550278 -38.77878452
OS 43.88642734 -38.7815582
OS 43.88920102 -38.7908038
OS 43.89289926 -38.80282308
OS 43.89752206 -38.81669148
OS 43.90306942 -38.832409
OS 43.90769222 -38.84997564
OS 43.91323958 -38.86754228
OS 43.91416414 -38.86569316
OS 43.9150887 -38.86107036
OS 43.91786238 -38.85367388
OS 43.92063606 -38.84257916
OS 43.92525886 -38.83055988
OS 43.92988166 -38.81484236
OS 43.93635358 -38.79820028
OS 43.9428255 -38.77970908
OS 44.04545166 -38.49586916
OS 44.12681294 -38.49586916
OS 43.95022198 -38.95999828
OE
OB 44.2756671 -38.40988508 I
OS 44.1970795 -38.40988508
OS 44.1970795 -38.32020276
OS 44.2756671 -38.32020276
OS 44.2756671 -38.40988508
OE
OB 44.5669035 -38.48662356 I
OS 44.5807719 -38.48754812
OS 44.59556486 -38.48939724
OS 44.61128238 -38.49309548
OS 44.62792446 -38.49679372
OS 44.64364198 -38.50234108
OS 44.64456654 -38.50234108
OS 44.6454911 -38.50326564
OS 44.6501139 -38.50511476
OS 44.65751038 -38.508813
OS 44.66675598 -38.5134358
OS 44.67692614 -38.51990772
OS 44.6870963 -38.5273042
OS 44.6963419 -38.53562524
OS 44.70466294 -38.54487084
OS 44.7055875 -38.5457954
OS 44.70743662 -38.54949364
OS 44.71113486 -38.55596556
OS 44.71575766 -38.56336204
OS 44.72038046 -38.57445676
OS 44.72500326 -38.58647604
OS 44.7287015 -38.60034444
OS 44.73239974 -38.61606196
OS 44.65566126 -38.62623212
OS 44.65566126 -38.624383
OS 44.6547367 -38.62068476
OS 44.65288758 -38.61421284
OS 44.6501139 -38.6058918
OS 44.6454911 -38.59757076
OS 44.63994374 -38.58832516
OS 44.63347182 -38.57907956
OS 44.62422622 -38.57075852
OS 44.62330166 -38.56983396
OS 44.61960342 -38.56798484
OS 44.61405606 -38.5642866
OS 44.60573502 -38.56058836
OS 44.59648942 -38.55689012
OS 44.58447014 -38.55319188
OS 44.56967718 -38.55134276
OS 44.55395966 -38.5504182
OS 44.54471406 -38.5504182
OS 44.53546846 -38.55134276
OS 44.52344918 -38.55226732
OS 44.5114299 -38.555041
OS 44.49848606 -38.55781468
OS 44.48646678 -38.56243748
OS 44.47629662 -38.5689094
OS 44.47537206 -38.56983396
OS 44.47259838 -38.57168308
OS 44.46890014 -38.57538132
OS 44.4652019 -38.58092868
OS 44.4605791 -38.58647604
OS 44.45688086 -38.59387252
OS 44.45410718 -38.60219356
OS 44.45318262 -38.6105146
OS 44.45318262 -38.61143916
OS 44.45318262 -38.61328828
OS 44.45410718 -38.61606196
OS 44.45410718 -38.6197602
OS 44.45688086 -38.6290058
OS 44.46242822 -38.6382514
OS 44.46335278 -38.63917596
OS 44.46427734 -38.64010052
OS 44.46612646 -38.6428742
OS 44.4698247 -38.64564788
OS 44.47352294 -38.64842156
OS 44.4790703 -38.6521198
OS 44.48554222 -38.65489348
OS 44.4929387 -38.65859172
OS 44.49386326 -38.65859172
OS 44.49571238 -38.65951628
OS 44.49941062 -38.66044084
OS 44.50588254 -38.66321452
OS 44.51512814 -38.6659882
OS 44.52714742 -38.66876188
OS 44.5345439 -38.67153556
OS 44.54286494 -38.67338468
OS 44.55211054 -38.67615836
OS 44.5622807 -38.67893204
OS 44.56320526 -38.67893204
OS 44.56597894 -38.6798566
OS 44.57060174 -38.68078116
OS 44.5761491 -38.68263028
OS 44.58262102 -38.6844794
OS 44.59094206 -38.68632852
OS 44.6085087 -38.69187588
OS 44.62792446 -38.69742324
OS 44.64734022 -38.70389516
OS 44.66490686 -38.71036708
OS 44.67230334 -38.71314076
OS 44.67877526 -38.71591444
OS 44.68062438 -38.716839
OS 44.68432262 -38.71868812
OS 44.68986998 -38.7214618
OS 44.69819102 -38.7260846
OS 44.70651206 -38.73163196
OS 44.7148331 -38.73902844
OS 44.72315414 -38.74734948
OS 44.73055062 -38.75659508
OS 44.73147518 -38.75751964
OS 44.7333243 -38.76121788
OS 44.73702254 -38.76676524
OS 44.74072078 -38.77508628
OS 44.74349446 -38.78525644
OS 44.7471927 -38.79635116
OS 44.74904182 -38.809295
OS 44.74996638 -38.82408796
OS 44.74996638 -38.82593708
OS 44.74996638 -38.83055988
OS 44.74904182 -38.83795636
OS 44.7471927 -38.84812652
OS 44.74441902 -38.85922124
OS 44.73979622 -38.87124052
OS 44.73424886 -38.88510892
OS 44.72685238 -38.89805276
OS 44.72592782 -38.89990188
OS 44.72222958 -38.90360012
OS 44.71760678 -38.91007204
OS 44.7102103 -38.91746852
OS 44.70004014 -38.92578956
OS 44.68894542 -38.93503516
OS 44.67600158 -38.9433562
OS 44.66028406 -38.95167724
OS 44.6593595 -38.95167724
OS 44.65843494 -38.9526018
OS 44.65288758 -38.95445092
OS 44.64364198 -38.9572246
OS 44.6316227 -38.96092284
OS 44.61682974 -38.96462108
OS 44.60018766 -38.96739476
OS 44.58262102 -38.96924388
OS 44.5622807 -38.97016844
OS 44.55395966 -38.97016844
OS 44.54748774 -38.96924388
OS 44.54009126 -38.96924388
OS 44.53084566 -38.96831932
OS 44.52160006 -38.96739476
OS 44.5114299 -38.96554564
OS 44.48924046 -38.96092284
OS 44.46612646 -38.95445092
OS 44.44393702 -38.94520532
OS 44.43376686 -38.93965796
OS 44.42452126 -38.93318604
OS 44.4235967 -38.93226148
OS 44.42267214 -38.93133692
OS 44.41712478 -38.92578956
OS 44.40880374 -38.91746852
OS 44.39955814 -38.90452468
OS 44.38938798 -38.88880716
OS 44.37921782 -38.87031596
OS 44.37089678 -38.84720196
OS 44.36442486 -38.82131428
OS 44.4420879 -38.809295
OS 44.4420879 -38.81021956
OS 44.4420879 -38.81114412
OS 44.44393702 -38.81669148
OS 44.44578614 -38.82593708
OS 44.44948438 -38.83610724
OS 44.45410718 -38.84720196
OS 44.45965454 -38.85922124
OS 44.46797558 -38.87124052
OS 44.47814574 -38.88141068
OS 44.47999486 -38.88233524
OS 44.4836931 -38.88510892
OS 44.49108958 -38.88880716
OS 44.50033518 -38.89342996
OS 44.51235446 -38.89805276
OS 44.52622286 -38.901751
OS 44.54286494 -38.90452468
OS 44.5622807 -38.90544924
OS 44.5715263 -38.90544924
OS 44.5807719 -38.90452468
OS 44.59279118 -38.90267556
OS 44.60573502 -38.89990188
OS 44.61960342 -38.89620364
OS 44.6316227 -38.89158084
OS 44.64271742 -38.88418436
OS 44.64364198 -38.8832598
OS 44.64734022 -38.88048612
OS 44.65103846 -38.87586332
OS 44.65658582 -38.8693914
OS 44.66120862 -38.86199492
OS 44.66583142 -38.85274932
OS 44.6686051 -38.84350372
OS 44.66952966 -38.832409
OS 44.66952966 -38.83148444
OS 44.66952966 -38.8277862
OS 44.6686051 -38.8231634
OS 44.66675598 -38.81669148
OS 44.6639823 -38.81021956
OS 44.6593595 -38.80374764
OS 44.65381214 -38.79635116
OS 44.6454911 -38.7908038
OS 44.64456654 -38.78987924
OS 44.64179286 -38.78895468
OS 44.63717006 -38.786181
OS 44.62977358 -38.78340732
OS 44.61867886 -38.77970908
OS 44.61220694 -38.7769354
OS 44.60481046 -38.77508628
OS 44.59648942 -38.7723126
OS 44.58724382 -38.76953892
OS 44.57707366 -38.76676524
OS 44.56505438 -38.76399156
OS 44.56412982 -38.76399156
OS 44.56135614 -38.763067
OS 44.55673334 -38.76214244
OS 44.55118598 -38.76029332
OS 44.5437895 -38.7584442
OS 44.53546846 -38.75567052
OS 44.51790182 -38.75104772
OS 44.4975615 -38.7445758
OS 44.47814574 -38.73902844
OS 44.45965454 -38.73255652
OS 44.4513335 -38.72885828
OS 44.44486158 -38.7260846
OS 44.44301246 -38.72516004
OS 44.43931422 -38.72331092
OS 44.43376686 -38.71961268
OS 44.42637038 -38.71498988
OS 44.41804934 -38.70851796
OS 44.4097283 -38.70112148
OS 44.40140726 -38.69280044
OS 44.39401078 -38.68263028
OS 44.39308622 -38.68170572
OS 44.3912371 -38.67800748
OS 44.38846342 -38.67153556
OS 44.38568974 -38.66413908
OS 44.38291606 -38.65489348
OS 44.38014238 -38.64379876
OS 44.37829326 -38.63270404
OS 44.3773687 -38.6197602
OS 44.3773687 -38.61791108
OS 44.3773687 -38.61421284
OS 44.37829326 -38.60866548
OS 44.37921782 -38.60034444
OS 44.38106694 -38.5920234
OS 44.38291606 -38.58185324
OS 44.3866143 -38.57260764
OS 44.3912371 -38.56243748
OS 44.39216166 -38.56151292
OS 44.39401078 -38.55781468
OS 44.39678446 -38.55319188
OS 44.40140726 -38.54671996
OS 44.40695462 -38.54024804
OS 44.41342654 -38.531927
OS 44.42082302 -38.52453052
OS 44.43006862 -38.5180586
OS 44.43099318 -38.51713404
OS 44.43376686 -38.51620948
OS 44.4374651 -38.5134358
OS 44.44301246 -38.51066212
OS 44.45040894 -38.50696388
OS 44.45872998 -38.50326564
OS 44.46890014 -38.4995674
OS 44.47999486 -38.49586916
OS 44.48184398 -38.4949446
OS 44.48554222 -38.49402004
OS 44.49201414 -38.49217092
OS 44.50033518 -38.4903218
OS 44.51050534 -38.48847268
OS 44.52160006 -38.48754812
OS 44.5345439 -38.485699
OS 44.55673334 -38.485699
OS 44.5669035 -38.48662356
OE
OB 33.15968222 -38.32112732 I
OS 33.17539974 -38.32205188
OS 33.19204182 -38.32297644
OS 33.20775934 -38.32482556
OS 33.22162774 -38.32667468
OS 33.22347686 -38.32667468
OS 33.22994878 -38.3285238
OS 33.23826982 -38.33037292
OS 33.24936454 -38.3331466
OS 33.26138382 -38.3377694
OS 33.27432766 -38.34331676
OS 33.28819606 -38.34978868
OS 33.30021534 -38.35718516
OS 33.30206446 -38.35810972
OS 33.3057627 -38.3608834
OS 33.31131006 -38.36643076
OS 33.31870654 -38.37290268
OS 33.32702758 -38.38122372
OS 33.33534862 -38.39231844
OS 33.34459422 -38.40433772
OS 33.3519907 -38.41820612
OS 33.35291526 -38.42005524
OS 33.35476438 -38.42467804
OS 33.35846262 -38.43299908
OS 33.36216086 -38.4440938
OS 33.36493454 -38.45703764
OS 33.36863278 -38.4718306
OS 33.3704819 -38.48847268
OS 33.37140646 -38.50603932
OS 33.37140646 -38.50696388
OS 33.37140646 -38.50973756
OS 33.37140646 -38.5134358
OS 33.3704819 -38.51990772
OS 33.36955734 -38.52637964
OS 33.36863278 -38.53470068
OS 33.36678366 -38.54394628
OS 33.36493454 -38.55411644
OS 33.35846262 -38.57538132
OS 33.35476438 -38.58647604
OS 33.34921702 -38.59849532
OS 33.3427451 -38.6105146
OS 33.33627318 -38.62160932
OS 33.32795214 -38.63270404
OS 33.31870654 -38.64379876
OS 33.31778198 -38.64472332
OS 33.31593286 -38.64657244
OS 33.31315918 -38.64934612
OS 33.30853638 -38.6521198
OS 33.30298902 -38.6567426
OS 33.29559254 -38.6613654
OS 33.28634694 -38.66691276
OS 33.27617678 -38.67153556
OS 33.2641575 -38.67708292
OS 33.2502891 -38.68263028
OS 33.23549614 -38.68725308
OS 33.2179295 -38.69095132
OS 33.1994383 -38.69464956
OS 33.17909798 -38.69742324
OS 33.15598398 -38.69927236
OS 33.13194542 -38.70019692
OS 32.9682983 -38.70019692
OS 32.9682983 -38.95999828
OS 32.88323878 -38.95999828
OS 32.88323878 -38.32020276
OS 33.14581382 -38.32020276
OS 33.15968222 -38.32112732
OE
OB 32.75195126 -38.98403684 I
OS 32.75195126 -38.9849614
OS 32.75195126 -38.98773508
OS 32.75195126 -38.99235788
OS 32.75195126 -38.99790524
OS 32.7510267 -39.00530172
OS 32.7510267 -39.0126982
OS 32.74917758 -39.0311894
OS 32.7464039 -39.05060516
OS 32.74270566 -39.07094548
OS 32.7371583 -39.08851212
OS 32.73346006 -39.09683316
OS 32.72976182 -39.10330508
OS 32.72976182 -39.10422964
OS 32.72883726 -39.1051542
OS 32.72421446 -39.109777
OS 32.71681798 -39.11717348
OS 32.70757238 -39.12549452
OS 32.69462854 -39.13381556
OS 32.67798646 -39.14028748
OS 32.6585707 -39.14583484
OS 32.64747598 -39.1467594
OS 32.6354567 -39.14768396
OS 32.62990934 -39.14768396
OS 32.62436198 -39.1467594
OS 32.61604094 -39.1467594
OS 32.60679534 -39.14583484
OS 32.59662518 -39.14398572
OS 32.57443574 -39.13843836
OS 32.5892287 -39.07187004
OS 32.59015326 -39.07187004
OS 32.59292694 -39.0727946
OS 32.59754974 -39.07371916
OS 32.60217254 -39.07464372
OS 32.61419182 -39.0774174
OS 32.61973918 -39.07834196
OS 32.62898478 -39.07834196
OS 32.63360758 -39.0774174
OS 32.63915494 -39.07649284
OS 32.6447023 -39.07464372
OS 32.65024966 -39.07094548
OS 32.65672158 -39.06724724
OS 32.66134438 -39.06169988
OS 32.66226894 -39.06077532
OS 32.6631935 -39.05800164
OS 32.66504262 -39.05337884
OS 32.6678163 -39.04598236
OS 32.66966542 -39.0358122
OS 32.67058998 -39.02841572
OS 32.67151454 -39.0219438
OS 32.6724391 -39.01362276
OS 32.6724391 -39.0034526
OS 32.67336366 -38.99328244
OS 32.67336366 -38.98218772
OS 32.67336366 -38.49586916
OS 32.75195126 -38.49586916
OS 32.75195126 -38.98403684
OE
OB 33.77174094 -38.3100326 I
OS 33.78006198 -38.31095716
OS 33.79023214 -38.31188172
OS 33.8004023 -38.31280628
OS 33.81242158 -38.31557996
OS 33.8373847 -38.32112732
OS 33.8651215 -38.32944836
OS 33.8789899 -38.33499572
OS 33.89193374 -38.34146764
OS 33.90487758 -38.34978868
OS 33.91782142 -38.35810972
OS 33.91874598 -38.35903428
OS 33.9205951 -38.35995884
OS 33.92429334 -38.36273252
OS 33.92891614 -38.36735532
OS 33.93353894 -38.37197812
OS 33.94001086 -38.37845004
OS 33.94648278 -38.38584652
OS 33.95387926 -38.393243
OS 33.96127574 -38.4024886
OS 33.96867222 -38.41358332
OS 33.97699326 -38.42467804
OS 33.98438974 -38.43669732
OS 33.99086166 -38.45056572
OS 33.99825814 -38.46443412
OS 34.0038055 -38.47922708
OS 34.00935286 -38.49586916
OS 33.92614246 -38.51528492
OS 33.92614246 -38.51436036
OS 33.9252179 -38.51251124
OS 33.92336878 -38.508813
OS 33.92151966 -38.5041902
OS 33.91967054 -38.49864284
OS 33.91689686 -38.49124636
OS 33.90950038 -38.4764534
OS 33.90025478 -38.45981132
OS 33.88916006 -38.44316924
OS 33.87529166 -38.42745172
OS 33.8604987 -38.41358332
OS 33.85864958 -38.4117342
OS 33.85310222 -38.40803596
OS 33.84385662 -38.40341316
OS 33.83183734 -38.39694124
OS 33.81611982 -38.39139388
OS 33.79855318 -38.38584652
OS 33.7772883 -38.38214828
OS 33.7541743 -38.38122372
OS 33.74677782 -38.38122372
OS 33.74215502 -38.38214828
OS 33.7356831 -38.38214828
OS 33.72828662 -38.38307284
OS 33.71071998 -38.38584652
OS 33.69130422 -38.38954476
OS 33.6709639 -38.39601668
OS 33.64969902 -38.40526228
OS 33.63028326 -38.41728156
OS 33.6293587 -38.41728156
OS 33.62843414 -38.41913068
OS 33.62196222 -38.42375348
OS 33.61364118 -38.43114996
OS 33.60347102 -38.44224468
OS 33.59145174 -38.45611308
OS 33.58035702 -38.4718306
OS 33.57018686 -38.49124636
OS 33.56094126 -38.51251124
OS 33.56094126 -38.5134358
OS 33.5600167 -38.51528492
OS 33.55909214 -38.5180586
OS 33.55816758 -38.5226814
OS 33.55631846 -38.52822876
OS 33.55446934 -38.53470068
OS 33.55169566 -38.5504182
OS 33.54799742 -38.5689094
OS 33.54429918 -38.58924972
OS 33.54245006 -38.61143916
OS 33.5415255 -38.63547772
OS 33.5415255 -38.63640228
OS 33.5415255 -38.63917596
OS 33.5415255 -38.64379876
OS 33.5415255 -38.64934612
OS 33.54245006 -38.65581804
OS 33.54245006 -38.66413908
OS 33.54337462 -38.67338468
OS 33.54429918 -38.68355484
OS 33.54707286 -38.70574428
OS 33.55169566 -38.72978284
OS 33.55724302 -38.7538214
OS 33.5646395 -38.77785996
OS 33.5646395 -38.77878452
OS 33.56556406 -38.78063364
OS 33.56741318 -38.78340732
OS 33.5692623 -38.78803012
OS 33.57480966 -38.79912484
OS 33.5831307 -38.81206868
OS 33.59330086 -38.82686164
OS 33.6062447 -38.84257916
OS 33.62103766 -38.85644756
OS 33.6386043 -38.8693914
OS 33.63952886 -38.8693914
OS 33.64137798 -38.87031596
OS 33.64415166 -38.87216508
OS 33.6478499 -38.8740142
OS 33.6524727 -38.87586332
OS 33.65802006 -38.878637
OS 33.6709639 -38.88418436
OS 33.68760598 -38.88973172
OS 33.70609718 -38.89435452
OS 33.7264375 -38.89805276
OS 33.74770238 -38.89897732
OS 33.7541743 -38.89897732
OS 33.75972166 -38.89805276
OS 33.76619358 -38.89805276
OS 33.7726655 -38.8971282
OS 33.78930758 -38.89342996
OS 33.80872334 -38.88880716
OS 33.8281391 -38.88141068
OS 33.84847942 -38.87124052
OS 33.85864958 -38.86569316
OS 33.86789518 -38.85829668
OS 33.86881974 -38.85737212
OS 33.8697443 -38.85644756
OS 33.87251798 -38.85367388
OS 33.87621622 -38.8509002
OS 33.87991446 -38.8462774
OS 33.88453726 -38.84073004
OS 33.89008462 -38.83518268
OS 33.89470742 -38.8277862
OS 33.90025478 -38.81946516
OS 33.9067267 -38.81021956
OS 33.91227406 -38.80097396
OS 33.91782142 -38.78987924
OS 33.92244422 -38.77785996
OS 33.92706702 -38.76491612
OS 33.93168982 -38.75104772
OS 33.93538806 -38.73625476
OS 34.02044758 -38.75751964
OS 34.02044758 -38.7584442
OS 34.01952302 -38.76214244
OS 34.0176739 -38.7676898
OS 34.01490022 -38.77508628
OS 34.01212654 -38.78340732
OS 34.0084283 -38.79357748
OS 34.0038055 -38.8046722
OS 33.99825814 -38.81669148
OS 33.9853143 -38.84257916
OS 33.96867222 -38.86846684
OS 33.95850206 -38.88141068
OS 33.9483319 -38.89435452
OS 33.93723718 -38.90544924
OS 33.92429334 -38.91654396
OS 33.92336878 -38.91746852
OS 33.92151966 -38.91931764
OS 33.91689686 -38.92116676
OS 33.91227406 -38.924865
OS 33.90487758 -38.9294878
OS 33.8974811 -38.9341106
OS 33.88731094 -38.9387334
OS 33.87714078 -38.9433562
OS 33.8651215 -38.94890356
OS 33.85217766 -38.95352636
OS 33.83830926 -38.95814916
OS 33.8235163 -38.96277196
OS 33.80779878 -38.9664702
OS 33.7911567 -38.96831932
OS 33.77359006 -38.97016844
OS 33.75509886 -38.971093
OS 33.7449287 -38.971093
OS 33.73753222 -38.97016844
OS 33.72921118 -38.97016844
OS 33.71904102 -38.96924388
OS 33.7079463 -38.96739476
OS 33.69500246 -38.96554564
OS 33.66819022 -38.96092284
OS 33.64045342 -38.95352636
OS 33.61271662 -38.9433562
OS 33.59977278 -38.93688428
OS 33.58682894 -38.9294878
OS 33.58590438 -38.92856324
OS 33.58405526 -38.92763868
OS 33.58035702 -38.924865
OS 33.57665878 -38.92116676
OS 33.57111142 -38.91746852
OS 33.5646395 -38.91192116
OS 33.55724302 -38.90544924
OS 33.54984654 -38.89805276
OS 33.54245006 -38.88973172
OS 33.53412902 -38.88141068
OS 33.51748694 -38.8601458
OS 33.50176942 -38.83518268
OS 33.48790102 -38.80744588
OS 33.48790102 -38.80652132
OS 33.4860519 -38.80374764
OS 33.48512734 -38.79912484
OS 33.48235366 -38.79357748
OS 33.48050454 -38.786181
OS 33.47773086 -38.7769354
OS 33.47403262 -38.76676524
OS 33.47125894 -38.75567052
OS 33.46848526 -38.74365124
OS 33.46478702 -38.72978284
OS 33.46016422 -38.70112148
OS 33.45646598 -38.66876188
OS 33.45461686 -38.63547772
OS 33.45461686 -38.63455316
OS 33.45461686 -38.63085492
OS 33.45461686 -38.62530756
OS 33.45554142 -38.61883564
OS 33.45554142 -38.60959004
OS 33.45646598 -38.60034444
OS 33.45739054 -38.58832516
OS 33.45923966 -38.57630588
OS 33.46386246 -38.54949364
OS 33.47033438 -38.51990772
OS 33.47957998 -38.4903218
OS 33.49252382 -38.46166044
OS 33.49344838 -38.46073588
OS 33.49437294 -38.4579622
OS 33.49622206 -38.45426396
OS 33.4999203 -38.44964116
OS 33.50361854 -38.44316924
OS 33.50824134 -38.43577276
OS 33.52026062 -38.41913068
OS 33.53597814 -38.40063948
OS 33.55446934 -38.38214828
OS 33.57573422 -38.36365708
OS 33.60069734 -38.34793956
OS 33.6016219 -38.347015
OS 33.60439558 -38.34609044
OS 33.60809382 -38.34424132
OS 33.61271662 -38.34146764
OS 33.6201131 -38.33869396
OS 33.62750958 -38.33592028
OS 33.63675518 -38.33222204
OS 33.64692534 -38.3285238
OS 33.65802006 -38.32482556
OS 33.67003934 -38.32112732
OS 33.69592702 -38.31557996
OS 33.72551294 -38.31095716
OS 33.75602342 -38.30910804
OS 33.76526902 -38.30910804
OS 33.77174094 -38.3100326
OE
OB 35.15858094 -39.1375138 I
OS 34.63805366 -39.1375138
OS 34.63805366 -39.08111564
OS 35.15858094 -39.08111564
OS 35.15858094 -39.1375138
OE
OB 34.37917686 -38.32112732 I
OS 34.38657334 -38.32112732
OS 34.40321542 -38.32297644
OS 34.42170662 -38.32482556
OS 34.44112238 -38.3285238
OS 34.46053814 -38.3331466
OS 34.47810478 -38.33961852
OS 34.47902934 -38.33961852
OS 34.4799539 -38.34054308
OS 34.48550126 -38.34331676
OS 34.4938223 -38.34793956
OS 34.5030679 -38.35441148
OS 34.51416262 -38.36273252
OS 34.5261819 -38.37290268
OS 34.53727662 -38.38584652
OS 34.54744678 -38.39971492
OS 34.54837134 -38.40156404
OS 34.55114502 -38.4071114
OS 34.55576782 -38.41450788
OS 34.56039062 -38.4256026
OS 34.56501342 -38.43854644
OS 34.56963622 -38.45241484
OS 34.5724099 -38.46813236
OS 34.57333446 -38.48384988
OS 34.57333446 -38.485699
OS 34.57333446 -38.4903218
OS 34.5724099 -38.49864284
OS 34.57056078 -38.508813
OS 34.5677871 -38.52083228
OS 34.5631643 -38.53377612
OS 34.55761694 -38.54671996
OS 34.55022046 -38.56058836
OS 34.5492959 -38.56243748
OS 34.54652222 -38.56613572
OS 34.54097486 -38.5735322
OS 34.53357838 -38.58092868
OS 34.52433278 -38.59017428
OS 34.51323806 -38.60034444
OS 34.49936966 -38.60959004
OS 34.48365214 -38.61883564
OS 34.4845767 -38.61883564
OS 34.48642582 -38.6197602
OS 34.4891995 -38.62068476
OS 34.49289774 -38.62253388
OS 34.50399246 -38.62623212
OS 34.5169363 -38.63270404
OS 34.5308047 -38.64102508
OS 34.54652222 -38.65119524
OS 34.56039062 -38.66321452
OS 34.57333446 -38.67800748
OS 34.57425902 -38.6798566
OS 34.57795726 -38.68540396
OS 34.58350462 -38.693725
OS 34.58905198 -38.70481972
OS 34.59459934 -38.71961268
OS 34.6001467 -38.7353302
OS 34.60384494 -38.7538214
OS 34.6047695 -38.77416172
OS 34.6047695 -38.77508628
OS 34.6047695 -38.77601084
OS 34.6047695 -38.7815582
OS 34.60384494 -38.7908038
OS 34.60199582 -38.80189852
OS 34.6001467 -38.81484236
OS 34.59644846 -38.82871076
OS 34.59182566 -38.84350372
OS 34.58535374 -38.85829668
OS 34.58442918 -38.8601458
OS 34.5816555 -38.8647686
OS 34.57795726 -38.87124052
OS 34.5724099 -38.88048612
OS 34.56501342 -38.88973172
OS 34.55761694 -38.89990188
OS 34.54837134 -38.91007204
OS 34.53820118 -38.91839308
OS 34.53727662 -38.91931764
OS 34.53357838 -38.92209132
OS 34.52710646 -38.92578956
OS 34.51878542 -38.9294878
OS 34.50861526 -38.93503516
OS 34.49659598 -38.94058252
OS 34.48365214 -38.94520532
OS 34.46793462 -38.94982812
OS 34.4660855 -38.94982812
OS 34.46053814 -38.95167724
OS 34.45129254 -38.9526018
OS 34.43927326 -38.95445092
OS 34.4244803 -38.95630004
OS 34.40691366 -38.95814916
OS 34.3874979 -38.95907372
OS 34.36530846 -38.95999828
OS 34.12122462 -38.95999828
OS 34.12122462 -38.32020276
OS 34.37270494 -38.32020276
OS 34.37917686 -38.32112732
OE
OB 31.74233174 -38.95999828 I
OS 31.65264942 -38.95999828
OS 31.65264942 -38.87031596
OS 31.74233174 -38.87031596
OS 31.74233174 -38.95999828
OE
OB 31.52968294 -38.42745172 I
OS 31.50841806 -38.54671996
OS 31.45941638 -38.54671996
OS 31.44000062 -38.42745172
OS 31.44000062 -38.32020276
OS 31.52968294 -38.32020276
OS 31.52968294 -38.42745172
OE
OB 32.0992119 -38.48662356 I
OS 32.10568382 -38.48754812
OS 32.11955222 -38.48939724
OS 32.1361943 -38.49309548
OS 32.15376094 -38.49864284
OS 32.17132758 -38.50696388
OS 32.18889422 -38.51713404
OS 32.18981878 -38.51713404
OS 32.19074334 -38.51898316
OS 32.1962907 -38.5226814
OS 32.20461174 -38.53007788
OS 32.2147819 -38.53932348
OS 32.22587662 -38.55134276
OS 32.23697134 -38.56613572
OS 32.24806606 -38.58370236
OS 32.25731166 -38.60311812
OS 32.25731166 -38.60404268
OS 32.25823622 -38.6058918
OS 32.25916078 -38.60866548
OS 32.2610099 -38.61236372
OS 32.26285902 -38.61791108
OS 32.26470814 -38.624383
OS 32.26933094 -38.63917596
OS 32.27395374 -38.65766716
OS 32.27765198 -38.67800748
OS 32.28042566 -38.70112148
OS 32.28135022 -38.72516004
OS 32.28135022 -38.7260846
OS 32.28135022 -38.72793372
OS 32.28135022 -38.73163196
OS 32.28135022 -38.73717932
OS 32.28042566 -38.74365124
OS 32.28042566 -38.75104772
OS 32.27857654 -38.7676898
OS 32.2748783 -38.78803012
OS 32.2702555 -38.809295
OS 32.26378358 -38.83148444
OS 32.25546254 -38.85367388
OS 32.25546254 -38.85459844
OS 32.25453798 -38.85644756
OS 32.25268886 -38.85922124
OS 32.25083974 -38.86291948
OS 32.24436782 -38.87308964
OS 32.23604678 -38.88603348
OS 32.22587662 -38.89990188
OS 32.21293278 -38.91377028
OS 32.19813982 -38.92763868
OS 32.18057318 -38.94058252
OS 32.17964862 -38.94058252
OS 32.17872406 -38.94150708
OS 32.17595038 -38.9433562
OS 32.17225214 -38.94520532
OS 32.16300654 -38.94982812
OS 32.1500627 -38.95537548
OS 32.13434518 -38.96092284
OS 32.1177031 -38.96554564
OS 32.09828734 -38.96924388
OS 32.07887158 -38.97016844
OS 32.07239966 -38.97016844
OS 32.06500318 -38.96924388
OS 32.05575758 -38.96831932
OS 32.04466286 -38.9664702
OS 32.03264358 -38.96369652
OS 32.0206243 -38.95999828
OS 32.00860502 -38.95445092
OS 32.00768046 -38.95352636
OS 32.00305766 -38.95167724
OS 31.9975103 -38.947979
OS 31.99011382 -38.94243164
OS 31.98271734 -38.93688428
OS 31.97347174 -38.9294878
OS 31.9651507 -38.92116676
OS 31.95775422 -38.91192116
OS 31.95775422 -39.1375138
OS 31.87916662 -39.1375138
OS 31.87916662 -38.49586916
OS 31.95035774 -38.49586916
OS 31.95035774 -38.55689012
OS 31.9512823 -38.555041
OS 31.95498054 -38.55134276
OS 31.95960334 -38.54487084
OS 31.96699982 -38.53747436
OS 31.97532086 -38.52822876
OS 31.98456646 -38.51990772
OS 31.99566118 -38.51158668
OS 32.0067559 -38.5041902
OS 32.00860502 -38.50326564
OS 32.01230326 -38.50141652
OS 32.01969974 -38.49864284
OS 32.02894534 -38.4949446
OS 32.04004006 -38.49124636
OS 32.0529839 -38.48847268
OS 32.06777686 -38.48662356
OS 32.08441894 -38.485699
OS 32.0945891 -38.485699
OS 32.0992119 -38.48662356
OE
OB 32.5614919 -38.48662356 I
OS 32.57166206 -38.48847268
OS 32.58368134 -38.49217092
OS 32.59662518 -38.49679372
OS 32.61141814 -38.50326564
OS 32.62713566 -38.51158668
OS 32.5984743 -38.58370236
OS 32.59754974 -38.5827778
OS 32.5938515 -38.58092868
OS 32.58830414 -38.578155
OS 32.58090766 -38.57538132
OS 32.57258662 -38.57260764
OS 32.56241646 -38.56983396
OS 32.5522463 -38.56798484
OS 32.54207614 -38.56706028
OS 32.53745334 -38.56706028
OS 32.53283054 -38.56798484
OS 32.52635862 -38.5689094
OS 32.5198867 -38.57075852
OS 32.51156566 -38.5735322
OS 32.50324462 -38.57723044
OS 32.49584814 -38.5827778
OS 32.49492358 -38.58370236
OS 32.4921499 -38.58555148
OS 32.48937622 -38.58924972
OS 32.48475342 -38.59387252
OS 32.48013062 -38.60034444
OS 32.47550782 -38.60774092
OS 32.47088502 -38.61606196
OS 32.46718678 -38.62623212
OS 32.46626222 -38.62808124
OS 32.46533766 -38.6336286
OS 32.46348854 -38.64194964
OS 32.46071486 -38.65304436
OS 32.45794118 -38.66691276
OS 32.45609206 -38.68263028
OS 32.4551675 -38.69927236
OS 32.45424294 -38.71776356
OS 32.45424294 -38.95999828
OS 32.37565534 -38.95999828
OS 32.37565534 -38.49586916
OS 32.44684646 -38.49586916
OS 32.44684646 -38.56613572
OS 32.44777102 -38.56521116
OS 32.45146926 -38.55873924
OS 32.45609206 -38.5504182
OS 32.46348854 -38.54024804
OS 32.47088502 -38.53007788
OS 32.47920606 -38.51898316
OS 32.4875271 -38.50973756
OS 32.49584814 -38.50234108
OS 32.4967727 -38.50141652
OS 32.49954638 -38.4995674
OS 32.50509374 -38.49679372
OS 32.5106411 -38.49402004
OS 32.51803758 -38.49124636
OS 32.52728318 -38.48847268
OS 32.53652878 -38.48662356
OS 32.54669894 -38.485699
OS 32.55317086 -38.485699
OS 32.5614919 -38.48662356
OE
OB 32.75195126 -38.4117342 I
OS 32.67336366 -38.4117342
OS 32.67336366 -38.32020276
OS 32.75195126 -38.32020276
OS 32.75195126 -38.4117342
OE
OB 36.56668582 -38.95999828 I
OS 36.47885262 -38.95999828
OS 36.1441619 -38.4579622
OS 36.1441619 -38.95999828
OS 36.06280062 -38.95999828
OS 36.06280062 -38.32020276
OS 36.14970926 -38.32020276
OS 36.48532454 -38.8231634
OS 36.48532454 -38.32020276
OS 36.56668582 -38.32020276
OS 36.56668582 -38.95999828
OE
OB 35.74382742 -38.32112732 I
OS 35.75954494 -38.32205188
OS 35.77618702 -38.32297644
OS 35.79190454 -38.32482556
OS 35.80577294 -38.32667468
OS 35.80762206 -38.32667468
OS 35.81409398 -38.3285238
OS 35.82241502 -38.33037292
OS 35.83350974 -38.3331466
OS 35.84552902 -38.3377694
OS 35.85847286 -38.34331676
OS 35.87234126 -38.34978868
OS 35.88436054 -38.35718516
OS 35.88620966 -38.35810972
OS 35.8899079 -38.3608834
OS 35.89545526 -38.36643076
OS 35.90285174 -38.37290268
OS 35.91117278 -38.38122372
OS 35.91949382 -38.39231844
OS 35.92873942 -38.40433772
OS 35.9361359 -38.41820612
OS 35.93706046 -38.42005524
OS 35.93890958 -38.42467804
OS 35.94260782 -38.43299908
OS 35.94630606 -38.4440938
OS 35.94907974 -38.45703764
OS 35.95277798 -38.4718306
OS 35.9546271 -38.48847268
OS 35.95555166 -38.50603932
OS 35.95555166 -38.50696388
OS 35.95555166 -38.50973756
OS 35.95555166 -38.5134358
OS 35.9546271 -38.51990772
OS 35.95370254 -38.52637964
OS 35.95277798 -38.53470068
OS 35.95092886 -38.54394628
OS 35.94907974 -38.55411644
OS 35.94260782 -38.57538132
OS 35.93890958 -38.58647604
OS 35.93336222 -38.59849532
OS 35.9268903 -38.6105146
OS 35.92041838 -38.62160932
OS 35.91209734 -38.63270404
OS 35.90285174 -38.64379876
OS 35.90192718 -38.64472332
OS 35.90007806 -38.64657244
OS 35.89730438 -38.64934612
OS 35.89268158 -38.6521198
OS 35.88713422 -38.6567426
OS 35.87973774 -38.6613654
OS 35.87049214 -38.66691276
OS 35.86032198 -38.67153556
OS 35.8483027 -38.67708292
OS 35.8344343 -38.68263028
OS 35.81964134 -38.68725308
OS 35.8020747 -38.69095132
OS 35.7835835 -38.69464956
OS 35.76324318 -38.69742324
OS 35.74012918 -38.69927236
OS 35.71609062 -38.70019692
OS 35.5524435 -38.70019692
OS 35.5524435 -38.95999828
OS 35.46738398 -38.95999828
OS 35.46738398 -38.32020276
OS 35.72995902 -38.32020276
OS 35.74382742 -38.32112732
OE
OB 36.76916446 -38.42745172 I
OS 36.74789958 -38.54671996
OS 36.6988979 -38.54671996
OS 36.67948214 -38.42745172
OS 36.67948214 -38.32020276
OS 36.76916446 -38.32020276
OS 36.76916446 -38.42745172
OE
OB 38.2382903 -38.39601668 I
OS 37.86014526 -38.39601668
OS 37.86014526 -38.59109884
OS 38.21425174 -38.59109884
OS 38.21425174 -38.66691276
OS 37.86014526 -38.66691276
OS 37.86014526 -38.88418436
OS 38.25308326 -38.88418436
OS 38.25308326 -38.95999828
OS 37.77508574 -38.95999828
OS 37.77508574 -38.32020276
OS 38.2382903 -38.32020276
OS 38.2382903 -38.39601668
OE
OB 37.4339231 -38.32112732 I
OS 37.44224414 -38.32112732
OS 37.4616599 -38.32205188
OS 37.48200022 -38.32482556
OS 37.50418966 -38.32759924
OS 37.52452998 -38.33222204
OS 37.53470014 -38.33499572
OS 37.54302118 -38.3377694
OS 37.54394574 -38.3377694
OS 37.5448703 -38.33869396
OS 37.55041766 -38.34146764
OS 37.5587387 -38.34516588
OS 37.56890886 -38.3516378
OS 37.58000358 -38.35995884
OS 37.59202286 -38.37105356
OS 37.60311758 -38.3839974
OS 37.6142123 -38.39879036
OS 37.6142123 -38.39971492
OS 37.61513686 -38.40063948
OS 37.6188351 -38.40618684
OS 37.62253334 -38.41543244
OS 37.6280807 -38.42745172
OS 37.6327035 -38.44132012
OS 37.6373263 -38.4579622
OS 37.64009998 -38.47552884
OS 37.64102454 -38.4949446
OS 37.64102454 -38.49586916
OS 37.64102454 -38.49771828
OS 37.64102454 -38.50141652
OS 37.64009998 -38.50603932
OS 37.64009998 -38.51251124
OS 37.63917542 -38.51898316
OS 37.63547718 -38.53470068
OS 37.62992982 -38.55319188
OS 37.62253334 -38.57260764
OS 37.61143862 -38.5920234
OS 37.60404214 -38.601269
OS 37.59664566 -38.6105146
OS 37.5957211 -38.61143916
OS 37.59479654 -38.61236372
OS 37.59202286 -38.6151374
OS 37.58832462 -38.61791108
OS 37.58370182 -38.62160932
OS 37.57815446 -38.62530756
OS 37.57075798 -38.62993036
OS 37.5633615 -38.63547772
OS 37.5541159 -38.64010052
OS 37.54394574 -38.64472332
OS 37.53285102 -38.65027068
OS 37.52083174 -38.65489348
OS 37.50696334 -38.65859172
OS 37.49309494 -38.66321452
OS 37.47737742 -38.6659882
OS 37.46073534 -38.66876188
OS 37.46258446 -38.66968644
OS 37.4662827 -38.67153556
OS 37.47183006 -38.6752338
OS 37.47922654 -38.67893204
OS 37.49586862 -38.6891022
OS 37.50418966 -38.69557412
OS 37.51158614 -38.70112148
OS 37.51343526 -38.7029706
OS 37.51805806 -38.7075934
OS 37.52545454 -38.71498988
OS 37.53470014 -38.72423548
OS 37.5448703 -38.73717932
OS 37.55688958 -38.75104772
OS 37.56890886 -38.7676898
OS 37.5818527 -38.786181
OS 37.69187534 -38.95999828
OS 37.5864755 -38.95999828
OS 37.50234054 -38.82686164
OS 37.50234054 -38.82593708
OS 37.50049142 -38.82408796
OS 37.4986423 -38.82131428
OS 37.49586862 -38.81761604
OS 37.4893967 -38.80744588
OS 37.48107566 -38.79450204
OS 37.4709055 -38.78063364
OS 37.46073534 -38.76584068
OS 37.45056518 -38.75197228
OS 37.44131958 -38.73902844
OS 37.44039502 -38.73810388
OS 37.43762134 -38.73440564
OS 37.43299854 -38.72885828
OS 37.42652662 -38.72238636
OS 37.41265822 -38.70851796
OS 37.40526174 -38.70204604
OS 37.39786526 -38.69649868
OS 37.3969407 -38.69557412
OS 37.39509158 -38.69464956
OS 37.39139334 -38.69280044
OS 37.38584598 -38.69002676
OS 37.38029862 -38.68725308
OS 37.3738267 -38.6844794
OS 37.35903374 -38.6798566
OS 37.35810918 -38.6798566
OS 37.35626006 -38.67893204
OS 37.35256182 -38.67893204
OS 37.34793902 -38.67800748
OS 37.3414671 -38.67708292
OS 37.33407062 -38.67708292
OS 37.32390046 -38.67615836
OS 37.21480238 -38.67615836
OS 37.21480238 -38.95999828
OS 37.12974286 -38.95999828
OS 37.12974286 -38.32020276
OS 37.42652662 -38.32020276
OS 37.4339231 -38.32112732
OE
OB 35.31760526 -38.95999828 I
OS 35.23254574 -38.95999828
OS 35.23254574 -38.32020276
OS 35.31760526 -38.32020276
OS 35.31760526 -38.95999828
OE
OB 42.12051774 -38.66413908 H
OS 41.95224782 -38.66413908
OS 41.95224782 -38.88418436
OS 42.13438614 -38.88418436
OS 42.1538019 -38.8832598
OS 42.16212294 -38.88233524
OS 42.16951942 -38.88141068
OS 42.17044398 -38.88141068
OS 42.17414222 -38.88048612
OS 42.17968958 -38.87956156
OS 42.1861615 -38.87771244
OS 42.20187902 -38.87216508
OS 42.21759654 -38.8647686
OS 42.2185211 -38.86384404
OS 42.22129478 -38.86199492
OS 42.22499302 -38.85922124
OS 42.22961582 -38.855523
OS 42.23423862 -38.84997564
OS 42.24071054 -38.84442828
OS 42.24533334 -38.8370318
OS 42.2508807 -38.82871076
OS 42.25180526 -38.8277862
OS 42.25272982 -38.82501252
OS 42.25457894 -38.81946516
OS 42.25735262 -38.81299324
OS 42.2601263 -38.80559676
OS 42.26197542 -38.79635116
OS 42.26289998 -38.78525644
OS 42.26382454 -38.77416172
OS 42.26382454 -38.7723126
OS 42.26382454 -38.76861436
OS 42.26289998 -38.76121788
OS 42.26105086 -38.75289684
OS 42.25920174 -38.74365124
OS 42.2555035 -38.73348108
OS 42.2508807 -38.72331092
OS 42.24440878 -38.71314076
OS 42.24348422 -38.7122162
OS 42.24071054 -38.70851796
OS 42.2370123 -38.70389516
OS 42.23146494 -38.6983478
OS 42.22406846 -38.69187588
OS 42.21482286 -38.68540396
OS 42.2046527 -38.6798566
OS 42.19263342 -38.6752338
OS 42.1907843 -38.67430924
OS 42.18708606 -38.67338468
OS 42.17876502 -38.67153556
OS 42.16859486 -38.66968644
OS 42.15565102 -38.66783732
OS 42.1399335 -38.6659882
OS 42.12051774 -38.66413908
OE
OB 45.22981302 -38.5504182 H
OS 45.22426566 -38.5504182
OS 45.21964286 -38.55134276
OS 45.2094727 -38.55226732
OS 45.1956043 -38.55596556
OS 45.17988678 -38.56151292
OS 45.1632447 -38.5689094
OS 45.14752718 -38.58000412
OS 45.13920614 -38.5874006
OS 45.13180966 -38.59479708
OS 45.13180966 -38.59572164
OS 45.12996054 -38.5966462
OS 45.12811142 -38.59941988
OS 45.12533774 -38.60311812
OS 45.12256406 -38.60774092
OS 45.11979038 -38.61328828
OS 45.11609214 -38.62068476
OS 45.1123939 -38.62808124
OS 45.10869566 -38.63732684
OS 45.10499742 -38.64657244
OS 45.10222374 -38.65766716
OS 45.09945006 -38.66968644
OS 45.09667638 -38.68263028
OS 45.09482726 -38.69649868
OS 45.0939027 -38.7122162
OS 45.09297814 -38.72793372
OS 45.09297814 -38.72885828
OS 45.09297814 -38.73163196
OS 45.09297814 -38.73625476
OS 45.0939027 -38.74272668
OS 45.0939027 -38.75012316
OS 45.09482726 -38.7584442
OS 45.09760094 -38.77785996
OS 45.10222374 -38.8000494
OS 45.10962022 -38.82223884
OS 45.11886582 -38.84350372
OS 45.12533774 -38.85274932
OS 45.13180966 -38.86199492
OS 45.13273422 -38.86199492
OS 45.13365878 -38.86384404
OS 45.13920614 -38.86846684
OS 45.14752718 -38.87586332
OS 45.1586219 -38.8832598
OS 45.1724903 -38.89158084
OS 45.18913238 -38.89897732
OS 45.20854814 -38.90360012
OS 45.2187183 -38.90452468
OS 45.22981302 -38.90544924
OS 45.23536038 -38.90544924
OS 45.23998318 -38.90452468
OS 45.25015334 -38.90267556
OS 45.26402174 -38.89990188
OS 45.2788147 -38.89435452
OS 45.29545678 -38.88695804
OS 45.3111743 -38.87586332
OS 45.31949534 -38.86846684
OS 45.32689182 -38.86107036
OS 45.32781638 -38.8601458
OS 45.32874094 -38.85922124
OS 45.33059006 -38.85644756
OS 45.33336374 -38.85274932
OS 45.33613742 -38.84812652
OS 45.33983566 -38.84257916
OS 45.3435339 -38.83518268
OS 45.34723214 -38.8277862
OS 45.35093038 -38.8185406
OS 45.35370406 -38.80837044
OS 45.3574023 -38.79727572
OS 45.36017598 -38.78525644
OS 45.36294966 -38.77138804
OS 45.36479878 -38.75751964
OS 45.3666479 -38.74180212
OS 45.3666479 -38.72516004
OS 45.3666479 -38.72423548
OS 45.3666479 -38.7214618
OS 45.3666479 -38.716839
OS 45.36572334 -38.71129164
OS 45.36572334 -38.70389516
OS 45.36479878 -38.69557412
OS 45.3620251 -38.67615836
OS 45.3574023 -38.65581804
OS 45.35000582 -38.6336286
OS 45.33983566 -38.61328828
OS 45.3342883 -38.60311812
OS 45.32689182 -38.59479708
OS 45.32689182 -38.59387252
OS 45.3250427 -38.59294796
OS 45.31949534 -38.5874006
OS 45.3111743 -38.58092868
OS 45.30007958 -38.57260764
OS 45.28621118 -38.5642866
OS 45.2695691 -38.55689012
OS 45.2510779 -38.55226732
OS 45.24090774 -38.55134276
OS 45.22981302 -38.5504182
OE
OB 32.07702246 -38.54764452 H
OS 32.07239966 -38.54764452
OS 32.06870142 -38.54856908
OS 32.05945582 -38.5504182
OS 32.04743654 -38.55319188
OS 32.03356814 -38.55873924
OS 32.01877518 -38.56706028
OS 32.01045414 -38.57260764
OS 32.00305766 -38.57907956
OS 31.99566118 -38.58647604
OS 31.9882647 -38.59479708
OS 31.9882647 -38.59572164
OS 31.98641558 -38.5966462
OS 31.98456646 -38.59941988
OS 31.98271734 -38.60311812
OS 31.97994366 -38.60866548
OS 31.97624542 -38.61421284
OS 31.97254718 -38.62160932
OS 31.9697735 -38.6290058
OS 31.96607526 -38.6382514
OS 31.96237702 -38.64842156
OS 31.95960334 -38.65951628
OS 31.9559051 -38.67153556
OS 31.95405598 -38.68540396
OS 31.95220686 -38.69927236
OS 31.95035774 -38.71406532
OS 31.95035774 -38.7307074
OS 31.95035774 -38.73163196
OS 31.95035774 -38.73440564
OS 31.95035774 -38.73902844
OS 31.9512823 -38.74550036
OS 31.9512823 -38.75289684
OS 31.95220686 -38.76121788
OS 31.95498054 -38.78063364
OS 31.95960334 -38.80282308
OS 31.9651507 -38.82408796
OS 31.9743963 -38.84535284
OS 31.97994366 -38.85459844
OS 31.98641558 -38.86291948
OS 31.9882647 -38.8647686
OS 31.9928875 -38.8693914
OS 32.00028398 -38.87678788
OS 32.01045414 -38.88418436
OS 32.02339798 -38.89158084
OS 32.03819094 -38.89897732
OS 32.05483302 -38.90360012
OS 32.06407862 -38.90452468
OS 32.07332422 -38.90544924
OS 32.07887158 -38.90544924
OS 32.08256982 -38.90452468
OS 32.09181542 -38.90267556
OS 32.10475926 -38.89990188
OS 32.11862766 -38.89435452
OS 32.13342062 -38.88695804
OS 32.14821358 -38.87586332
OS 32.15561006 -38.8693914
OS 32.16300654 -38.86199492
OS 32.16300654 -38.86107036
OS 32.16485566 -38.8601458
OS 32.16670478 -38.85737212
OS 32.1685539 -38.85367388
OS 32.17225214 -38.84905108
OS 32.17502582 -38.84257916
OS 32.17872406 -38.83610724
OS 32.1824223 -38.8277862
OS 32.18519598 -38.81946516
OS 32.18889422 -38.80837044
OS 32.19259246 -38.79727572
OS 32.19536614 -38.78525644
OS 32.19721526 -38.77138804
OS 32.19906438 -38.75659508
OS 32.2009135 -38.74087756
OS 32.2009135 -38.72423548
OS 32.2009135 -38.72331092
OS 32.2009135 -38.72053724
OS 32.2009135 -38.71591444
OS 32.19998894 -38.70944252
OS 32.19998894 -38.70204604
OS 32.19906438 -38.693725
OS 32.1962907 -38.67430924
OS 32.1916679 -38.65304436
OS 32.18519598 -38.63177948
OS 32.17595038 -38.6105146
OS 32.17040302 -38.60034444
OS 32.1639311 -38.5920234
OS 32.1639311 -38.59109884
OS 32.16208198 -38.59017428
OS 32.15745918 -38.58462692
OS 32.1500627 -38.578155
OS 32.13989254 -38.56983396
OS 32.1269487 -38.56151292
OS 32.11215574 -38.55411644
OS 32.09551366 -38.54949364
OS 32.08626806 -38.54856908
OS 32.07702246 -38.54764452
OE
OB 42.10387566 -38.39601668 H
OS 41.95224782 -38.39601668
OS 41.95224782 -38.58832516
OS 42.10942302 -38.58832516
OS 42.1214423 -38.5874006
OS 42.13438614 -38.58647604
OS 42.14732998 -38.58555148
OS 42.16027382 -38.58370236
OS 42.17044398 -38.58185324
OS 42.1722931 -38.58092868
OS 42.17599134 -38.58000412
OS 42.1815387 -38.57723044
OS 42.18893518 -38.5735322
OS 42.19633166 -38.56983396
OS 42.2046527 -38.5642866
OS 42.21297374 -38.55689012
OS 42.21944566 -38.54949364
OS 42.22037022 -38.54856908
OS 42.22221934 -38.5457954
OS 42.22499302 -38.54024804
OS 42.2277667 -38.53377612
OS 42.23054038 -38.52637964
OS 42.23331406 -38.51713404
OS 42.23516318 -38.50603932
OS 42.23608774 -38.49402004
OS 42.23608774 -38.49217092
OS 42.23608774 -38.48847268
OS 42.23516318 -38.48292532
OS 42.23423862 -38.47552884
OS 42.2323895 -38.46628324
OS 42.22961582 -38.45703764
OS 42.22591758 -38.44779204
OS 42.22037022 -38.43854644
OS 42.21944566 -38.43762188
OS 42.21759654 -38.4348482
OS 42.2138983 -38.4302254
OS 42.2092755 -38.4256026
OS 42.20280358 -38.42005524
OS 42.1954071 -38.41450788
OS 42.1861615 -38.40896052
OS 42.17599134 -38.40526228
OS 42.17506678 -38.40526228
OS 42.17044398 -38.40341316
OS 42.16397206 -38.4024886
OS 42.1538019 -38.40063948
OS 42.1399335 -38.39879036
OS 42.12421598 -38.3978658
OS 42.10387566 -38.39601668
OE
OB 37.41635646 -38.39139388 H
OS 37.21480238 -38.39139388
OS 37.21480238 -38.60311812
OS 37.40526174 -38.60311812
OS 37.41635646 -38.60219356
OS 37.4293003 -38.601269
OS 37.44409326 -38.60034444
OS 37.45888622 -38.59849532
OS 37.47367918 -38.59572164
OS 37.48662302 -38.5920234
OS 37.48847214 -38.59109884
OS 37.49217038 -38.58924972
OS 37.49771774 -38.58647604
OS 37.50511422 -38.5827778
OS 37.51343526 -38.57723044
OS 37.5217563 -38.57075852
OS 37.53007734 -38.56243748
OS 37.53654926 -38.55319188
OS 37.53747382 -38.55226732
OS 37.53932294 -38.54856908
OS 37.54209662 -38.54302172
OS 37.54579486 -38.53562524
OS 37.54856854 -38.5273042
OS 37.55134222 -38.5180586
OS 37.55319134 -38.50696388
OS 37.5541159 -38.49586916
OS 37.5541159 -38.4949446
OS 37.5541159 -38.49402004
OS 37.55319134 -38.48847268
OS 37.55226678 -38.48015164
OS 37.55041766 -38.46905692
OS 37.54579486 -38.4579622
OS 37.5402475 -38.44501836
OS 37.53192646 -38.43299908
OS 37.52083174 -38.4209798
OS 37.51898262 -38.42005524
OS 37.51435982 -38.416357
OS 37.50696334 -38.4117342
OS 37.49494406 -38.40618684
OS 37.48107566 -38.40063948
OS 37.46258446 -38.39601668
OS 37.44131958 -38.39231844
OS 37.41635646 -38.39139388
OE
OB 39.82298614 -38.54764452 H
OS 39.81836334 -38.54764452
OS 39.8146651 -38.54856908
OS 39.8054195 -38.5504182
OS 39.79340022 -38.55319188
OS 39.77953182 -38.55873924
OS 39.76473886 -38.56706028
OS 39.75641782 -38.57260764
OS 39.74902134 -38.57907956
OS 39.74162486 -38.58647604
OS 39.73422838 -38.59479708
OS 39.73422838 -38.59572164
OS 39.73237926 -38.5966462
OS 39.73053014 -38.59941988
OS 39.72868102 -38.60311812
OS 39.72590734 -38.60866548
OS 39.7222091 -38.61421284
OS 39.71851086 -38.62160932
OS 39.71573718 -38.6290058
OS 39.71203894 -38.6382514
OS 39.7083407 -38.64842156
OS 39.70556702 -38.65951628
OS 39.70186878 -38.67153556
OS 39.70001966 -38.68540396
OS 39.69817054 -38.69927236
OS 39.69632142 -38.71406532
OS 39.69632142 -38.7307074
OS 39.69632142 -38.73163196
OS 39.69632142 -38.73440564
OS 39.69632142 -38.73902844
OS 39.69724598 -38.74550036
OS 39.69724598 -38.75289684
OS 39.69817054 -38.76121788
OS 39.70094422 -38.78063364
OS 39.70556702 -38.80282308
OS 39.71111438 -38.82408796
OS 39.72035998 -38.84535284
OS 39.72590734 -38.85459844
OS 39.73237926 -38.86291948
OS 39.73422838 -38.8647686
OS 39.73885118 -38.8693914
OS 39.74624766 -38.87678788
OS 39.75641782 -38.88418436
OS 39.76936166 -38.89158084
OS 39.78415462 -38.89897732
OS 39.8007967 -38.90360012
OS 39.8100423 -38.90452468
OS 39.8192879 -38.90544924
OS 39.82483526 -38.90544924
OS 39.8285335 -38.90452468
OS 39.8377791 -38.90267556
OS 39.85072294 -38.89990188
OS 39.86459134 -38.89435452
OS 39.8793843 -38.88695804
OS 39.89417726 -38.87586332
OS 39.90157374 -38.8693914
OS 39.90897022 -38.86199492
OS 39.90897022 -38.86107036
OS 39.91081934 -38.8601458
OS 39.91266846 -38.85737212
OS 39.91451758 -38.85367388
OS 39.91821582 -38.84905108
OS 39.9209895 -38.84257916
OS 39.92468774 -38.83610724
OS 39.92838598 -38.8277862
OS 39.93115966 -38.81946516
OS 39.9348579 -38.80837044
OS 39.93855614 -38.79727572
OS 39.94132982 -38.78525644
OS 39.94317894 -38.77138804
OS 39.94502806 -38.75659508
OS 39.94687718 -38.74087756
OS 39.94687718 -38.72423548
OS 39.94687718 -38.72331092
OS 39.94687718 -38.72053724
OS 39.94687718 -38.71591444
OS 39.94595262 -38.70944252
OS 39.94595262 -38.70204604
OS 39.94502806 -38.693725
OS 39.94225438 -38.67430924
OS 39.93763158 -38.65304436
OS 39.93115966 -38.63177948
OS 39.92191406 -38.6105146
OS 39.9163667 -38.60034444
OS 39.90989478 -38.5920234
OS 39.90989478 -38.59109884
OS 39.90804566 -38.59017428
OS 39.90342286 -38.58462692
OS 39.89602638 -38.578155
OS 39.88585622 -38.56983396
OS 39.87291238 -38.56151292
OS 39.85811942 -38.55411644
OS 39.84147734 -38.54949364
OS 39.83223174 -38.54856908
OS 39.82298614 -38.54764452
OE
OB 35.73550638 -38.39601668 H
OS 35.5524435 -38.39601668
OS 35.5524435 -38.624383
OS 35.72441166 -38.624383
OS 35.73088358 -38.62345844
OS 35.7373555 -38.62345844
OS 35.74475198 -38.62253388
OS 35.76231862 -38.62068476
OS 35.78173438 -38.61698652
OS 35.80115014 -38.61143916
OS 35.81871678 -38.60404268
OS 35.82703782 -38.59941988
OS 35.83350974 -38.59387252
OS 35.83535886 -38.5920234
OS 35.8390571 -38.58832516
OS 35.84460446 -38.58092868
OS 35.85107638 -38.57168308
OS 35.8575483 -38.5596638
OS 35.86309566 -38.54487084
OS 35.8667939 -38.52822876
OS 35.86864302 -38.508813
OS 35.86864302 -38.50788844
OS 35.86864302 -38.50696388
OS 35.86864302 -38.50234108
OS 35.86771846 -38.49402004
OS 35.86586934 -38.48477444
OS 35.86402022 -38.47460428
OS 35.86032198 -38.462585
OS 35.85477462 -38.45149028
OS 35.8483027 -38.44039556
OS 35.84737814 -38.439471
OS 35.84460446 -38.43577276
OS 35.83998166 -38.43114996
OS 35.8344343 -38.42467804
OS 35.82611326 -38.41820612
OS 35.81686766 -38.41265876
OS 35.8066975 -38.4071114
OS 35.79467822 -38.4024886
OS 35.79375366 -38.4024886
OS 35.79005542 -38.40156404
OS 35.78450806 -38.40063948
OS 35.77711158 -38.39879036
OS 35.76601686 -38.3978658
OS 35.75214846 -38.39694124
OS 35.73550638 -38.39601668
OE
OB 43.44263854 -38.5504182 H
OS 43.43709118 -38.5504182
OS 43.43339294 -38.55134276
OS 43.42322278 -38.55226732
OS 43.4112035 -38.555041
OS 43.39641054 -38.5596638
OS 43.38069302 -38.56613572
OS 43.36590006 -38.57538132
OS 43.3511071 -38.5874006
OS 43.34925798 -38.58924972
OS 43.34555974 -38.59387252
OS 43.33908782 -38.60219356
OS 43.3326159 -38.61328828
OS 43.32521942 -38.62623212
OS 43.3187475 -38.6428742
OS 43.31320014 -38.66228996
OS 43.31042646 -38.68355484
OS 43.57022782 -38.68355484
OS 43.57022782 -38.68263028
OS 43.57022782 -38.68078116
OS 43.56930326 -38.67800748
OS 43.56930326 -38.67430924
OS 43.56745414 -38.66321452
OS 43.56468046 -38.65119524
OS 43.56005766 -38.63640228
OS 43.55543486 -38.62253388
OS 43.54803838 -38.60866548
OS 43.53971734 -38.5966462
OS 43.53971734 -38.59572164
OS 43.53786822 -38.59479708
OS 43.53324542 -38.58924972
OS 43.52492438 -38.58185324
OS 43.51382966 -38.5735322
OS 43.49996126 -38.56521116
OS 43.48331918 -38.55781468
OS 43.46390342 -38.55226732
OS 43.45373326 -38.55134276
OS 43.44263854 -38.5504182
OE
OB 34.35791198 -38.39601668 H
OS 34.20628414 -38.39601668
OS 34.20628414 -38.58832516
OS 34.36345934 -38.58832516
OS 34.37547862 -38.5874006
OS 34.38842246 -38.58647604
OS 34.4013663 -38.58555148
OS 34.41431014 -38.58370236
OS 34.4244803 -38.58185324
OS 34.42632942 -38.58092868
OS 34.43002766 -38.58000412
OS 34.43557502 -38.57723044
OS 34.4429715 -38.5735322
OS 34.45036798 -38.56983396
OS 34.45868902 -38.5642866
OS 34.46701006 -38.55689012
OS 34.47348198 -38.54949364
OS 34.47440654 -38.54856908
OS 34.47625566 -38.5457954
OS 34.47902934 -38.54024804
OS 34.48180302 -38.53377612
OS 34.4845767 -38.52637964
OS 34.48735038 -38.51713404
OS 34.4891995 -38.50603932
OS 34.49012406 -38.49402004
OS 34.49012406 -38.49217092
OS 34.49012406 -38.48847268
OS 34.4891995 -38.48292532
OS 34.48827494 -38.47552884
OS 34.48642582 -38.46628324
OS 34.48365214 -38.45703764
OS 34.4799539 -38.44779204
OS 34.47440654 -38.43854644
OS 34.47348198 -38.43762188
OS 34.47163286 -38.4348482
OS 34.46793462 -38.4302254
OS 34.46331182 -38.4256026
OS 34.4568399 -38.42005524
OS 34.44944342 -38.41450788
OS 34.44019782 -38.40896052
OS 34.43002766 -38.40526228
OS 34.4291031 -38.40526228
OS 34.4244803 -38.40341316
OS 34.41800838 -38.4024886
OS 34.40783822 -38.40063948
OS 34.39396982 -38.39879036
OS 34.3782523 -38.3978658
OS 34.35791198 -38.39601668
OE
OB 40.89732486 -38.39601668 H
OS 40.71426198 -38.39601668
OS 40.71426198 -38.624383
OS 40.88623014 -38.624383
OS 40.89270206 -38.62345844
OS 40.89917398 -38.62345844
OS 40.90657046 -38.62253388
OS 40.9241371 -38.62068476
OS 40.94355286 -38.61698652
OS 40.96296862 -38.61143916
OS 40.98053526 -38.60404268
OS 40.9888563 -38.59941988
OS 40.99532822 -38.59387252
OS 40.99717734 -38.5920234
OS 41.00087558 -38.58832516
OS 41.00642294 -38.58092868
OS 41.01289486 -38.57168308
OS 41.01936678 -38.5596638
OS 41.02491414 -38.54487084
OS 41.02861238 -38.52822876
OS 41.0304615 -38.508813
OS 41.0304615 -38.50788844
OS 41.0304615 -38.50696388
OS 41.0304615 -38.50234108
OS 41.02953694 -38.49402004
OS 41.02768782 -38.48477444
OS 41.0258387 -38.47460428
OS 41.02214046 -38.462585
OS 41.0165931 -38.45149028
OS 41.01012118 -38.44039556
OS 41.00919662 -38.439471
OS 41.00642294 -38.43577276
OS 41.00180014 -38.43114996
OS 40.99625278 -38.42467804
OS 40.98793174 -38.41820612
OS 40.97868614 -38.41265876
OS 40.96851598 -38.4071114
OS 40.9564967 -38.4024886
OS 40.95557214 -38.4024886
OS 40.9518739 -38.40156404
OS 40.94632654 -38.40063948
OS 40.93893006 -38.39879036
OS 40.92783534 -38.3978658
OS 40.91396694 -38.39694124
OS 40.89732486 -38.39601668
OE
OB 33.15136118 -38.39601668 H
OS 32.9682983 -38.39601668
OS 32.9682983 -38.624383
OS 33.14026646 -38.624383
OS 33.14673838 -38.62345844
OS 33.1532103 -38.62345844
OS 33.16060678 -38.62253388
OS 33.17817342 -38.62068476
OS 33.19758918 -38.61698652
OS 33.21700494 -38.61143916
OS 33.23457158 -38.60404268
OS 33.24289262 -38.59941988
OS 33.24936454 -38.59387252
OS 33.25121366 -38.5920234
OS 33.2549119 -38.58832516
OS 33.26045926 -38.58092868
OS 33.26693118 -38.57168308
OS 33.2734031 -38.5596638
OS 33.27895046 -38.54487084
OS 33.2826487 -38.52822876
OS 33.28449782 -38.508813
OS 33.28449782 -38.50788844
OS 33.28449782 -38.50696388
OS 33.28449782 -38.50234108
OS 33.28357326 -38.49402004
OS 33.28172414 -38.48477444
OS 33.27987502 -38.47460428
OS 33.27617678 -38.462585
OS 33.27062942 -38.45149028
OS 33.2641575 -38.44039556
OS 33.26323294 -38.439471
OS 33.26045926 -38.43577276
OS 33.25583646 -38.43114996
OS 33.2502891 -38.42467804
OS 33.24196806 -38.41820612
OS 33.23272246 -38.41265876
OS 33.2225523 -38.4071114
OS 33.21053302 -38.4024886
OS 33.20960846 -38.4024886
OS 33.20591022 -38.40156404
OS 33.20036286 -38.40063948
OS 33.19296638 -38.39879036
OS 33.18187166 -38.3978658
OS 33.16800326 -38.39694124
OS 33.15136118 -38.39601668
OE
OB 34.37455406 -38.66413908 H
OS 34.20628414 -38.66413908
OS 34.20628414 -38.88418436
OS 34.38842246 -38.88418436
OS 34.40783822 -38.8832598
OS 34.41615926 -38.88233524
OS 34.42355574 -38.88141068
OS 34.4244803 -38.88141068
OS 34.42817854 -38.88048612
OS 34.4337259 -38.87956156
OS 34.44019782 -38.87771244
OS 34.45591534 -38.87216508
OS 34.47163286 -38.8647686
OS 34.47255742 -38.86384404
OS 34.4753311 -38.86199492
OS 34.47902934 -38.85922124
OS 34.48365214 -38.855523
OS 34.48827494 -38.84997564
OS 34.49474686 -38.84442828
OS 34.49936966 -38.8370318
OS 34.50491702 -38.82871076
OS 34.50584158 -38.8277862
OS 34.50676614 -38.82501252
OS 34.50861526 -38.81946516
OS 34.51138894 -38.81299324
OS 34.51416262 -38.80559676
OS 34.51601174 -38.79635116
OS 34.5169363 -38.78525644
OS 34.51786086 -38.77416172
OS 34.51786086 -38.7723126
OS 34.51786086 -38.76861436
OS 34.5169363 -38.76121788
OS 34.51508718 -38.75289684
OS 34.51323806 -38.74365124
OS 34.50953982 -38.73348108
OS 34.50491702 -38.72331092
OS 34.4984451 -38.71314076
OS 34.49752054 -38.7122162
OS 34.49474686 -38.70851796
OS 34.49104862 -38.70389516
OS 34.48550126 -38.6983478
OS 34.47810478 -38.69187588
OS 34.46885918 -38.68540396
OS 34.45868902 -38.6798566
OS 34.44666974 -38.6752338
OS 34.44482062 -38.67430924
OS 34.44112238 -38.67338468
OS 34.43280134 -38.67153556
OS 34.42263118 -38.66968644
OS 34.40968734 -38.66783732
OS 34.39396982 -38.6659882
OS 34.37455406 -38.66413908
OE
SE
S P 0
OB 48.49040086 -36.61402634 I
OS 48.17420134 -36.61402634
OS 48.17420134 -37.45999874
OS 48.04661206 -37.45999874
OS 48.04661206 -36.61402634
OS 47.73041254 -36.61402634
OS 47.73041254 -36.50030546
OS 48.49040086 -36.50030546
OS 48.49040086 -36.61402634
OE
OB 47.69990206 -37.45999874 I
OS 47.5556707 -37.45999874
OS 47.44333666 -37.16876234
OS 47.04115306 -37.16876234
OS 46.93714006 -37.45999874
OS 46.80261658 -37.45999874
OS 47.16874234 -36.50030546
OS 47.30742634 -36.50030546
OS 47.69990206 -37.45999874
OE
OB 49.31834434 -36.61402634 I
OS 48.75112678 -36.61402634
OS 48.75112678 -36.90664958
OS 49.2822865 -36.90664958
OS 49.2822865 -37.02037046
OS 48.75112678 -37.02037046
OS 48.75112678 -37.34627786
OS 49.34053378 -37.34627786
OS 49.34053378 -37.45999874
OS 48.6235375 -37.45999874
OS 48.6235375 -36.50030546
OS 49.31834434 -36.50030546
OS 49.31834434 -36.61402634
OE
OB 46.33386466 -36.5016923 I
OS 46.36160146 -36.50307914
OS 46.38933826 -36.50585282
OS 46.41707506 -36.51001334
OS 46.44065134 -36.51417386
OS 46.44203818 -36.51417386
OS 46.44481186 -36.5155607
OS 46.44897238 -36.5155607
OS 46.45451974 -36.51833438
OS 46.46977498 -36.5224949
OS 46.48919074 -36.5294291
OS 46.51138018 -36.53913698
OS 46.53495646 -36.55161854
OS 46.55853274 -36.56548694
OS 46.58072218 -36.58351586
OS 46.58210902 -36.5849027
OS 46.58349586 -36.58628954
OS 46.58765638 -36.59045006
OS 46.59320374 -36.59461058
OS 46.60707214 -36.60847898
OS 46.62371422 -36.62789474
OS 46.64174314 -36.65147102
OS 46.6611589 -36.67920782
OS 46.67918782 -36.71110514
OS 46.69444306 -36.74716298
OS 46.69444306 -36.74854982
OS 46.6958299 -36.7513235
OS 46.69860358 -36.75687086
OS 46.69999042 -36.7651919
OS 46.70415094 -36.77489978
OS 46.70692462 -36.7859945
OS 46.7096983 -36.79847606
OS 46.71385882 -36.8137313
OS 46.71801934 -36.82898654
OS 46.72079302 -36.84701546
OS 46.72772722 -36.88584698
OS 46.73188774 -36.92883902
OS 46.73327458 -36.97599158
OS 46.73327458 -36.97737842
OS 46.73327458 -36.9801521
OS 46.73327458 -36.9870863
OS 46.73327458 -36.9940205
OS 46.73188774 -37.00372838
OS 46.73188774 -37.0148231
OS 46.7305009 -37.04117306
OS 46.72634038 -37.07168354
OS 46.72217986 -37.10358086
OS 46.71524566 -37.13686502
OS 46.70692462 -37.17014918
OS 46.70692462 -37.17153602
OS 46.70553778 -37.1743097
OS 46.70415094 -37.17847022
OS 46.7027641 -37.18401758
OS 46.69721674 -37.19927282
OS 46.6888957 -37.21868858
OS 46.68057466 -37.24087802
OS 46.66947994 -37.26306746
OS 46.65561154 -37.28664374
OS 46.64174314 -37.30883318
OS 46.6403563 -37.31160686
OS 46.63480894 -37.31854106
OS 46.6264879 -37.32824894
OS 46.61539318 -37.3407305
OS 46.60291162 -37.3545989
OS 46.58765638 -37.3684673
OS 46.57240114 -37.38372254
OS 46.55437222 -37.3962041
OS 46.55159854 -37.39759094
OS 46.54605118 -37.40175146
OS 46.5363433 -37.40729882
OS 46.5224749 -37.41423302
OS 46.50583282 -37.42255406
OS 46.48641706 -37.42948826
OS 46.46422762 -37.4378093
OS 46.4392645 -37.4447435
OS 46.43649082 -37.4447435
OS 46.4323303 -37.44613034
OS 46.42816978 -37.44751718
OS 46.41430138 -37.44890402
OS 46.39488562 -37.4516777
OS 46.37269618 -37.45445138
OS 46.34634622 -37.45722506
OS 46.31722258 -37.4586119
OS 46.28532526 -37.45999874
OS 45.9400021 -37.45999874
OS 45.9400021 -36.50030546
OS 46.30890154 -36.50030546
OS 46.33386466 -36.5016923
OE
OB 46.28948578 -36.61402634 H
OS 46.06759138 -36.61402634
OS 46.06759138 -37.34627786
OS 46.29503314 -37.34627786
OS 46.30474102 -37.34489102
OS 46.32554362 -37.34350418
OS 46.3491199 -37.34211734
OS 46.37408302 -37.33934366
OS 46.39904614 -37.33518314
OS 46.41984874 -37.32963578
OS 46.42262242 -37.32824894
OS 46.42955662 -37.3268621
OS 46.4392645 -37.32270158
OS 46.45174606 -37.31715422
OS 46.46561446 -37.30883318
OS 46.47948286 -37.30051214
OS 46.49335126 -37.29080426
OS 46.50721966 -37.27970954
OS 46.5086065 -37.27693586
OS 46.51415386 -37.2713885
OS 46.5224749 -37.26168062
OS 46.53218278 -37.24781222
OS 46.5432775 -37.2297833
OS 46.55575906 -37.2089807
OS 46.56685378 -37.18540442
OS 46.57656166 -37.15905446
OS 46.57656166 -37.15766762
OS 46.5779485 -37.15489394
OS 46.57933534 -37.15073342
OS 46.58072218 -37.14518606
OS 46.58210902 -37.13825186
OS 46.5848827 -37.12854398
OS 46.58765638 -37.1188361
OS 46.59043006 -37.10774138
OS 46.59459058 -37.08000458
OS 46.5987511 -37.04810726
OS 46.60152478 -37.01204942
OS 46.60291162 -36.9732179
OS 46.60291162 -36.97183106
OS 46.60291162 -36.9662837
OS 46.60291162 -36.9593495
OS 46.60152478 -36.94825478
OS 46.60152478 -36.93577322
OS 46.60013794 -36.92190482
OS 46.5987511 -36.90526274
OS 46.59736426 -36.88862066
OS 46.59043006 -36.85117598
OS 46.58210902 -36.81234446
OS 46.56962746 -36.77628662
OS 46.56130642 -36.7582577
OS 46.55298538 -36.74300246
OS 46.55298538 -36.74161562
OS 46.5502117 -36.73884194
OS 46.54743802 -36.73468142
OS 46.54466434 -36.72913406
OS 46.53356962 -36.71526566
OS 46.51970122 -36.69862358
OS 46.5016723 -36.68059466
OS 46.4808697 -36.66256574
OS 46.45729342 -36.6473105
OS 46.4323303 -36.63482894
OS 46.42955662 -36.6334421
OS 46.42262242 -36.63205526
OS 46.41014086 -36.62789474
OS 46.39211194 -36.62373422
OS 46.3699225 -36.62096054
OS 46.3421857 -36.61680002
OS 46.32554362 -36.61541318
OS 46.3075147 -36.61541318
OS 46.28948578 -36.61402634
OE
OB 47.23531066 -36.60015794 H
OS 47.23531066 -36.60154478
OS 47.23392382 -36.60431846
OS 47.23392382 -36.60986582
OS 47.23115014 -36.61541318
OS 47.2297633 -36.62512106
OS 47.22698962 -36.63482894
OS 47.22144226 -36.65840522
OS 47.21450806 -36.68614202
OS 47.20480018 -36.7166525
OS 47.1950923 -36.74993666
OS 47.18261074 -36.78460766
OS 47.07859774 -37.06474934
OS 47.4031183 -37.06474934
OS 47.30326582 -36.80124974
OS 47.30326582 -36.7998629
OS 47.30187898 -36.79570238
OS 47.2991053 -36.78876818
OS 47.29633162 -36.78044714
OS 47.2921711 -36.77073926
OS 47.28801058 -36.7582577
OS 47.28385006 -36.7443893
OS 47.2783027 -36.7305209
OS 47.26720798 -36.69862358
OS 47.25611326 -36.66533942
OS 47.24501854 -36.63205526
OS 47.23531066 -36.60015794
OE
SE
S P 0
OB 53.64989524 -38.94890356 I
OS 53.57130764 -38.94890356
OS 53.57130764 -38.4487166
OS 53.57038308 -38.44964116
OS 53.56576028 -38.4533394
OS 53.56021292 -38.45888676
OS 53.55096732 -38.46535868
OS 53.54079716 -38.47367972
OS 53.52785332 -38.48292532
OS 53.51306036 -38.49309548
OS 53.49641828 -38.50326564
OS 53.49549372 -38.50326564
OS 53.49456916 -38.5041902
OS 53.4890218 -38.50788844
OS 53.4797762 -38.51251124
OS 53.46868148 -38.5180586
OS 53.45573764 -38.52453052
OS 53.44186924 -38.53100244
OS 53.42800084 -38.53747436
OS 53.41413244 -38.54302172
OS 53.41413244 -38.4672078
OS 53.415057 -38.4672078
OS 53.41690612 -38.46535868
OS 53.42060436 -38.46443412
OS 53.42522716 -38.46166044
OS 53.43077452 -38.45888676
OS 53.43724644 -38.45518852
OS 53.45296396 -38.44594292
OS 53.47145516 -38.43577276
OS 53.48994636 -38.42282892
OS 53.50936212 -38.40803596
OS 53.52877788 -38.39231844
OS 53.52970244 -38.39139388
OS 53.530627 -38.39046932
OS 53.53340068 -38.38769564
OS 53.53709892 -38.38492196
OS 53.54541996 -38.37567636
OS 53.55651468 -38.36458164
OS 53.5676094 -38.3516378
OS 53.57962868 -38.33684484
OS 53.58979884 -38.32205188
OS 53.59904444 -38.30633436
OS 53.64989524 -38.30633436
OS 53.64989524 -38.94890356
OE
OB 54.07334372 -38.30725892 I
OS 54.0807402 -38.30818348
OS 54.08906124 -38.30910804
OS 54.09830684 -38.3100326
OS 54.10755244 -38.31280628
OS 54.12974188 -38.31835364
OS 54.15193132 -38.32667468
OS 54.16302604 -38.33222204
OS 54.17412076 -38.33869396
OS 54.18429092 -38.347015
OS 54.19446108 -38.35533604
OS 54.19538564 -38.3562606
OS 54.1963102 -38.35718516
OS 54.19908388 -38.35995884
OS 54.20278212 -38.36365708
OS 54.20648036 -38.36920444
OS 54.21110316 -38.3747518
OS 54.22034876 -38.3886202
OS 54.22959436 -38.40618684
OS 54.2379154 -38.42652716
OS 54.24438732 -38.44964116
OS 54.24531188 -38.46166044
OS 54.24623644 -38.47460428
OS 54.24623644 -38.47552884
OS 54.24623644 -38.4764534
OS 54.24623644 -38.48200076
OS 54.24531188 -38.4903218
OS 54.24346276 -38.50049196
OS 54.24068908 -38.5134358
OS 54.23606628 -38.52637964
OS 54.23051892 -38.53932348
OS 54.22219788 -38.55226732
OS 54.22127332 -38.55411644
OS 54.21757508 -38.55781468
OS 54.21202772 -38.56336204
OS 54.20463124 -38.57075852
OS 54.19446108 -38.57907956
OS 54.1824418 -38.5874006
OS 54.1685734 -38.59572164
OS 54.15193132 -38.60311812
OS 54.15285588 -38.60311812
OS 54.154705 -38.60404268
OS 54.15747868 -38.60496724
OS 54.16117692 -38.60681636
OS 54.17227164 -38.61143916
OS 54.18521548 -38.61791108
OS 54.19908388 -38.62715668
OS 54.21387684 -38.63732684
OS 54.22774524 -38.65027068
OS 54.24068908 -38.66506364
OS 54.24068908 -38.6659882
OS 54.24161364 -38.66691276
OS 54.24531188 -38.67246012
OS 54.25085924 -38.68170572
OS 54.2564066 -38.693725
OS 54.26195396 -38.70851796
OS 54.26750132 -38.7260846
OS 54.27119956 -38.74550036
OS 54.27212412 -38.76676524
OS 54.27212412 -38.7676898
OS 54.27212412 -38.77046348
OS 54.27212412 -38.77508628
OS 54.27119956 -38.78063364
OS 54.270275 -38.78710556
OS 54.26935044 -38.7954266
OS 54.26750132 -38.8046722
OS 54.26472764 -38.81484236
OS 54.25825572 -38.83610724
OS 54.25363292 -38.84812652
OS 54.247161 -38.85922124
OS 54.24068908 -38.87124052
OS 54.2332926 -38.88233524
OS 54.224047 -38.89342996
OS 54.21387684 -38.90452468
OS 54.21295228 -38.90544924
OS 54.21110316 -38.90729836
OS 54.20832948 -38.91007204
OS 54.20370668 -38.91284572
OS 54.19723476 -38.91746852
OS 54.19076284 -38.92209132
OS 54.1824418 -38.92671412
OS 54.1731962 -38.93226148
OS 54.16302604 -38.93780884
OS 54.15100676 -38.94243164
OS 54.13806292 -38.94705444
OS 54.12511908 -38.95167724
OS 54.11032612 -38.95445092
OS 54.0946086 -38.9572246
OS 54.07889108 -38.95907372
OS 54.06132444 -38.95999828
OS 54.05207884 -38.95999828
OS 54.04560692 -38.95907372
OS 54.03728588 -38.95814916
OS 54.02804028 -38.9572246
OS 54.01787012 -38.95537548
OS 54.0067754 -38.9526018
OS 53.98181228 -38.94612988
OS 53.96886844 -38.94150708
OS 53.95684916 -38.93688428
OS 53.94390532 -38.93041236
OS 53.93096148 -38.92301588
OS 53.9189422 -38.91469484
OS 53.90784748 -38.90452468
OS 53.90692292 -38.90360012
OS 53.9050738 -38.901751
OS 53.90230012 -38.89897732
OS 53.89860188 -38.89435452
OS 53.89490364 -38.88880716
OS 53.88935628 -38.88233524
OS 53.88473348 -38.87493876
OS 53.87918612 -38.86569316
OS 53.87363876 -38.85644756
OS 53.86901596 -38.84535284
OS 53.85977036 -38.82223884
OS 53.85607212 -38.80837044
OS 53.85329844 -38.79450204
OS 53.85144932 -38.77970908
OS 53.85052476 -38.76491612
OS 53.85052476 -38.76399156
OS 53.85052476 -38.76214244
OS 53.85052476 -38.7584442
OS 53.85144932 -38.75474596
OS 53.85144932 -38.7491986
OS 53.85237388 -38.74272668
OS 53.854223 -38.72793372
OS 53.85792124 -38.71129164
OS 53.8634686 -38.69464956
OS 53.87178964 -38.67708292
OS 53.8819598 -38.66044084
OS 53.8819598 -38.65951628
OS 53.88380892 -38.65859172
OS 53.88750716 -38.65396892
OS 53.89490364 -38.64657244
OS 53.9050738 -38.63732684
OS 53.91801764 -38.62808124
OS 53.93373516 -38.61791108
OS 53.9513018 -38.60959004
OS 53.97256668 -38.60311812
OS 53.97164212 -38.60311812
OS 53.97071756 -38.60219356
OS 53.96794388 -38.601269
OS 53.96424564 -38.59941988
OS 53.9559246 -38.59572164
OS 53.94482988 -38.59017428
OS 53.9328106 -38.5827778
OS 53.92079132 -38.5735322
OS 53.9096966 -38.56336204
OS 53.89952644 -38.55226732
OS 53.89860188 -38.5504182
OS 53.8958282 -38.54671996
OS 53.89212996 -38.53932348
OS 53.88843172 -38.53007788
OS 53.88380892 -38.5180586
OS 53.88011068 -38.5041902
OS 53.877337 -38.48847268
OS 53.87641244 -38.4718306
OS 53.87641244 -38.47090604
OS 53.87641244 -38.46905692
OS 53.87641244 -38.46535868
OS 53.877337 -38.45981132
OS 53.87826156 -38.45426396
OS 53.87918612 -38.44686748
OS 53.88288436 -38.43114996
OS 53.88843172 -38.41265876
OS 53.89767732 -38.393243
OS 53.90322468 -38.38307284
OS 53.9096966 -38.37290268
OS 53.91801764 -38.36365708
OS 53.92633868 -38.35441148
OS 53.92726324 -38.35348692
OS 53.92911236 -38.35256236
OS 53.93188604 -38.34978868
OS 53.93558428 -38.347015
OS 53.94020708 -38.34331676
OS 53.946679 -38.33961852
OS 53.95407548 -38.33499572
OS 53.96147196 -38.33037292
OS 53.97071756 -38.32575012
OS 53.98088772 -38.32112732
OS 53.99198244 -38.31742908
OS 54.00400172 -38.31373084
OS 54.0298894 -38.30818348
OS 54.04468236 -38.30725892
OS 54.05947532 -38.30633436
OS 54.06779636 -38.30633436
OS 54.07334372 -38.30725892
OE
OB 53.23846604 -38.94890356 I
OS 53.14878372 -38.94890356
OS 53.14878372 -38.85922124
OS 53.23846604 -38.85922124
OS 53.23846604 -38.94890356
OE
OB 53.00177868 -38.39231844 I
OS 52.74567556 -38.39231844
OS 52.71146684 -38.56521116
OS 52.7123914 -38.5642866
OS 52.71424052 -38.56336204
OS 52.7170142 -38.56151292
OS 52.721637 -38.55873924
OS 52.72718436 -38.55596556
OS 52.73365628 -38.55226732
OS 52.74844924 -38.54487084
OS 52.76694044 -38.53747436
OS 52.78728076 -38.53100244
OS 52.8094702 -38.52637964
OS 52.82056492 -38.52453052
OS 52.84090524 -38.52453052
OS 52.8464526 -38.52545508
OS 52.85384908 -38.52637964
OS 52.86217012 -38.5273042
OS 52.87141572 -38.52915332
OS 52.88158588 -38.531927
OS 52.90377532 -38.53839892
OS 52.9157946 -38.54302172
OS 52.92781388 -38.54949364
OS 52.93983316 -38.55596556
OS 52.95185244 -38.56336204
OS 52.96294716 -38.57260764
OS 52.97404188 -38.5827778
OS 52.97496644 -38.58370236
OS 52.97681556 -38.58555148
OS 52.97958924 -38.58832516
OS 52.98328748 -38.59294796
OS 52.98791028 -38.59941988
OS 52.99253308 -38.6058918
OS 52.99808044 -38.61421284
OS 53.0036278 -38.62345844
OS 53.0082506 -38.6336286
OS 53.01379796 -38.64472332
OS 53.01842076 -38.65766716
OS 53.02304356 -38.670611
OS 53.0267418 -38.6844794
OS 53.02951548 -38.70019692
OS 53.0313646 -38.71591444
OS 53.03228916 -38.73255652
OS 53.03228916 -38.73348108
OS 53.03228916 -38.73625476
OS 53.03228916 -38.74087756
OS 53.0313646 -38.74734948
OS 53.03044004 -38.75474596
OS 53.02951548 -38.763067
OS 53.02766636 -38.77323716
OS 53.02581724 -38.78340732
OS 53.02026988 -38.80744588
OS 53.01102428 -38.832409
OS 53.00547692 -38.84535284
OS 52.99808044 -38.85737212
OS 52.99068396 -38.87031596
OS 52.98143836 -38.88233524
OS 52.9805138 -38.8832598
OS 52.97866468 -38.88603348
OS 52.97496644 -38.88973172
OS 52.97034364 -38.89435452
OS 52.96387172 -38.89990188
OS 52.95647524 -38.90729836
OS 52.94722964 -38.91377028
OS 52.93705948 -38.92116676
OS 52.92596476 -38.92856324
OS 52.91302092 -38.93503516
OS 52.89915252 -38.94150708
OS 52.88435956 -38.947979
OS 52.86864204 -38.9526018
OS 52.8510754 -38.95630004
OS 52.8325842 -38.95907372
OS 52.81316844 -38.95999828
OS 52.8048474 -38.95999828
OS 52.79837548 -38.95907372
OS 52.790979 -38.95814916
OS 52.78265796 -38.9572246
OS 52.7724878 -38.95630004
OS 52.76231764 -38.95352636
OS 52.73920364 -38.947979
OS 52.71608964 -38.93965796
OS 52.70407036 -38.9341106
OS 52.69205108 -38.92763868
OS 52.68095636 -38.9202422
OS 52.66986164 -38.91192116
OS 52.66893708 -38.9109966
OS 52.66708796 -38.91007204
OS 52.66523884 -38.9063738
OS 52.6615406 -38.90267556
OS 52.6569178 -38.89805276
OS 52.652295 -38.8925054
OS 52.64674764 -38.88510892
OS 52.64212484 -38.87678788
OS 52.63657748 -38.86846684
OS 52.63103012 -38.85829668
OS 52.62085996 -38.83610724
OS 52.61253892 -38.81021956
OS 52.60976524 -38.79635116
OS 52.60791612 -38.7815582
OS 52.69020196 -38.77508628
OS 52.69020196 -38.77601084
OS 52.69020196 -38.77785996
OS 52.69112652 -38.78063364
OS 52.69205108 -38.78525644
OS 52.69482476 -38.7954266
OS 52.698523 -38.809295
OS 52.70407036 -38.8231634
OS 52.71146684 -38.83888092
OS 52.72071244 -38.85274932
OS 52.73180716 -38.86569316
OS 52.73365628 -38.86661772
OS 52.73735452 -38.87031596
OS 52.744751 -38.87493876
OS 52.75492116 -38.88048612
OS 52.76601588 -38.88603348
OS 52.77988428 -38.89065628
OS 52.7956018 -38.89435452
OS 52.81316844 -38.89527908
OS 52.8187158 -38.89527908
OS 52.82241404 -38.89435452
OS 52.83350876 -38.89342996
OS 52.8464526 -38.88973172
OS 52.86217012 -38.88510892
OS 52.87788764 -38.87771244
OS 52.89452972 -38.86661772
OS 52.9019262 -38.8601458
OS 52.90932268 -38.85274932
OS 52.91024724 -38.85182476
OS 52.9111718 -38.8509002
OS 52.91302092 -38.84812652
OS 52.9157946 -38.84535284
OS 52.92226652 -38.83518268
OS 52.929663 -38.82223884
OS 52.93613492 -38.80652132
OS 52.94260684 -38.78710556
OS 52.94722964 -38.76399156
OS 52.94907876 -38.75197228
OS 52.94907876 -38.73902844
OS 52.94907876 -38.73810388
OS 52.94907876 -38.73625476
OS 52.94907876 -38.73255652
OS 52.9481542 -38.72793372
OS 52.9481542 -38.72238636
OS 52.94722964 -38.71591444
OS 52.94445596 -38.70112148
OS 52.93983316 -38.68355484
OS 52.93336124 -38.6659882
OS 52.92411564 -38.64934612
OS 52.9111718 -38.6336286
OS 52.9111718 -38.63270404
OS 52.90932268 -38.63177948
OS 52.90469988 -38.62715668
OS 52.89637884 -38.62068476
OS 52.88528412 -38.61328828
OS 52.87049116 -38.60681636
OS 52.85384908 -38.60034444
OS 52.83443332 -38.59572164
OS 52.8233386 -38.59387252
OS 52.80577196 -38.59387252
OS 52.79837548 -38.59479708
OS 52.78912988 -38.59572164
OS 52.77803516 -38.59849532
OS 52.76694044 -38.601269
OS 52.75492116 -38.6058918
OS 52.74290188 -38.61143916
OS 52.74197732 -38.61236372
OS 52.73827908 -38.61421284
OS 52.73273172 -38.61883564
OS 52.72533524 -38.62345844
OS 52.71793876 -38.62993036
OS 52.71054228 -38.6382514
OS 52.70222124 -38.64657244
OS 52.69574932 -38.6567426
OS 52.62178452 -38.64657244
OS 52.68373004 -38.31742908
OS 53.00177868 -38.31742908
OS 53.00177868 -38.39231844
OE
OB 53.23846604 -38.57445676 I
OS 53.14878372 -38.57445676
OS 53.14878372 -38.48477444
OS 53.23846604 -38.48477444
OS 53.23846604 -38.57445676
OE
OB 54.48199924 -38.57445676 I
OS 54.39231692 -38.57445676
OS 54.39231692 -38.48477444
OS 54.48199924 -38.48477444
OS 54.48199924 -38.57445676
OE
OB 56.14990548 -38.3100326 I
OS 56.165623 -38.31095716
OS 56.18226508 -38.31188172
OS 56.1979826 -38.31373084
OS 56.211851 -38.31557996
OS 56.21370012 -38.31557996
OS 56.22017204 -38.31742908
OS 56.22849308 -38.3192782
OS 56.2395878 -38.32205188
OS 56.25160708 -38.32667468
OS 56.26455092 -38.33222204
OS 56.27841932 -38.33869396
OS 56.2904386 -38.34609044
OS 56.29228772 -38.347015
OS 56.29598596 -38.34978868
OS 56.30153332 -38.35533604
OS 56.3089298 -38.36180796
OS 56.31725084 -38.370129
OS 56.32557188 -38.38122372
OS 56.33481748 -38.393243
OS 56.34221396 -38.4071114
OS 56.34313852 -38.40896052
OS 56.34498764 -38.41358332
OS 56.34868588 -38.42190436
OS 56.35238412 -38.43299908
OS 56.3551578 -38.44594292
OS 56.35885604 -38.46073588
OS 56.36070516 -38.47737796
OS 56.36162972 -38.4949446
OS 56.36162972 -38.49586916
OS 56.36162972 -38.49864284
OS 56.36162972 -38.50234108
OS 56.36070516 -38.508813
OS 56.3597806 -38.51528492
OS 56.35885604 -38.52360596
OS 56.35700692 -38.53285156
OS 56.3551578 -38.54302172
OS 56.34868588 -38.5642866
OS 56.34498764 -38.57538132
OS 56.33944028 -38.5874006
OS 56.33296836 -38.59941988
OS 56.32649644 -38.6105146
OS 56.3181754 -38.62160932
OS 56.3089298 -38.63270404
OS 56.30800524 -38.6336286
OS 56.30615612 -38.63547772
OS 56.30338244 -38.6382514
OS 56.29875964 -38.64102508
OS 56.29321228 -38.64564788
OS 56.2858158 -38.65027068
OS 56.2765702 -38.65581804
OS 56.26640004 -38.66044084
OS 56.25438076 -38.6659882
OS 56.24051236 -38.67153556
OS 56.2257194 -38.67615836
OS 56.20815276 -38.6798566
OS 56.18966156 -38.68355484
OS 56.16932124 -38.68632852
OS 56.14620724 -38.68817764
OS 56.12216868 -38.6891022
OS 55.95852156 -38.6891022
OS 55.95852156 -38.94890356
OS 55.87346204 -38.94890356
OS 55.87346204 -38.30910804
OS 56.13603708 -38.30910804
OS 56.14990548 -38.3100326
OE
OB 57.07723916 -38.94890356 I
OS 56.99587788 -38.94890356
OS 56.99587788 -38.41358332
OS 56.80911676 -38.94890356
OS 56.73330284 -38.94890356
OS 56.54839084 -38.40433772
OS 56.54839084 -38.94890356
OS 56.46702956 -38.94890356
OS 56.46702956 -38.30910804
OS 56.59369428 -38.30910804
OS 56.74532212 -38.763067
OS 56.74532212 -38.76399156
OS 56.74624668 -38.76584068
OS 56.74717124 -38.76861436
OS 56.74902036 -38.77323716
OS 56.7527186 -38.78433188
OS 56.7573414 -38.79820028
OS 56.7619642 -38.8139178
OS 56.76751156 -38.82963532
OS 56.77213436 -38.84442828
OS 56.7758326 -38.85737212
OS 56.77675716 -38.855523
OS 56.77768172 -38.8509002
OS 56.7804554 -38.84257916
OS 56.78415364 -38.83148444
OS 56.78877644 -38.81669148
OS 56.79524836 -38.79912484
OS 56.80172028 -38.77878452
OS 56.81004132 -38.75474596
OS 56.96351828 -38.30910804
OS 57.07723916 -38.30910804
OS 57.07723916 -38.94890356
OE
OB 55.39084172 -38.94890356 I
OS 55.31225412 -38.94890356
OS 55.31225412 -38.4487166
OS 55.31132956 -38.44964116
OS 55.30670676 -38.4533394
OS 55.3011594 -38.45888676
OS 55.2919138 -38.46535868
OS 55.28174364 -38.47367972
OS 55.2687998 -38.48292532
OS 55.25400684 -38.49309548
OS 55.23736476 -38.50326564
OS 55.2364402 -38.50326564
OS 55.23551564 -38.5041902
OS 55.22996828 -38.50788844
OS 55.22072268 -38.51251124
OS 55.20962796 -38.5180586
OS 55.19668412 -38.52453052
OS 55.18281572 -38.53100244
OS 55.16894732 -38.53747436
OS 55.15507892 -38.54302172
OS 55.15507892 -38.4672078
OS 55.15600348 -38.4672078
OS 55.1578526 -38.46535868
OS 55.16155084 -38.46443412
OS 55.16617364 -38.46166044
OS 55.171721 -38.45888676
OS 55.17819292 -38.45518852
OS 55.19391044 -38.44594292
OS 55.21240164 -38.43577276
OS 55.23089284 -38.42282892
OS 55.2503086 -38.40803596
OS 55.26972436 -38.39231844
OS 55.27064892 -38.39139388
OS 55.27157348 -38.39046932
OS 55.27434716 -38.38769564
OS 55.2780454 -38.38492196
OS 55.28636644 -38.37567636
OS 55.29746116 -38.36458164
OS 55.30855588 -38.3516378
OS 55.32057516 -38.33684484
OS 55.33074532 -38.32205188
OS 55.33999092 -38.30633436
OS 55.39084172 -38.30633436
OS 55.39084172 -38.94890356
OE
OB 54.48199924 -38.94890356 I
OS 54.39231692 -38.94890356
OS 54.39231692 -38.85922124
OS 54.48199924 -38.85922124
OS 54.48199924 -38.94890356
OE
OB 54.825011 -38.30725892 I
OS 54.83703028 -38.30910804
OS 54.85089868 -38.31188172
OS 54.86569164 -38.31557996
OS 54.88140916 -38.32020276
OS 54.89620212 -38.32759924
OS 54.89712668 -38.32759924
OS 54.89805124 -38.3285238
OS 54.90267404 -38.33129748
OS 54.91007052 -38.33592028
OS 54.91931612 -38.3423922
OS 54.92948628 -38.3516378
OS 54.940581 -38.36180796
OS 54.95075116 -38.37382724
OS 54.96092132 -38.38769564
OS 54.96184588 -38.38954476
OS 54.96554412 -38.39416756
OS 54.96924236 -38.4024886
OS 54.97571428 -38.41450788
OS 54.98126164 -38.42837628
OS 54.98865812 -38.4440938
OS 54.99513004 -38.462585
OS 55.0006774 -38.48292532
OS 55.0006774 -38.48384988
OS 55.00160196 -38.485699
OS 55.00252652 -38.48847268
OS 55.00345108 -38.49309548
OS 55.00437564 -38.49864284
OS 55.0053002 -38.50511476
OS 55.00714932 -38.5134358
OS 55.00807388 -38.5226814
OS 55.009923 -38.53285156
OS 55.01084756 -38.54394628
OS 55.01177212 -38.55689012
OS 55.01362124 -38.56983396
OS 55.0145458 -38.58462692
OS 55.0145458 -38.59941988
OS 55.01547036 -38.61606196
OS 55.01547036 -38.6336286
OS 55.01547036 -38.63455316
OS 55.01547036 -38.6382514
OS 55.01547036 -38.64472332
OS 55.01547036 -38.6521198
OS 55.0145458 -38.66228996
OS 55.0145458 -38.67338468
OS 55.01362124 -38.68540396
OS 55.01269668 -38.6983478
OS 55.009923 -38.72793372
OS 55.0053002 -38.7584442
OS 54.99975284 -38.78803012
OS 54.9960546 -38.80189852
OS 54.9914318 -38.81576692
OS 54.9914318 -38.81669148
OS 54.99050724 -38.8185406
OS 54.98865812 -38.82223884
OS 54.986809 -38.82686164
OS 54.98495988 -38.83333356
OS 54.98126164 -38.83980548
OS 54.97386516 -38.855523
OS 54.96461956 -38.87216508
OS 54.95260028 -38.89065628
OS 54.93873188 -38.90729836
OS 54.9220898 -38.92301588
OS 54.92116524 -38.92301588
OS 54.92024068 -38.924865
OS 54.917467 -38.92671412
OS 54.91376876 -38.92856324
OS 54.90914596 -38.93133692
OS 54.90452316 -38.93503516
OS 54.89065476 -38.94150708
OS 54.87401268 -38.947979
OS 54.85459692 -38.95445092
OS 54.83148292 -38.95814916
OS 54.8065198 -38.95999828
OS 54.7972742 -38.95999828
OS 54.79080228 -38.95907372
OS 54.7834058 -38.95814916
OS 54.7741602 -38.95630004
OS 54.76399004 -38.95445092
OS 54.75289532 -38.95167724
OS 54.7418006 -38.947979
OS 54.72978132 -38.94428076
OS 54.71776204 -38.9387334
OS 54.70574276 -38.93226148
OS 54.69372348 -38.924865
OS 54.6817042 -38.9156194
OS 54.67060948 -38.90544924
OS 54.66043932 -38.89435452
OS 54.65951476 -38.89342996
OS 54.65766564 -38.89065628
OS 54.65489196 -38.88603348
OS 54.65026916 -38.878637
OS 54.64564636 -38.87031596
OS 54.64102356 -38.85922124
OS 54.63455164 -38.8462774
OS 54.62900428 -38.83148444
OS 54.62345692 -38.81484236
OS 54.61790956 -38.7954266
OS 54.6123622 -38.77416172
OS 54.6077394 -38.75012316
OS 54.6031166 -38.72423548
OS 54.60034292 -38.69649868
OS 54.5984938 -38.6659882
OS 54.59756924 -38.6336286
OS 54.59756924 -38.63270404
OS 54.59756924 -38.6290058
OS 54.59756924 -38.62253388
OS 54.59756924 -38.6151374
OS 54.5984938 -38.60496724
OS 54.5984938 -38.59387252
OS 54.59941836 -38.58185324
OS 54.60034292 -38.56798484
OS 54.6031166 -38.53932348
OS 54.6077394 -38.508813
OS 54.61328676 -38.47830252
OS 54.616985 -38.46443412
OS 54.62068324 -38.45056572
OS 54.62068324 -38.44964116
OS 54.6216078 -38.44779204
OS 54.62345692 -38.4440938
OS 54.62530604 -38.439471
OS 54.62715516 -38.43299908
OS 54.6308534 -38.42652716
OS 54.63824988 -38.41080964
OS 54.64749548 -38.39416756
OS 54.65951476 -38.37660092
OS 54.67338316 -38.35903428
OS 54.69002524 -38.34424132
OS 54.6909498 -38.34424132
OS 54.69187436 -38.3423922
OS 54.69464804 -38.34054308
OS 54.69834628 -38.33869396
OS 54.70296908 -38.33499572
OS 54.70851644 -38.33222204
OS 54.72238484 -38.32482556
OS 54.73902692 -38.31835364
OS 54.75844268 -38.31188172
OS 54.78155668 -38.30818348
OS 54.8065198 -38.30633436
OS 54.81484084 -38.30633436
OS 54.825011 -38.30725892
OE
OB 49.95350436 -38.72331092 I
OS 50.040413 -38.72331092
OS 50.040413 -38.7954266
OS 49.95350436 -38.7954266
OS 49.95350436 -38.94890356
OS 49.87491676 -38.94890356
OS 49.87491676 -38.7954266
OS 49.5966242 -38.7954266
OS 49.5966242 -38.72331092
OS 49.88970972 -38.30910804
OS 49.95350436 -38.30910804
OS 49.95350436 -38.72331092
OE
OB 50.1467374 -38.95999828 I
OS 50.08386732 -38.95999828
OS 50.26970388 -38.29801332
OS 50.33257396 -38.29801332
OS 50.1467374 -38.95999828
OE
OB 50.59699812 -38.30725892 I
OS 50.6043946 -38.30818348
OS 50.6136402 -38.30910804
OS 50.62381036 -38.31095716
OS 50.63398052 -38.31280628
OS 50.65801908 -38.3192782
OS 50.68205764 -38.3285238
OS 50.69407692 -38.33407116
OS 50.7060962 -38.34054308
OS 50.71719092 -38.34886412
OS 50.72736108 -38.35810972
OS 50.72828564 -38.35903428
OS 50.73013476 -38.35995884
OS 50.73198388 -38.36365708
OS 50.73568212 -38.36735532
OS 50.74030492 -38.37197812
OS 50.74492772 -38.37845004
OS 50.74955052 -38.38492196
OS 50.75509788 -38.393243
OS 50.76434348 -38.41080964
OS 50.77358908 -38.43299908
OS 50.77728732 -38.4440938
OS 50.77913644 -38.45703764
OS 50.78098556 -38.46998148
OS 50.78191012 -38.48384988
OS 50.78191012 -38.485699
OS 50.78191012 -38.4903218
OS 50.78098556 -38.49771828
OS 50.780061 -38.50788844
OS 50.77821188 -38.51898316
OS 50.77451364 -38.531927
OS 50.7708154 -38.5457954
OS 50.76526804 -38.5596638
OS 50.76434348 -38.56151292
OS 50.76249436 -38.56613572
OS 50.75879612 -38.5735322
OS 50.75324876 -38.58370236
OS 50.74585228 -38.59479708
OS 50.73660668 -38.60866548
OS 50.72551196 -38.62253388
OS 50.71256812 -38.6382514
OS 50.710719 -38.64010052
OS 50.7060962 -38.64564788
OS 50.7014734 -38.65027068
OS 50.6968506 -38.65489348
OS 50.69130324 -38.66044084
OS 50.68390676 -38.66783732
OS 50.67651028 -38.6752338
OS 50.66726468 -38.68355484
OS 50.65801908 -38.69280044
OS 50.64692436 -38.7029706
OS 50.63490508 -38.71314076
OS 50.62196124 -38.72516004
OS 50.60716828 -38.73717932
OS 50.59237532 -38.75012316
OS 50.59145076 -38.75104772
OS 50.58960164 -38.75289684
OS 50.5859034 -38.75567052
OS 50.5812806 -38.75936876
OS 50.57573324 -38.76491612
OS 50.56926132 -38.77046348
OS 50.55446836 -38.78248276
OS 50.53875084 -38.79635116
OS 50.52395788 -38.81021956
OS 50.51101404 -38.82223884
OS 50.50546668 -38.82686164
OS 50.50084388 -38.83148444
OS 50.49991932 -38.832409
OS 50.49714564 -38.83518268
OS 50.4934474 -38.83888092
OS 50.4888246 -38.84442828
OS 50.4842018 -38.8509002
OS 50.47865444 -38.85737212
OS 50.46755972 -38.87308964
OS 50.78283468 -38.87308964
OS 50.78283468 -38.94890356
OS 50.35846164 -38.94890356
OS 50.35846164 -38.947979
OS 50.35846164 -38.94428076
OS 50.35846164 -38.9387334
OS 50.3593862 -38.93133692
OS 50.36031076 -38.92301588
OS 50.36215988 -38.91377028
OS 50.364009 -38.90452468
OS 50.36770724 -38.89435452
OS 50.36770724 -38.89342996
OS 50.3686318 -38.8925054
OS 50.37048092 -38.88695804
OS 50.37417916 -38.878637
OS 50.37972652 -38.86754228
OS 50.387123 -38.85459844
OS 50.3963686 -38.83980548
OS 50.40653876 -38.82501252
OS 50.4194826 -38.809295
OS 50.4194826 -38.80837044
OS 50.42133172 -38.80744588
OS 50.42595452 -38.80189852
OS 50.43427556 -38.79357748
OS 50.44629484 -38.7815582
OS 50.46016324 -38.7676898
OS 50.47772988 -38.75104772
OS 50.49899476 -38.73255652
OS 50.52210876 -38.71314076
OS 50.52303332 -38.7122162
OS 50.52673156 -38.70944252
OS 50.53227892 -38.70481972
OS 50.53875084 -38.69927236
OS 50.54707188 -38.69187588
OS 50.55724204 -38.68355484
OS 50.5674122 -38.67430924
OS 50.57943148 -38.66413908
OS 50.60254548 -38.64194964
OS 50.62565948 -38.6197602
OS 50.6367542 -38.60866548
OS 50.64692436 -38.59757076
OS 50.65616996 -38.5874006
OS 50.66356644 -38.57723044
OS 50.66356644 -38.57630588
OS 50.66541556 -38.57538132
OS 50.66726468 -38.57260764
OS 50.6691138 -38.5689094
OS 50.67558572 -38.55873924
OS 50.6829822 -38.54671996
OS 50.68945412 -38.531927
OS 50.69592604 -38.51620948
OS 50.69962428 -38.49864284
OS 50.7014734 -38.48200076
OS 50.7014734 -38.4810762
OS 50.7014734 -38.48015164
OS 50.70054884 -38.47460428
OS 50.69962428 -38.46535868
OS 50.6968506 -38.45518852
OS 50.69315236 -38.44224468
OS 50.68668044 -38.42930084
OS 50.6783594 -38.416357
OS 50.66726468 -38.40341316
OS 50.66541556 -38.40156404
OS 50.66079276 -38.3978658
OS 50.65432084 -38.393243
OS 50.64415068 -38.38677108
OS 50.63120684 -38.38122372
OS 50.61641388 -38.37567636
OS 50.59884724 -38.37197812
OS 50.57943148 -38.37105356
OS 50.57388412 -38.37105356
OS 50.57018588 -38.37197812
OS 50.55909116 -38.37290268
OS 50.54614732 -38.37567636
OS 50.53227892 -38.3793746
OS 50.5165614 -38.38584652
OS 50.50176844 -38.39416756
OS 50.48790004 -38.40526228
OS 50.48605092 -38.4071114
OS 50.48235268 -38.4117342
OS 50.47680532 -38.41913068
OS 50.47125796 -38.4302254
OS 50.46478604 -38.44316924
OS 50.45923868 -38.45981132
OS 50.45554044 -38.47830252
OS 50.45369132 -38.4995674
OS 50.3732546 -38.49124636
OS 50.3732546 -38.4903218
OS 50.37417916 -38.48754812
OS 50.37417916 -38.48292532
OS 50.37510372 -38.4764534
OS 50.37695284 -38.46905692
OS 50.37880196 -38.46073588
OS 50.38157564 -38.45056572
OS 50.38434932 -38.44039556
OS 50.3917458 -38.41820612
OS 50.40284052 -38.39601668
OS 50.40931244 -38.38492196
OS 50.41763348 -38.37382724
OS 50.42595452 -38.36365708
OS 50.43520012 -38.35441148
OS 50.43612468 -38.35348692
OS 50.4379738 -38.35256236
OS 50.44074748 -38.34978868
OS 50.44537028 -38.347015
OS 50.45091764 -38.34331676
OS 50.45738956 -38.33961852
OS 50.46478604 -38.33499572
OS 50.47403164 -38.33037292
OS 50.4842018 -38.32575012
OS 50.49529652 -38.32112732
OS 50.5073158 -38.31742908
OS 50.52025964 -38.31373084
OS 50.53412804 -38.31095716
OS 50.548921 -38.30818348
OS 50.56463852 -38.30725892
OS 50.5812806 -38.30633436
OS 50.5905262 -38.30633436
OS 50.59699812 -38.30725892
OE
OB 48.67576244 -38.94890356 I
OS 48.59717484 -38.94890356
OS 48.59717484 -38.4487166
OS 48.59625028 -38.44964116
OS 48.59162748 -38.4533394
OS 48.58608012 -38.45888676
OS 48.57683452 -38.46535868
OS 48.56666436 -38.47367972
OS 48.55372052 -38.48292532
OS 48.53892756 -38.49309548
OS 48.52228548 -38.50326564
OS 48.52136092 -38.50326564
OS 48.52043636 -38.5041902
OS 48.514889 -38.50788844
OS 48.5056434 -38.51251124
OS 48.49454868 -38.5180586
OS 48.48160484 -38.52453052
OS 48.46773644 -38.53100244
OS 48.45386804 -38.53747436
OS 48.43999964 -38.54302172
OS 48.43999964 -38.4672078
OS 48.4409242 -38.4672078
OS 48.44277332 -38.46535868
OS 48.44647156 -38.46443412
OS 48.45109436 -38.46166044
OS 48.45664172 -38.45888676
OS 48.46311364 -38.45518852
OS 48.47883116 -38.44594292
OS 48.49732236 -38.43577276
OS 48.51581356 -38.42282892
OS 48.53522932 -38.40803596
OS 48.55464508 -38.39231844
OS 48.55556964 -38.39139388
OS 48.5564942 -38.39046932
OS 48.55926788 -38.38769564
OS 48.56296612 -38.38492196
OS 48.57128716 -38.37567636
OS 48.58238188 -38.36458164
OS 48.5934766 -38.3516378
OS 48.60549588 -38.33684484
OS 48.61566604 -38.32205188
OS 48.62491164 -38.30633436
OS 48.67576244 -38.30633436
OS 48.67576244 -38.94890356
OE
OB 48.9032042 -38.95999828 I
OS 48.84033412 -38.95999828
OS 49.02617068 -38.29801332
OS 49.08904076 -38.29801332
OS 48.9032042 -38.95999828
OE
OB 49.35346492 -38.30725892 I
OS 49.3608614 -38.30818348
OS 49.370107 -38.30910804
OS 49.38027716 -38.31095716
OS 49.39044732 -38.31280628
OS 49.41448588 -38.3192782
OS 49.43852444 -38.3285238
OS 49.45054372 -38.33407116
OS 49.462563 -38.34054308
OS 49.47365772 -38.34886412
OS 49.48382788 -38.35810972
OS 49.48475244 -38.35903428
OS 49.48660156 -38.35995884
OS 49.48845068 -38.36365708
OS 49.49214892 -38.36735532
OS 49.49677172 -38.37197812
OS 49.50139452 -38.37845004
OS 49.50601732 -38.38492196
OS 49.51156468 -38.393243
OS 49.52081028 -38.41080964
OS 49.53005588 -38.43299908
OS 49.53375412 -38.4440938
OS 49.53560324 -38.45703764
OS 49.53745236 -38.46998148
OS 49.53837692 -38.48384988
OS 49.53837692 -38.485699
OS 49.53837692 -38.4903218
OS 49.53745236 -38.49771828
OS 49.5365278 -38.50788844
OS 49.53467868 -38.51898316
OS 49.53098044 -38.531927
OS 49.5272822 -38.5457954
OS 49.52173484 -38.5596638
OS 49.52081028 -38.56151292
OS 49.51896116 -38.56613572
OS 49.51526292 -38.5735322
OS 49.50971556 -38.58370236
OS 49.50231908 -38.59479708
OS 49.49307348 -38.60866548
OS 49.48197876 -38.62253388
OS 49.46903492 -38.6382514
OS 49.4671858 -38.64010052
OS 49.462563 -38.64564788
OS 49.4579402 -38.65027068
OS 49.4533174 -38.65489348
OS 49.44777004 -38.66044084
OS 49.44037356 -38.66783732
OS 49.43297708 -38.6752338
OS 49.42373148 -38.68355484
OS 49.41448588 -38.69280044
OS 49.40339116 -38.7029706
OS 49.39137188 -38.71314076
OS 49.37842804 -38.72516004
OS 49.36363508 -38.73717932
OS 49.34884212 -38.75012316
OS 49.34791756 -38.75104772
OS 49.34606844 -38.75289684
OS 49.3423702 -38.75567052
OS 49.3377474 -38.75936876
OS 49.33220004 -38.76491612
OS 49.32572812 -38.77046348
OS 49.31093516 -38.78248276
OS 49.29521764 -38.79635116
OS 49.28042468 -38.81021956
OS 49.26748084 -38.82223884
OS 49.26193348 -38.82686164
OS 49.25731068 -38.83148444
OS 49.25638612 -38.832409
OS 49.25361244 -38.83518268
OS 49.2499142 -38.83888092
OS 49.2452914 -38.84442828
OS 49.2406686 -38.8509002
OS 49.23512124 -38.85737212
OS 49.22402652 -38.87308964
OS 49.53930148 -38.87308964
OS 49.53930148 -38.94890356
OS 49.11492844 -38.94890356
OS 49.11492844 -38.947979
OS 49.11492844 -38.94428076
OS 49.11492844 -38.9387334
OS 49.115853 -38.93133692
OS 49.11677756 -38.92301588
OS 49.11862668 -38.91377028
OS 49.1204758 -38.90452468
OS 49.12417404 -38.89435452
OS 49.12417404 -38.89342996
OS 49.1250986 -38.8925054
OS 49.12694772 -38.88695804
OS 49.13064596 -38.878637
OS 49.13619332 -38.86754228
OS 49.1435898 -38.85459844
OS 49.1528354 -38.83980548
OS 49.16300556 -38.82501252
OS 49.1759494 -38.809295
OS 49.1759494 -38.80837044
OS 49.17779852 -38.80744588
OS 49.18242132 -38.80189852
OS 49.19074236 -38.79357748
OS 49.20276164 -38.7815582
OS 49.21663004 -38.7676898
OS 49.23419668 -38.75104772
OS 49.25546156 -38.73255652
OS 49.27857556 -38.71314076
OS 49.27950012 -38.7122162
OS 49.28319836 -38.70944252
OS 49.28874572 -38.70481972
OS 49.29521764 -38.69927236
OS 49.30353868 -38.69187588
OS 49.31370884 -38.68355484
OS 49.323879 -38.67430924
OS 49.33589828 -38.66413908
OS 49.35901228 -38.64194964
OS 49.38212628 -38.6197602
OS 49.393221 -38.60866548
OS 49.40339116 -38.59757076
OS 49.41263676 -38.5874006
OS 49.42003324 -38.57723044
OS 49.42003324 -38.57630588
OS 49.42188236 -38.57538132
OS 49.42373148 -38.57260764
OS 49.4255806 -38.5689094
OS 49.43205252 -38.55873924
OS 49.439449 -38.54671996
OS 49.44592092 -38.531927
OS 49.45239284 -38.51620948
OS 49.45609108 -38.49864284
OS 49.4579402 -38.48200076
OS 49.4579402 -38.4810762
OS 49.4579402 -38.48015164
OS 49.45701564 -38.47460428
OS 49.45609108 -38.46535868
OS 49.4533174 -38.45518852
OS 49.44961916 -38.44224468
OS 49.44314724 -38.42930084
OS 49.4348262 -38.416357
OS 49.42373148 -38.40341316
OS 49.42188236 -38.40156404
OS 49.41725956 -38.3978658
OS 49.41078764 -38.393243
OS 49.40061748 -38.38677108
OS 49.38767364 -38.38122372
OS 49.37288068 -38.37567636
OS 49.35531404 -38.37197812
OS 49.33589828 -38.37105356
OS 49.33035092 -38.37105356
OS 49.32665268 -38.37197812
OS 49.31555796 -38.37290268
OS 49.30261412 -38.37567636
OS 49.28874572 -38.3793746
OS 49.2730282 -38.38584652
OS 49.25823524 -38.39416756
OS 49.24436684 -38.40526228
OS 49.24251772 -38.4071114
OS 49.23881948 -38.4117342
OS 49.23327212 -38.41913068
OS 49.22772476 -38.4302254
OS 49.22125284 -38.44316924
OS 49.21570548 -38.45981132
OS 49.21200724 -38.47830252
OS 49.21015812 -38.4995674
OS 49.1297214 -38.49124636
OS 49.1297214 -38.4903218
OS 49.13064596 -38.48754812
OS 49.13064596 -38.48292532
OS 49.13157052 -38.4764534
OS 49.13341964 -38.46905692
OS 49.13526876 -38.46073588
OS 49.13804244 -38.45056572
OS 49.14081612 -38.44039556
OS 49.1482126 -38.41820612
OS 49.15930732 -38.39601668
OS 49.16577924 -38.38492196
OS 49.17410028 -38.37382724
OS 49.18242132 -38.36365708
OS 49.19166692 -38.35441148
OS 49.19259148 -38.35348692
OS 49.1944406 -38.35256236
OS 49.19721428 -38.34978868
OS 49.20183708 -38.347015
OS 49.20738444 -38.34331676
OS 49.21385636 -38.33961852
OS 49.22125284 -38.33499572
OS 49.23049844 -38.33037292
OS 49.2406686 -38.32575012
OS 49.25176332 -38.32112732
OS 49.2637826 -38.31742908
OS 49.27672644 -38.31373084
OS 49.29059484 -38.31095716
OS 49.3053878 -38.30818348
OS 49.32110532 -38.30725892
OS 49.3377474 -38.30633436
OS 49.346993 -38.30633436
OS 49.35346492 -38.30725892
OE
OB 51.0944114 -38.30725892 I
OS 51.10643068 -38.30910804
OS 51.12029908 -38.31188172
OS 51.13509204 -38.31557996
OS 51.15080956 -38.32020276
OS 51.16560252 -38.32759924
OS 51.16652708 -38.32759924
OS 51.16745164 -38.3285238
OS 51.17207444 -38.33129748
OS 51.17947092 -38.33592028
OS 51.18871652 -38.3423922
OS 51.19888668 -38.3516378
OS 51.2099814 -38.36180796
OS 51.22015156 -38.37382724
OS 51.23032172 -38.38769564
OS 51.23124628 -38.38954476
OS 51.23494452 -38.39416756
OS 51.23864276 -38.4024886
OS 51.24511468 -38.41450788
OS 51.25066204 -38.42837628
OS 51.25805852 -38.4440938
OS 51.26453044 -38.462585
OS 51.2700778 -38.48292532
OS 51.2700778 -38.48384988
OS 51.27100236 -38.485699
OS 51.27192692 -38.48847268
OS 51.27285148 -38.49309548
OS 51.27377604 -38.49864284
OS 51.2747006 -38.50511476
OS 51.27654972 -38.5134358
OS 51.27747428 -38.5226814
OS 51.2793234 -38.53285156
OS 51.28024796 -38.54394628
OS 51.28117252 -38.55689012
OS 51.28302164 -38.56983396
OS 51.2839462 -38.58462692
OS 51.2839462 -38.59941988
OS 51.28487076 -38.61606196
OS 51.28487076 -38.6336286
OS 51.28487076 -38.63455316
OS 51.28487076 -38.6382514
OS 51.28487076 -38.64472332
OS 51.28487076 -38.6521198
OS 51.2839462 -38.66228996
OS 51.2839462 -38.67338468
OS 51.28302164 -38.68540396
OS 51.28209708 -38.6983478
OS 51.2793234 -38.72793372
OS 51.2747006 -38.7584442
OS 51.26915324 -38.78803012
OS 51.265455 -38.80189852
OS 51.2608322 -38.81576692
OS 51.2608322 -38.81669148
OS 51.25990764 -38.8185406
OS 51.25805852 -38.82223884
OS 51.2562094 -38.82686164
OS 51.25436028 -38.83333356
OS 51.25066204 -38.83980548
OS 51.24326556 -38.855523
OS 51.23401996 -38.87216508
OS 51.22200068 -38.89065628
OS 51.20813228 -38.90729836
OS 51.1914902 -38.92301588
OS 51.19056564 -38.92301588
OS 51.18964108 -38.924865
OS 51.1868674 -38.92671412
OS 51.18316916 -38.92856324
OS 51.17854636 -38.93133692
OS 51.17392356 -38.93503516
OS 51.16005516 -38.94150708
OS 51.14341308 -38.947979
OS 51.12399732 -38.95445092
OS 51.10088332 -38.95814916
OS 51.0759202 -38.95999828
OS 51.0666746 -38.95999828
OS 51.06020268 -38.95907372
OS 51.0528062 -38.95814916
OS 51.0435606 -38.95630004
OS 51.03339044 -38.95445092
OS 51.02229572 -38.95167724
OS 51.011201 -38.947979
OS 50.99918172 -38.94428076
OS 50.98716244 -38.9387334
OS 50.97514316 -38.93226148
OS 50.96312388 -38.924865
OS 50.9511046 -38.9156194
OS 50.94000988 -38.90544924
OS 50.92983972 -38.89435452
OS 50.92891516 -38.89342996
OS 50.92706604 -38.89065628
OS 50.92429236 -38.88603348
OS 50.91966956 -38.878637
OS 50.91504676 -38.87031596
OS 50.91042396 -38.85922124
OS 50.90395204 -38.8462774
OS 50.89840468 -38.83148444
OS 50.89285732 -38.81484236
OS 50.88730996 -38.7954266
OS 50.8817626 -38.77416172
OS 50.8771398 -38.75012316
OS 50.872517 -38.72423548
OS 50.86974332 -38.69649868
OS 50.8678942 -38.6659882
OS 50.86696964 -38.6336286
OS 50.86696964 -38.63270404
OS 50.86696964 -38.6290058
OS 50.86696964 -38.62253388
OS 50.86696964 -38.6151374
OS 50.8678942 -38.60496724
OS 50.8678942 -38.59387252
OS 50.86881876 -38.58185324
OS 50.86974332 -38.56798484
OS 50.872517 -38.53932348
OS 50.8771398 -38.508813
OS 50.88268716 -38.47830252
OS 50.8863854 -38.46443412
OS 50.89008364 -38.45056572
OS 50.89008364 -38.44964116
OS 50.8910082 -38.44779204
OS 50.89285732 -38.4440938
OS 50.89470644 -38.439471
OS 50.89655556 -38.43299908
OS 50.9002538 -38.42652716
OS 50.90765028 -38.41080964
OS 50.91689588 -38.39416756
OS 50.92891516 -38.37660092
OS 50.94278356 -38.35903428
OS 50.95942564 -38.34424132
OS 50.9603502 -38.34424132
OS 50.96127476 -38.3423922
OS 50.96404844 -38.34054308
OS 50.96774668 -38.33869396
OS 50.97236948 -38.33499572
OS 50.97791684 -38.33222204
OS 50.99178524 -38.32482556
OS 51.00842732 -38.31835364
OS 51.02784308 -38.31188172
OS 51.05095708 -38.30818348
OS 51.0759202 -38.30633436
OS 51.08424124 -38.30633436
OS 51.0944114 -38.30725892
OE
OB 51.59182468 -38.30725892 I
OS 51.59922116 -38.30818348
OS 51.60846676 -38.30910804
OS 51.61863692 -38.31095716
OS 51.62880708 -38.31280628
OS 51.65284564 -38.3192782
OS 51.6768842 -38.3285238
OS 51.68890348 -38.33407116
OS 51.70092276 -38.34054308
OS 51.71201748 -38.34886412
OS 51.72218764 -38.35810972
OS 51.7231122 -38.35903428
OS 51.72496132 -38.35995884
OS 51.72681044 -38.36365708
OS 51.73050868 -38.36735532
OS 51.73513148 -38.37197812
OS 51.73975428 -38.37845004
OS 51.74437708 -38.38492196
OS 51.74992444 -38.393243
OS 51.75917004 -38.41080964
OS 51.76841564 -38.43299908
OS 51.77211388 -38.4440938
OS 51.773963 -38.45703764
OS 51.77581212 -38.46998148
OS 51.77673668 -38.48384988
OS 51.77673668 -38.485699
OS 51.77673668 -38.4903218
OS 51.77581212 -38.49771828
OS 51.77488756 -38.50788844
OS 51.77303844 -38.51898316
OS 51.7693402 -38.531927
OS 51.76564196 -38.5457954
OS 51.7600946 -38.5596638
OS 51.75917004 -38.56151292
OS 51.75732092 -38.56613572
OS 51.75362268 -38.5735322
OS 51.74807532 -38.58370236
OS 51.74067884 -38.59479708
OS 51.73143324 -38.60866548
OS 51.72033852 -38.62253388
OS 51.70739468 -38.6382514
OS 51.70554556 -38.64010052
OS 51.70092276 -38.64564788
OS 51.69629996 -38.65027068
OS 51.69167716 -38.65489348
OS 51.6861298 -38.66044084
OS 51.67873332 -38.66783732
OS 51.67133684 -38.6752338
OS 51.66209124 -38.68355484
OS 51.65284564 -38.69280044
OS 51.64175092 -38.7029706
OS 51.62973164 -38.71314076
OS 51.6167878 -38.72516004
OS 51.60199484 -38.73717932
OS 51.58720188 -38.75012316
OS 51.58627732 -38.75104772
OS 51.5844282 -38.75289684
OS 51.58072996 -38.75567052
OS 51.57610716 -38.75936876
OS 51.5705598 -38.76491612
OS 51.56408788 -38.77046348
OS 51.54929492 -38.78248276
OS 51.5335774 -38.79635116
OS 51.51878444 -38.81021956
OS 51.5058406 -38.82223884
OS 51.50029324 -38.82686164
OS 51.49567044 -38.83148444
OS 51.49474588 -38.832409
OS 51.4919722 -38.83518268
OS 51.48827396 -38.83888092
OS 51.48365116 -38.84442828
OS 51.47902836 -38.8509002
OS 51.473481 -38.85737212
OS 51.46238628 -38.87308964
OS 51.77766124 -38.87308964
OS 51.77766124 -38.94890356
OS 51.3532882 -38.94890356
OS 51.3532882 -38.947979
OS 51.3532882 -38.94428076
OS 51.3532882 -38.9387334
OS 51.35421276 -38.93133692
OS 51.35513732 -38.92301588
OS 51.35698644 -38.91377028
OS 51.35883556 -38.90452468
OS 51.3625338 -38.89435452
OS 51.3625338 -38.89342996
OS 51.36345836 -38.8925054
OS 51.36530748 -38.88695804
OS 51.36900572 -38.878637
OS 51.37455308 -38.86754228
OS 51.38194956 -38.85459844
OS 51.39119516 -38.83980548
OS 51.40136532 -38.82501252
OS 51.41430916 -38.809295
OS 51.41430916 -38.80837044
OS 51.41615828 -38.80744588
OS 51.42078108 -38.80189852
OS 51.42910212 -38.79357748
OS 51.4411214 -38.7815582
OS 51.4549898 -38.7676898
OS 51.47255644 -38.75104772
OS 51.49382132 -38.73255652
OS 51.51693532 -38.71314076
OS 51.51785988 -38.7122162
OS 51.52155812 -38.70944252
OS 51.52710548 -38.70481972
OS 51.5335774 -38.69927236
OS 51.54189844 -38.69187588
OS 51.5520686 -38.68355484
OS 51.56223876 -38.67430924
OS 51.57425804 -38.66413908
OS 51.59737204 -38.64194964
OS 51.62048604 -38.6197602
OS 51.63158076 -38.60866548
OS 51.64175092 -38.59757076
OS 51.65099652 -38.5874006
OS 51.658393 -38.57723044
OS 51.658393 -38.57630588
OS 51.66024212 -38.57538132
OS 51.66209124 -38.57260764
OS 51.66394036 -38.5689094
OS 51.67041228 -38.55873924
OS 51.67780876 -38.54671996
OS 51.68428068 -38.531927
OS 51.6907526 -38.51620948
OS 51.69445084 -38.49864284
OS 51.69629996 -38.48200076
OS 51.69629996 -38.4810762
OS 51.69629996 -38.48015164
OS 51.6953754 -38.47460428
OS 51.69445084 -38.46535868
OS 51.69167716 -38.45518852
OS 51.68797892 -38.44224468
OS 51.681507 -38.42930084
OS 51.67318596 -38.416357
OS 51.66209124 -38.40341316
OS 51.66024212 -38.40156404
OS 51.65561932 -38.3978658
OS 51.6491474 -38.393243
OS 51.63897724 -38.38677108
OS 51.6260334 -38.38122372
OS 51.61124044 -38.37567636
OS 51.5936738 -38.37197812
OS 51.57425804 -38.37105356
OS 51.56871068 -38.37105356
OS 51.56501244 -38.37197812
OS 51.55391772 -38.37290268
OS 51.54097388 -38.37567636
OS 51.52710548 -38.3793746
OS 51.51138796 -38.38584652
OS 51.496595 -38.39416756
OS 51.4827266 -38.40526228
OS 51.48087748 -38.4071114
OS 51.47717924 -38.4117342
OS 51.47163188 -38.41913068
OS 51.46608452 -38.4302254
OS 51.4596126 -38.44316924
OS 51.45406524 -38.45981132
OS 51.450367 -38.47830252
OS 51.44851788 -38.4995674
OS 51.36808116 -38.49124636
OS 51.36808116 -38.4903218
OS 51.36900572 -38.48754812
OS 51.36900572 -38.48292532
OS 51.36993028 -38.4764534
OS 51.3717794 -38.46905692
OS 51.37362852 -38.46073588
OS 51.3764022 -38.45056572
OS 51.37917588 -38.44039556
OS 51.38657236 -38.41820612
OS 51.39766708 -38.39601668
OS 51.404139 -38.38492196
OS 51.41246004 -38.37382724
OS 51.42078108 -38.36365708
OS 51.43002668 -38.35441148
OS 51.43095124 -38.35348692
OS 51.43280036 -38.35256236
OS 51.43557404 -38.34978868
OS 51.44019684 -38.347015
OS 51.4457442 -38.34331676
OS 51.45221612 -38.33961852
OS 51.4596126 -38.33499572
OS 51.4688582 -38.33037292
OS 51.47902836 -38.32575012
OS 51.49012308 -38.32112732
OS 51.50214236 -38.31742908
OS 51.5150862 -38.31373084
OS 51.5289546 -38.31095716
OS 51.54374756 -38.30818348
OS 51.55946508 -38.30725892
OS 51.57610716 -38.30633436
OS 51.58535276 -38.30633436
OS 51.59182468 -38.30725892
OE
OB 52.08184148 -38.30725892 I
OS 52.09386076 -38.30910804
OS 52.10865372 -38.31188172
OS 52.1252958 -38.31650452
OS 52.14193788 -38.32205188
OS 52.15857996 -38.32944836
OS 52.15950452 -38.32944836
OS 52.16042908 -38.33037292
OS 52.16597644 -38.3331466
OS 52.17429748 -38.33869396
OS 52.18354308 -38.34516588
OS 52.1946378 -38.35441148
OS 52.20573252 -38.36458164
OS 52.21682724 -38.37660092
OS 52.22607284 -38.39046932
OS 52.2269974 -38.39231844
OS 52.22977108 -38.39694124
OS 52.23346932 -38.40526228
OS 52.23809212 -38.41543244
OS 52.24271492 -38.42745172
OS 52.24641316 -38.44132012
OS 52.24918684 -38.45703764
OS 52.2501114 -38.47275516
OS 52.2501114 -38.47460428
OS 52.2501114 -38.48015164
OS 52.24918684 -38.48754812
OS 52.24733772 -38.49771828
OS 52.24456404 -38.50973756
OS 52.23994124 -38.5226814
OS 52.23439388 -38.53562524
OS 52.2269974 -38.54856908
OS 52.22607284 -38.5504182
OS 52.22329916 -38.55411644
OS 52.2177518 -38.56058836
OS 52.21035532 -38.56798484
OS 52.20110972 -38.57630588
OS 52.190015 -38.58555148
OS 52.17707116 -38.59387252
OS 52.16135364 -38.60219356
OS 52.1622782 -38.60219356
OS 52.16412732 -38.60311812
OS 52.166901 -38.60404268
OS 52.17059924 -38.60496724
OS 52.1807694 -38.60866548
OS 52.19371324 -38.61421284
OS 52.2085062 -38.62160932
OS 52.22329916 -38.63085492
OS 52.23716756 -38.6428742
OS 52.2501114 -38.6567426
OS 52.25103596 -38.65859172
OS 52.2547342 -38.66413908
OS 52.26028156 -38.67338468
OS 52.26582892 -38.68540396
OS 52.27137628 -38.70019692
OS 52.27692364 -38.71776356
OS 52.28062188 -38.73810388
OS 52.28154644 -38.76029332
OS 52.28154644 -38.76121788
OS 52.28154644 -38.76399156
OS 52.28154644 -38.76861436
OS 52.28062188 -38.77416172
OS 52.27969732 -38.7815582
OS 52.2778482 -38.78987924
OS 52.27599908 -38.79912484
OS 52.27414996 -38.809295
OS 52.26675348 -38.83148444
OS 52.26120612 -38.84350372
OS 52.25565876 -38.85459844
OS 52.24826228 -38.86661772
OS 52.23994124 -38.878637
OS 52.23069564 -38.89065628
OS 52.21960092 -38.901751
OS 52.21867636 -38.90267556
OS 52.21682724 -38.90452468
OS 52.213129 -38.90729836
OS 52.2085062 -38.9109966
OS 52.20295884 -38.9156194
OS 52.19556236 -38.9202422
OS 52.18724132 -38.92578956
OS 52.17707116 -38.93041236
OS 52.166901 -38.93595972
OS 52.15488172 -38.94150708
OS 52.14286244 -38.94612988
OS 52.12899404 -38.95075268
OS 52.11420108 -38.95445092
OS 52.09848356 -38.9572246
OS 52.08276604 -38.95907372
OS 52.0651994 -38.95999828
OS 52.05687836 -38.95999828
OS 52.051331 -38.95907372
OS 52.04393452 -38.95814916
OS 52.03561348 -38.9572246
OS 52.02636788 -38.95537548
OS 52.01619772 -38.95352636
OS 51.99400828 -38.947979
OS 51.97089428 -38.9387334
OS 51.958875 -38.93318604
OS 51.94778028 -38.92671412
OS 51.93668556 -38.91839308
OS 51.92559084 -38.91007204
OS 51.92466628 -38.90914748
OS 51.92281716 -38.90729836
OS 51.92004348 -38.90452468
OS 51.9172698 -38.90082644
OS 51.912647 -38.89620364
OS 51.9080242 -38.88973172
OS 51.90247684 -38.8832598
OS 51.89692948 -38.87493876
OS 51.89138212 -38.86569316
OS 51.88583476 -38.85644756
OS 51.8756646 -38.83425812
OS 51.86734356 -38.80837044
OS 51.86456988 -38.79450204
OS 51.86272076 -38.77970908
OS 51.94130836 -38.76953892
OS 51.94130836 -38.77046348
OS 51.94223292 -38.7723126
OS 51.94315748 -38.77601084
OS 51.94408204 -38.78063364
OS 51.9450066 -38.786181
OS 51.94685572 -38.79265292
OS 51.95147852 -38.80652132
OS 51.95795044 -38.8231634
OS 51.96627148 -38.83888092
OS 51.97551708 -38.85367388
OS 51.9866118 -38.86661772
OS 51.98846092 -38.86754228
OS 51.99215916 -38.87124052
OS 51.99955564 -38.87586332
OS 52.00880124 -38.88048612
OS 52.01989596 -38.88603348
OS 52.03376436 -38.89065628
OS 52.04948188 -38.89435452
OS 52.06612396 -38.89527908
OS 52.07167132 -38.89527908
OS 52.07536956 -38.89435452
OS 52.08553972 -38.89342996
OS 52.09848356 -38.89065628
OS 52.11327652 -38.88603348
OS 52.12899404 -38.87956156
OS 52.14471156 -38.87031596
OS 52.15950452 -38.85737212
OS 52.16135364 -38.855523
OS 52.16597644 -38.84997564
OS 52.1715238 -38.8416546
OS 52.17892028 -38.83055988
OS 52.18631676 -38.81669148
OS 52.19186412 -38.80097396
OS 52.19648692 -38.78248276
OS 52.19833604 -38.76214244
OS 52.19833604 -38.76121788
OS 52.19833604 -38.75936876
OS 52.19833604 -38.75659508
OS 52.19741148 -38.75289684
OS 52.19648692 -38.74272668
OS 52.19371324 -38.7307074
OS 52.190015 -38.71591444
OS 52.18354308 -38.70112148
OS 52.17429748 -38.68632852
OS 52.1622782 -38.67246012
OS 52.16042908 -38.670611
OS 52.15580628 -38.66691276
OS 52.1484098 -38.6613654
OS 52.13823964 -38.65489348
OS 52.1252958 -38.64842156
OS 52.10957828 -38.6428742
OS 52.09201164 -38.63917596
OS 52.07259588 -38.63732684
OS 52.06427484 -38.63732684
OS 52.05780292 -38.6382514
OS 52.04948188 -38.63917596
OS 52.04023628 -38.64102508
OS 52.02914156 -38.6428742
OS 52.01712228 -38.64564788
OS 52.02636788 -38.57630588
OS 52.03099068 -38.57630588
OS 52.03468892 -38.57723044
OS 52.0467082 -38.57723044
OS 52.05687836 -38.57538132
OS 52.06889764 -38.5735322
OS 52.08276604 -38.57075852
OS 52.09848356 -38.56613572
OS 52.11327652 -38.5596638
OS 52.12899404 -38.55134276
OS 52.1299186 -38.55134276
OS 52.13084316 -38.5504182
OS 52.13546596 -38.54671996
OS 52.14193788 -38.54024804
OS 52.14933436 -38.531927
OS 52.15673084 -38.51990772
OS 52.16320276 -38.50603932
OS 52.16782556 -38.4903218
OS 52.16967468 -38.4810762
OS 52.16967468 -38.47090604
OS 52.16967468 -38.46998148
OS 52.16967468 -38.46905692
OS 52.16967468 -38.46350956
OS 52.16782556 -38.45611308
OS 52.16597644 -38.44594292
OS 52.1622782 -38.4348482
OS 52.1576554 -38.42282892
OS 52.15025892 -38.41080964
OS 52.14008876 -38.39971492
OS 52.1391642 -38.39879036
OS 52.1345414 -38.39509212
OS 52.12806948 -38.39046932
OS 52.11974844 -38.38492196
OS 52.10865372 -38.38029916
OS 52.09570988 -38.37567636
OS 52.08091692 -38.37197812
OS 52.06427484 -38.37105356
OS 52.05687836 -38.37105356
OS 52.04855732 -38.37290268
OS 52.0374626 -38.3747518
OS 52.02544332 -38.37845004
OS 52.01342404 -38.38307284
OS 52.0004802 -38.39046932
OS 51.98846092 -38.39971492
OS 51.98753636 -38.40063948
OS 51.98383812 -38.40526228
OS 51.97829076 -38.4117342
OS 51.97181884 -38.4209798
OS 51.96534692 -38.43299908
OS 51.958875 -38.44779204
OS 51.95332764 -38.46535868
OS 51.9496294 -38.485699
OS 51.8710418 -38.4718306
OS 51.8710418 -38.47090604
OS 51.87196636 -38.46813236
OS 51.87289092 -38.46443412
OS 51.87381548 -38.45888676
OS 51.8756646 -38.45241484
OS 51.87843828 -38.44501836
OS 51.88398564 -38.42745172
OS 51.89323124 -38.4071114
OS 51.90432596 -38.38677108
OS 51.91819436 -38.36735532
OS 51.935761 -38.34978868
OS 51.93668556 -38.34886412
OS 51.93853468 -38.34793956
OS 51.94130836 -38.34609044
OS 51.9450066 -38.34331676
OS 51.9496294 -38.33961852
OS 51.95610132 -38.33592028
OS 51.96257324 -38.33222204
OS 51.97089428 -38.32759924
OS 51.98938548 -38.32020276
OS 52.01065036 -38.31280628
OS 52.03561348 -38.30818348
OS 52.04855732 -38.30633436
OS 52.07167132 -38.30633436
OS 52.08184148 -38.30725892
OE
OB 56.14158444 -38.38492196 H
OS 55.95852156 -38.38492196
OS 55.95852156 -38.61328828
OS 56.13048972 -38.61328828
OS 56.13696164 -38.61236372
OS 56.14343356 -38.61236372
OS 56.15083004 -38.61143916
OS 56.16839668 -38.60959004
OS 56.18781244 -38.6058918
OS 56.2072282 -38.60034444
OS 56.22479484 -38.59294796
OS 56.23311588 -38.58832516
OS 56.2395878 -38.5827778
OS 56.24143692 -38.58092868
OS 56.24513516 -38.57723044
OS 56.25068252 -38.56983396
OS 56.25715444 -38.56058836
OS 56.26362636 -38.54856908
OS 56.26917372 -38.53377612
OS 56.27287196 -38.51713404
OS 56.27472108 -38.49771828
OS 56.27472108 -38.49679372
OS 56.27472108 -38.49586916
OS 56.27472108 -38.49124636
OS 56.27379652 -38.48292532
OS 56.2719474 -38.47367972
OS 56.27009828 -38.46350956
OS 56.26640004 -38.45149028
OS 56.26085268 -38.44039556
OS 56.25438076 -38.42930084
OS 56.2534562 -38.42837628
OS 56.25068252 -38.42467804
OS 56.24605972 -38.42005524
OS 56.24051236 -38.41358332
OS 56.23219132 -38.4071114
OS 56.22294572 -38.40156404
OS 56.21277556 -38.39601668
OS 56.20075628 -38.39139388
OS 56.19983172 -38.39139388
OS 56.19613348 -38.39046932
OS 56.19058612 -38.38954476
OS 56.18318964 -38.38769564
OS 56.17209492 -38.38677108
OS 56.15822652 -38.38584652
OS 56.14158444 -38.38492196
OE
OB 49.87491676 -38.43669732 H
OS 49.67336268 -38.72331092
OS 49.87491676 -38.72331092
OS 49.87491676 -38.43669732
OE
OB 54.06132444 -38.37105356 H
OS 54.05392796 -38.37105356
OS 54.04560692 -38.37290268
OS 54.0345122 -38.3747518
OS 54.02249292 -38.37845004
OS 54.00954908 -38.38307284
OS 53.9975298 -38.39046932
OS 53.98551052 -38.40063948
OS 53.98458596 -38.40156404
OS 53.98088772 -38.40526228
OS 53.97626492 -38.4117342
OS 53.97164212 -38.42005524
OS 53.96609476 -38.4302254
OS 53.96147196 -38.44224468
OS 53.95777372 -38.45518852
OS 53.95684916 -38.46998148
OS 53.95684916 -38.47090604
OS 53.95684916 -38.4718306
OS 53.95777372 -38.47737796
OS 53.95869828 -38.485699
OS 53.9605474 -38.49586916
OS 53.96424564 -38.50788844
OS 53.96886844 -38.51990772
OS 53.97626492 -38.53285156
OS 53.98551052 -38.54394628
OS 53.98643508 -38.54487084
OS 53.99105788 -38.54856908
OS 53.9975298 -38.55319188
OS 54.00585084 -38.55781468
OS 54.01694556 -38.56336204
OS 54.0298894 -38.56798484
OS 54.04468236 -38.57168308
OS 54.06132444 -38.57260764
OS 54.06317356 -38.57260764
OS 54.06872092 -38.57168308
OS 54.07704196 -38.57075852
OS 54.08813668 -38.5689094
OS 54.10015596 -38.56521116
OS 54.11217524 -38.56058836
OS 54.12511908 -38.55319188
OS 54.1362138 -38.54394628
OS 54.13713836 -38.54302172
OS 54.1408366 -38.53839892
OS 54.1454594 -38.53285156
OS 54.15100676 -38.52453052
OS 54.15655412 -38.51436036
OS 54.16117692 -38.50234108
OS 54.16487516 -38.48847268
OS 54.16579972 -38.47367972
OS 54.16579972 -38.47275516
OS 54.16579972 -38.4718306
OS 54.16579972 -38.46628324
OS 54.1639506 -38.4579622
OS 54.16210148 -38.44779204
OS 54.15840324 -38.43669732
OS 54.15285588 -38.42467804
OS 54.1454594 -38.41265876
OS 54.13528924 -38.40063948
OS 54.13436468 -38.39971492
OS 54.12974188 -38.39601668
OS 54.12326996 -38.39139388
OS 54.11494892 -38.38584652
OS 54.1038542 -38.38029916
OS 54.09183492 -38.37567636
OS 54.07704196 -38.37197812
OS 54.06132444 -38.37105356
OE
OB 54.05855076 -38.63640228 H
OS 54.0530034 -38.63640228
OS 54.04930516 -38.63732684
OS 54.039135 -38.6382514
OS 54.02619116 -38.64102508
OS 54.0113982 -38.64564788
OS 53.99660524 -38.6521198
OS 53.98088772 -38.6613654
OS 53.96701932 -38.67338468
OS 53.9651702 -38.6752338
OS 53.96147196 -38.6798566
OS 53.9559246 -38.68817764
OS 53.94945268 -38.6983478
OS 53.9420562 -38.7122162
OS 53.93650884 -38.72793372
OS 53.9328106 -38.74550036
OS 53.93096148 -38.76491612
OS 53.93096148 -38.76676524
OS 53.93096148 -38.77046348
OS 53.93188604 -38.7769354
OS 53.9328106 -38.78525644
OS 53.93465972 -38.7954266
OS 53.9374334 -38.80652132
OS 53.94113164 -38.81761604
OS 53.94575444 -38.82963532
OS 53.946679 -38.83055988
OS 53.94852812 -38.83518268
OS 53.95222636 -38.84073004
OS 53.95777372 -38.84720196
OS 53.96424564 -38.855523
OS 53.97256668 -38.86384404
OS 53.98181228 -38.87124052
OS 53.992907 -38.878637
OS 53.99475612 -38.87956156
OS 53.99845436 -38.88141068
OS 54.00492628 -38.88418436
OS 54.01324732 -38.88695804
OS 54.02341748 -38.88973172
OS 54.03543676 -38.8925054
OS 54.0483806 -38.89435452
OS 54.06132444 -38.89527908
OS 54.0668718 -38.89527908
OS 54.07057004 -38.89435452
OS 54.08166476 -38.89342996
OS 54.0946086 -38.89065628
OS 54.10940156 -38.88603348
OS 54.12511908 -38.88048612
OS 54.13991204 -38.87124052
OS 54.154705 -38.85922124
OS 54.15655412 -38.85737212
OS 54.16025236 -38.85274932
OS 54.16672428 -38.84442828
OS 54.1731962 -38.83425812
OS 54.17966812 -38.82131428
OS 54.18614004 -38.80559676
OS 54.18983828 -38.78710556
OS 54.1916874 -38.7676898
OS 54.1916874 -38.76676524
OS 54.1916874 -38.76491612
OS 54.1916874 -38.76214244
OS 54.19076284 -38.7584442
OS 54.18983828 -38.74827404
OS 54.1870646 -38.73440564
OS 54.1824418 -38.72053724
OS 54.17596988 -38.70481972
OS 54.16672428 -38.6891022
OS 54.15378044 -38.67430924
OS 54.15193132 -38.67246012
OS 54.14730852 -38.66876188
OS 54.13898748 -38.66228996
OS 54.12789276 -38.65489348
OS 54.11402436 -38.64842156
OS 54.09738228 -38.64194964
OS 54.07889108 -38.6382514
OS 54.05855076 -38.63640228
OE
OB 54.80559524 -38.37105356 H
OS 54.80004788 -38.37105356
OS 54.79634964 -38.37197812
OS 54.78617948 -38.37382724
OS 54.7741602 -38.37660092
OS 54.7602918 -38.38214828
OS 54.74549884 -38.39046932
OS 54.73810236 -38.39601668
OS 54.73070588 -38.40156404
OS 54.72423396 -38.40896052
OS 54.71776204 -38.41728156
OS 54.71776204 -38.41820612
OS 54.71591292 -38.42005524
OS 54.7140638 -38.42375348
OS 54.71129012 -38.42837628
OS 54.70851644 -38.43577276
OS 54.7048182 -38.4440938
OS 54.70204452 -38.45426396
OS 54.69834628 -38.46628324
OS 54.69464804 -38.48015164
OS 54.6909498 -38.49586916
OS 54.68725156 -38.5134358
OS 54.68447788 -38.53285156
OS 54.6817042 -38.555041
OS 54.67985508 -38.57907956
OS 54.67893052 -38.60496724
OS 54.67800596 -38.6336286
OS 54.67800596 -38.63547772
OS 54.67800596 -38.64010052
OS 54.67800596 -38.64842156
OS 54.67893052 -38.65951628
OS 54.67893052 -38.67153556
OS 54.67985508 -38.68632852
OS 54.68077964 -38.70204604
OS 54.68262876 -38.71868812
OS 54.68725156 -38.75474596
OS 54.69002524 -38.7723126
OS 54.69372348 -38.78895468
OS 54.69742172 -38.8046722
OS 54.70296908 -38.81946516
OS 54.70851644 -38.832409
OS 54.71498836 -38.84350372
OS 54.71498836 -38.84442828
OS 54.71683748 -38.84535284
OS 54.72146028 -38.85182476
OS 54.72978132 -38.8601458
OS 54.73995148 -38.8693914
OS 54.75381988 -38.878637
OS 54.7695374 -38.88695804
OS 54.78710404 -38.89342996
OS 54.79634964 -38.89435452
OS 54.8065198 -38.89527908
OS 54.81206716 -38.89527908
OS 54.8157654 -38.89435452
OS 54.825011 -38.8925054
OS 54.83795484 -38.88880716
OS 54.85182324 -38.88233524
OS 54.86754076 -38.87308964
OS 54.87493724 -38.86754228
OS 54.88233372 -38.8601458
OS 54.8897302 -38.85274932
OS 54.89712668 -38.84350372
OS 54.89712668 -38.84257916
OS 54.8989758 -38.84073004
OS 54.90082492 -38.83795636
OS 54.90267404 -38.83333356
OS 54.90637228 -38.82686164
OS 54.90914596 -38.8185406
OS 54.9128442 -38.809295
OS 54.91654244 -38.79820028
OS 54.91931612 -38.78433188
OS 54.92301436 -38.76953892
OS 54.9267126 -38.75197228
OS 54.92948628 -38.73348108
OS 54.9313354 -38.71129164
OS 54.93318452 -38.68817764
OS 54.93503364 -38.66228996
OS 54.93503364 -38.6336286
OS 54.93503364 -38.63270404
OS 54.93503364 -38.63177948
OS 54.93503364 -38.62715668
OS 54.93503364 -38.61883564
OS 54.93410908 -38.60774092
OS 54.93410908 -38.59572164
OS 54.93318452 -38.58092868
OS 54.93225996 -38.56521116
OS 54.93041084 -38.54764452
OS 54.92578804 -38.51251124
OS 54.92301436 -38.4949446
OS 54.91931612 -38.47830252
OS 54.91561788 -38.462585
OS 54.91007052 -38.44779204
OS 54.90452316 -38.4348482
OS 54.89805124 -38.42375348
OS 54.89805124 -38.42282892
OS 54.89620212 -38.42190436
OS 54.894353 -38.41913068
OS 54.89157932 -38.41543244
OS 54.88325828 -38.4071114
OS 54.87308812 -38.39694124
OS 54.85921972 -38.38769564
OS 54.8435022 -38.3793746
OS 54.83518116 -38.37567636
OS 54.82593556 -38.37290268
OS 54.8157654 -38.37197812
OS 54.80559524 -38.37105356
OE
OB 51.07499564 -38.37105356 H
OS 51.06944828 -38.37105356
OS 51.06575004 -38.37197812
OS 51.05557988 -38.37382724
OS 51.0435606 -38.37660092
OS 51.0296922 -38.38214828
OS 51.01489924 -38.39046932
OS 51.00750276 -38.39601668
OS 51.00010628 -38.40156404
OS 50.99363436 -38.40896052
OS 50.98716244 -38.41728156
OS 50.98716244 -38.41820612
OS 50.98531332 -38.42005524
OS 50.9834642 -38.42375348
OS 50.98069052 -38.42837628
OS 50.97791684 -38.43577276
OS 50.9742186 -38.4440938
OS 50.97144492 -38.45426396
OS 50.96774668 -38.46628324
OS 50.96404844 -38.48015164
OS 50.9603502 -38.49586916
OS 50.95665196 -38.5134358
OS 50.95387828 -38.53285156
OS 50.9511046 -38.555041
OS 50.94925548 -38.57907956
OS 50.94833092 -38.60496724
OS 50.94740636 -38.6336286
OS 50.94740636 -38.63547772
OS 50.94740636 -38.64010052
OS 50.94740636 -38.64842156
OS 50.94833092 -38.65951628
OS 50.94833092 -38.67153556
OS 50.94925548 -38.68632852
OS 50.95018004 -38.70204604
OS 50.95202916 -38.71868812
OS 50.95665196 -38.75474596
OS 50.95942564 -38.7723126
OS 50.96312388 -38.78895468
OS 50.96682212 -38.8046722
OS 50.97236948 -38.81946516
OS 50.97791684 -38.832409
OS 50.98438876 -38.84350372
OS 50.98438876 -38.84442828
OS 50.98623788 -38.84535284
OS 50.99086068 -38.85182476
OS 50.99918172 -38.8601458
OS 51.00935188 -38.8693914
OS 51.02322028 -38.878637
OS 51.0389378 -38.88695804
OS 51.05650444 -38.89342996
OS 51.06575004 -38.89435452
OS 51.0759202 -38.89527908
OS 51.08146756 -38.89527908
OS 51.0851658 -38.89435452
OS 51.0944114 -38.8925054
OS 51.10735524 -38.88880716
OS 51.12122364 -38.88233524
OS 51.13694116 -38.87308964
OS 51.14433764 -38.86754228
OS 51.15173412 -38.8601458
OS 51.1591306 -38.85274932
OS 51.16652708 -38.84350372
OS 51.16652708 -38.84257916
OS 51.1683762 -38.84073004
OS 51.17022532 -38.83795636
OS 51.17207444 -38.83333356
OS 51.17577268 -38.82686164
OS 51.17854636 -38.8185406
OS 51.1822446 -38.809295
OS 51.18594284 -38.79820028
OS 51.18871652 -38.78433188
OS 51.19241476 -38.76953892
OS 51.196113 -38.75197228
OS 51.19888668 -38.73348108
OS 51.2007358 -38.71129164
OS 51.20258492 -38.68817764
OS 51.20443404 -38.66228996
OS 51.20443404 -38.6336286
OS 51.20443404 -38.63270404
OS 51.20443404 -38.63177948
OS 51.20443404 -38.62715668
OS 51.20443404 -38.61883564
OS 51.20350948 -38.60774092
OS 51.20350948 -38.59572164
OS 51.20258492 -38.58092868
OS 51.20166036 -38.56521116
OS 51.19981124 -38.54764452
OS 51.19518844 -38.51251124
OS 51.19241476 -38.4949446
OS 51.18871652 -38.47830252
OS 51.18501828 -38.462585
OS 51.17947092 -38.44779204
OS 51.17392356 -38.4348482
OS 51.16745164 -38.42375348
OS 51.16745164 -38.42282892
OS 51.16560252 -38.42190436
OS 51.1637534 -38.41913068
OS 51.16097972 -38.41543244
OS 51.15265868 -38.4071114
OS 51.14248852 -38.39694124
OS 51.12862012 -38.38769564
OS 51.1129026 -38.3793746
OS 51.10458156 -38.37567636
OS 51.09533596 -38.37290268
OS 51.0851658 -38.37197812
OS 51.07499564 -38.37105356
OE
SE
P -2.99999908 16.00000102 27 P 0 0 ;0=21,1=1
P -2.99999908 17.99999956 27 P 0 0 ;0=21,1=1
P -2.99999908 20.00000064 27 P 0 0 ;0=21,1=1
P -2.99999908 21.99999918 27 P 0 0 ;0=21,1=1
P -2.99999908 24.00000026 27 P 0 0 ;0=21,1=1
P -2.99999908 25.9999988 27 P 0 0 ;0=21,1=1
P -2.99999908 27.99999988 27 P 0 0 ;0=21,1=1
P -2.99999908 30.00000096 27 P 0 0 ;0=21,1=1
P -2.99999908 31.9999995 27 P 0 0 ;0=21,1=1
P -2.99999908 34.00000058 27 P 0 0 ;0=21,1=1
P -2.99999908 35.99999912 27 P 0 0 ;0=21,1=1
P -2.99999908 38.0000002 27 P 0 0 ;0=21,1=1
P -2.99999908 39.99999874 27 P 0 0 ;0=21,1=1
P 0.50000154 -3.99999962 27 P 0 0 ;0=21,1=1
P 2.50000008 -3.99999962 27 P 0 0 ;0=21,1=1
P 4.50000116 -3.99999962 27 P 0 0 ;0=21,1=1
P 6.4999997 -3.99999962 27 P 0 0 ;0=21,1=1
P 8.50000078 -3.99999962 27 P 0 0 ;0=21,1=1
P 10.49999932 -3.99999962 27 P 0 0 ;0=21,1=1
P 12.5000004 -3.99999962 27 P 0 0 ;0=21,1=1
P 12.74500118 40.26499948 27 P 0 0 ;0=21,1=1
P 12.74500118 41.21500012 27 P 0 0 ;0=21,1=1
P 12.74500118 44.63999962 27 P 0 0 ;0=21,1=1
P 12.75500116 42.16500076 27 P 0 0 ;0=21,1=1
P 12.98999942 18.0150008 27 P 0 0 ;0=21,1=1
P 14.50000148 -3.99999962 27 P 0 0 ;0=21,1=1
P 15.88470534 21.56499878 27 P 0 0 ;0=21,1=1
P 16.30970576 23.03999964 27 P 0 0 ;0=21,1=1
P 16.50000002 -3.99999962 27 P 0 0 ;0=21,1=1
P 17.57500168 13.89000016 27 P 0 0 ;0=21,1=1
P 17.915001 15.69625258 27 P 0 0 ;0=21,1=1
P 18.8149992 15.10000028 27 P 0 0 ;0=21,1=1
P 18.8149992 15.98270108 27 P 0 0 ;0=21,1=1
P 18.8149992 16.85250122 27 P 0 0 ;0=21,1=1
P 19.01500134 7.39000046 27 P 0 0 ;0=21,1=1
P 19.01500134 8.5900006 27 P 0 0 ;0=21,1=1
P 19.01500134 9.7899982 27 P 0 0 ;0=21,1=1
P 19.01500134 11.09000068 27 P 0 0 ;0=21,1=1
P 19.01500134 12.39000062 27 P 0 0 ;0=21,1=1
P 21.11499968 6.76500044 27 P 0 0 ;0=21,1=1
P 21.11499968 7.78999966 27 P 0 0 ;0=21,1=1
P 21.11499968 8.9899998 27 P 0 0 ;0=21,1=1
P 21.11499968 10.28999974 27 P 0 0 ;0=21,1=1
P 21.11499968 11.38590052 27 P 0 0 ;0=21,1=1
P 22.05919388 12.29000082 27 P 0 0 ;0=21,1=1
P 22.45970616 20.01499934 27 P 0 0 ;0=21,1=1
P 23.29999912 38.90000094 27 P 0 0 ;0=21,1=1
P 23.33999904 44.0138312 27 P 0 0 ;0=21,1=1
P 23.4097068 20.04000056 27 P 0 0 ;0=21,1=1
P 24.35970744 20.04000056 27 P 0 0 ;0=21,1=1
P 24.49999926 -3.50000062 27 P 0 0 ;0=21,1=1
P 25.7999992 38.90000094 27 P 0 0 ;0=21,1=1
P 26.50000034 -3.50000062 27 P 0 0 ;0=21,1=1
P 28.50000142 -3.50000062 27 P 0 0 ;0=21,1=1
P 30.49999996 -3.50000062 27 P 0 0 ;0=21,1=1
P 32.50000104 -3.50000062 27 P 0 0 ;0=21,1=1
P 32.80000044 38.90000094 27 P 0 0 ;0=21,1=1
P 35.30000052 44.0000009 27 P 0 0 ;0=21,1=1
P 38.4999992 -3.50000062 27 P 0 0 ;0=21,1=1
P 39.60000208 38.91499964 27 P 0 0 ;0=21,1=1
P 40.50000028 -3.50000062 27 P 0 0 ;0=21,1=1
P 40.67999992 42.76499956 27 P 0 0 ;0=21,1=1
P 42.2249981 38.91499964 27 P 0 0 ;0=21,1=1
P 44.4999999 0.499999 27 P 0 0 ;0=21,1=1
P 44.4999999 2.50000008 27 P 0 0 ;0=21,1=1
P 44.4999999 4.49999862 27 P 0 0 ;0=21,1=1
P 44.4999999 6.4999997 27 P 0 0 ;0=21,1=1
P 44.4999999 8.49999824 27 P 0 0 ;0=21,1=1
P 44.4999999 10.49999932 27 P 0 0 ;0=21,1=1
P 44.4999999 12.49999786 27 P 0 0 ;0=21,1=1
P 44.4999999 14.49999894 27 P 0 0 ;0=21,1=1
P 44.4999999 16.50000002 27 P 0 0 ;0=21,1=1
P 44.4999999 18.49999856 27 P 0 0 ;0=21,1=1
P 44.4999999 20.49999964 27 P 0 0 ;0=21,1=1
P 44.4999999 22.49999818 27 P 0 0 ;0=21,1=1
P 44.4999999 24.49999926 27 P 0 0 ;0=21,1=1
P 44.4999999 26.4999978 27 P 0 0 ;0=21,1=1
P 44.4999999 28.49999888 27 P 0 0 ;0=21,1=1
P 44.4999999 30.49999996 27 P 0 0 ;0=21,1=1
P 44.4999999 32.4999985 27 P 0 0 ;0=21,1=1
P 44.4999999 34.49999958 27 P 0 0 ;0=21,1=1
P 44.4999999 36.49999812 27 P 0 0 ;0=21,1=1
P 44.4999999 38.4999992 27 P 0 0 ;0=21,1=1
P 44.4999999 40.49999774 27 P 0 0 ;0=21,1=1

### steps/pcb/layers/top_overlay/features
UNITS=MM
#Layer_Color=65535
#
#Feature symbol names
#
$0 r99.9998

#
#Feature attribute names
#
@0 .nomenclature
@1 .string
@2 .string_angle

#
#Feature attribute text strings
#

#
#Layer features
#
L -9.5600012 -24.45999934 40.4400004 -24.45999934 0 P 0
L -9.5600012 -35.9599992 -9.5600012 -24.45999934 0 P 0
L -9.5600012 -35.9599992 28.439999 -35.9599992 0 P 0
L -9.5600012 -39.45999982 -9.5600012 -35.9599992 0 P 0
L -9.5600012 -39.45999982 28.439999 -39.45999982 0 P 0
L -9.5600012 -42.96000044 -9.5600012 -39.45999982 0 P 0
L -9.5600012 -42.96000044 28.439999 -42.96000044 0 P 0
L -10.0600002 -23.96000034 62.93999858 -23.96000034 0 P 0
L -10.0600002 -43.45999944 -10.0600002 -23.96000034 0 P 0
L -10.0600002 -43.45999944 62.93999858 -43.45999944 0 P 0
L 28.439999 -35.96000174 45.44000056 -35.9599992 0 P 0
L 28.439999 -39.45999982 28.439999 -35.9599992 0 P 0
L 28.439999 -39.46000236 45.44000056 -39.45999982 0 P 0
L 28.439999 -42.96000044 28.439999 -39.45999982 0 P 0
L 28.439999 -42.96000298 45.44000056 -42.96000044 0 P 0
L 40.4400004 -24.45999934 62.43999958 -24.45999934 0 P 0
L 40.4400004 -35.9599992 40.4400004 -24.45999934 0 P 0
L 45.44000056 -35.9599992 62.43999958 -35.9599992 0 P 0
L 45.44000056 -39.45999982 62.43999958 -39.45999982 0 P 0
L 45.44000056 -42.96000044 45.44000056 -35.9599992 0 P 0
L 45.44000056 -42.96000044 62.43999958 -42.96000044 0 P 0
L 62.43999958 -35.9599992 62.43999958 -24.45999934 0 P 0
L 62.43999958 -42.96000044 62.43999958 -35.9599992 0 P 0
L 62.93999858 -43.45999944 62.93999858 -23.96000034 0 P 0
S P 0
OB 0.7689596 36.47426284 I
OS 0.690372 36.47426284
OS 0.690372 36.9744498
OS 0.68944744 36.97352524
OS 0.68482464 36.969827
OS 0.67927728 36.96427964
OS 0.67003168 36.95780772
OS 0.65986152 36.94948668
OS 0.64691768 36.94024108
OS 0.63212472 36.93007092
OS 0.61548264 36.91990076
OS 0.61455808 36.91990076
OS 0.61363352 36.9189762
OS 0.60808616 36.91527796
OS 0.59884056 36.91065516
OS 0.58774584 36.9051078
OS 0.574802 36.89863588
OS 0.5609336 36.89216396
OS 0.5470652 36.88569204
OS 0.5331968 36.88014468
OS 0.5331968 36.9559586
OS 0.53412136 36.9559586
OS 0.53597048 36.95780772
OS 0.53966872 36.95873228
OS 0.54429152 36.96150596
OS 0.54983888 36.96427964
OS 0.5563108 36.96797788
OS 0.57202832 36.97722348
OS 0.59051952 36.98739364
OS 0.60901072 37.00033748
OS 0.62842648 37.01513044
OS 0.64784224 37.03084796
OS 0.6487668 37.03177252
OS 0.64969136 37.03269708
OS 0.65246504 37.03547076
OS 0.65616328 37.03824444
OS 0.66448432 37.04749004
OS 0.67557904 37.05858476
OS 0.68667376 37.0715286
OS 0.69869304 37.08632156
OS 0.7088632 37.10111452
OS 0.7181088 37.11683204
OS 0.7689596 37.11683204
OS 0.7689596 36.47426284
OE
OB 0.36400232 36.74423436 I
OS 0.36400232 36.7433098
OS 0.36400232 36.73961156
OS 0.36400232 36.73498876
OS 0.36400232 36.72851684
OS 0.36307776 36.7201958
OS 0.36307776 36.7109502
OS 0.3621532 36.69985548
OS 0.36122864 36.68876076
OS 0.35845496 36.66379764
OS 0.35475672 36.63790996
OS 0.34920936 36.61294684
OS 0.34551112 36.60092756
OS 0.34181288 36.58983284
OS 0.34181288 36.58890828
OS 0.34088832 36.58705916
OS 0.3390392 36.58428548
OS 0.33719008 36.58058724
OS 0.33164272 36.57041708
OS 0.32332168 36.55747324
OS 0.31222696 36.54268028
OS 0.29928312 36.52788732
OS 0.28264104 36.5121698
OS 0.26230072 36.4983014
OS 0.26137616 36.4983014
OS 0.25952704 36.49645228
OS 0.25675336 36.49552772
OS 0.25213056 36.49275404
OS 0.2465832 36.48998036
OS 0.23918672 36.48720668
OS 0.23179024 36.484433
OS 0.22254464 36.48073476
OS 0.21237448 36.47703652
OS 0.20127976 36.47426284
OS 0.18926048 36.47148916
OS 0.17539208 36.46871548
OS 0.16152368 36.46686636
OS 0.14673072 36.46501724
OS 0.11344656 36.46316812
OS 0.10512552 36.46316812
OS 0.0986536 36.46409268
OS 0.09125712 36.46409268
OS 0.08201152 36.46501724
OS 0.07184136 36.4659418
OS 0.0616712 36.46686636
OS 0.0385572 36.4705646
OS 0.01359408 36.47611196
OS -0.01044448 36.48350844
OS -0.03355848 36.4936786
OS -0.03448304 36.4936786
OS -0.03633216 36.49552772
OS -0.03910584 36.49737684
OS -0.04280408 36.49922596
OS -0.05297424 36.50662244
OS -0.06499352 36.5167926
OS -0.07886192 36.52973644
OS -0.09180576 36.5445294
OS -0.1047496 36.5630206
OS -0.11491976 36.58336092
OS -0.11491976 36.58428548
OS -0.11584432 36.5861346
OS -0.11676888 36.58983284
OS -0.118618 36.59445564
OS -0.12046712 36.600003
OS -0.12231624 36.60739948
OS -0.12508992 36.61572052
OS -0.12693904 36.62589068
OS -0.12878816 36.6369854
OS -0.13156184 36.64900468
OS -0.13341096 36.66194852
OS -0.13526008 36.67581692
OS -0.1371092 36.69153444
OS -0.13803376 36.70817652
OS -0.13895832 36.72574316
OS -0.13895832 36.74423436
OS -0.13895832 37.11405836
OS -0.0538988 37.11405836
OS -0.0538988 36.74423436
OS -0.0538988 36.7433098
OS -0.0538988 36.74053612
OS -0.0538988 36.73591332
OS -0.0538988 36.73036596
OS -0.05297424 36.72389404
OS -0.05297424 36.715573
OS -0.05204968 36.69800636
OS -0.05020056 36.67766604
OS -0.04742688 36.65732572
OS -0.04372864 36.63790996
OS -0.04187952 36.62958892
OS -0.03910584 36.62126788
OS -0.03818128 36.61941876
OS -0.03633216 36.61479596
OS -0.03170936 36.60832404
OS -0.026162 36.59907844
OS -0.01969008 36.58983284
OS -0.01044448 36.57966268
OS 0.00065024 36.56949252
OS 0.01359408 36.56117148
OS 0.0154432 36.56024692
OS 0.020066 36.55747324
OS 0.02838704 36.55469956
OS 0.03948176 36.55100132
OS 0.0524256 36.54637852
OS 0.06906768 36.54360484
OS 0.08663432 36.54083116
OS 0.10605008 36.5399066
OS 0.11529568 36.5399066
OS 0.12084304 36.54083116
OS 0.12916408 36.54083116
OS 0.13748512 36.54175572
OS 0.15782544 36.54545396
OS 0.18001488 36.55007676
OS 0.20127976 36.55747324
OS 0.22162008 36.5676434
OS 0.23086568 36.57411532
OS 0.23918672 36.5815118
OS 0.24011128 36.58243636
OS 0.24103584 36.58336092
OS 0.24288496 36.5861346
OS 0.24565864 36.58983284
OS 0.24843232 36.5953802
OS 0.25213056 36.60092756
OS 0.2558288 36.6092486
OS 0.25952704 36.61756964
OS 0.26322528 36.6277398
OS 0.26599896 36.63975908
OS 0.2696972 36.65362748
OS 0.27247088 36.66842044
OS 0.27524456 36.68506252
OS 0.27709368 36.70262916
OS 0.2789428 36.72296948
OS 0.2789428 36.74423436
OS 0.2789428 37.11405836
OS 0.36400232 37.11405836
OS 0.36400232 36.74423436
OE
SE
S P 0
OB -1.6831691 38.2909064 I
OS -1.67577262 38.28998184
OS -1.66652702 38.28905728
OS -1.65635686 38.28720816
OS -1.6461867 38.28535904
OS -1.62214814 38.27888712
OS -1.59810958 38.26964152
OS -1.5860903 38.26409416
OS -1.57407102 38.25762224
OS -1.5629763 38.2493012
OS -1.55280614 38.2400556
OS -1.55188158 38.23913104
OS -1.55003246 38.23820648
OS -1.54818334 38.23450824
OS -1.5444851 38.23081
OS -1.5398623 38.2261872
OS -1.5352395 38.21971528
OS -1.5306167 38.21324336
OS -1.52506934 38.20492232
OS -1.51582374 38.18735568
OS -1.50657814 38.16516624
OS -1.5028799 38.15407152
OS -1.50103078 38.14112768
OS -1.49918166 38.12818384
OS -1.4982571 38.11431544
OS -1.4982571 38.11246632
OS -1.4982571 38.10784352
OS -1.49918166 38.10044704
OS -1.50010622 38.09027688
OS -1.50195534 38.07918216
OS -1.50565358 38.06623832
OS -1.50935182 38.05236992
OS -1.51489918 38.03850152
OS -1.51582374 38.0366524
OS -1.51767286 38.0320296
OS -1.5213711 38.02463312
OS -1.52691846 38.01446296
OS -1.53431494 38.00336824
OS -1.54356054 37.98949984
OS -1.55465526 37.97563144
OS -1.5675991 37.95991392
OS -1.56944822 37.9580648
OS -1.57407102 37.95251744
OS -1.57869382 37.94789464
OS -1.58331662 37.94327184
OS -1.58886398 37.93772448
OS -1.59626046 37.930328
OS -1.60365694 37.92293152
OS -1.61290254 37.91461048
OS -1.62214814 37.90536488
OS -1.63324286 37.89519472
OS -1.64526214 37.88502456
OS -1.65820598 37.87300528
OS -1.67299894 37.860986
OS -1.6877919 37.84804216
OS -1.68871646 37.8471176
OS -1.69056558 37.84526848
OS -1.69426382 37.8424948
OS -1.69888662 37.83879656
OS -1.70443398 37.8332492
OS -1.7109059 37.82770184
OS -1.72569886 37.81568256
OS -1.74141638 37.80181416
OS -1.75620934 37.78794576
OS -1.76915318 37.77592648
OS -1.77470054 37.77130368
OS -1.77932334 37.76668088
OS -1.7802479 37.76575632
OS -1.78302158 37.76298264
OS -1.78671982 37.7592844
OS -1.79134262 37.75373704
OS -1.79596542 37.74726512
OS -1.80151278 37.7407932
OS -1.8126075 37.72507568
OS -1.49733254 37.72507568
OS -1.49733254 37.64926176
OS -1.92170558 37.64926176
OS -1.92170558 37.65018632
OS -1.92170558 37.65388456
OS -1.92170558 37.65943192
OS -1.92078102 37.6668284
OS -1.91985646 37.67514944
OS -1.91800734 37.68439504
OS -1.91615822 37.69364064
OS -1.91245998 37.7038108
OS -1.91245998 37.70473536
OS -1.91153542 37.70565992
OS -1.9096863 37.71120728
OS -1.90598806 37.71952832
OS -1.9004407 37.73062304
OS -1.89304422 37.74356688
OS -1.88379862 37.75835984
OS -1.87362846 37.7731528
OS -1.86068462 37.78887032
OS -1.86068462 37.78979488
OS -1.8588355 37.79071944
OS -1.8542127 37.7962668
OS -1.84589166 37.80458784
OS -1.83387238 37.81660712
OS -1.82000398 37.83047552
OS -1.80243734 37.8471176
OS -1.78117246 37.8656088
OS -1.75805846 37.88502456
OS -1.7571339 37.88594912
OS -1.75343566 37.8887228
OS -1.7478883 37.8933456
OS -1.74141638 37.89889296
OS -1.73309534 37.90628944
OS -1.72292518 37.91461048
OS -1.71275502 37.92385608
OS -1.70073574 37.93402624
OS -1.67762174 37.95621568
OS -1.65450774 37.97840512
OS -1.64341302 37.98949984
OS -1.63324286 38.00059456
OS -1.62399726 38.01076472
OS -1.61660078 38.02093488
OS -1.61660078 38.02185944
OS -1.61475166 38.022784
OS -1.61290254 38.02555768
OS -1.61105342 38.02925592
OS -1.6045815 38.03942608
OS -1.59718502 38.05144536
OS -1.5907131 38.06623832
OS -1.58424118 38.08195584
OS -1.58054294 38.09952248
OS -1.57869382 38.11616456
OS -1.57869382 38.11708912
OS -1.57869382 38.11801368
OS -1.57961838 38.12356104
OS -1.58054294 38.13280664
OS -1.58331662 38.1429768
OS -1.58701486 38.15592064
OS -1.59348678 38.16886448
OS -1.60180782 38.18180832
OS -1.61290254 38.19475216
OS -1.61475166 38.19660128
OS -1.61937446 38.20029952
OS -1.62584638 38.20492232
OS -1.63601654 38.21139424
OS -1.64896038 38.2169416
OS -1.66375334 38.22248896
OS -1.68131998 38.2261872
OS -1.70073574 38.22711176
OS -1.7062831 38.22711176
OS -1.70998134 38.2261872
OS -1.72107606 38.22526264
OS -1.7340199 38.22248896
OS -1.7478883 38.21879072
OS -1.76360582 38.2123188
OS -1.77839878 38.20399776
OS -1.79226718 38.19290304
OS -1.7941163 38.19105392
OS -1.79781454 38.18643112
OS -1.8033619 38.17903464
OS -1.80890926 38.16793992
OS -1.81538118 38.15499608
OS -1.82092854 38.138354
OS -1.82462678 38.1198628
OS -1.8264759 38.09859792
OS -1.90691262 38.10691896
OS -1.90691262 38.10784352
OS -1.90598806 38.1106172
OS -1.90598806 38.11524
OS -1.9050635 38.12171192
OS -1.90321438 38.1291084
OS -1.90136526 38.13742944
OS -1.89859158 38.1475996
OS -1.8958179 38.15776976
OS -1.88842142 38.1799592
OS -1.8773267 38.20214864
OS -1.87085478 38.21324336
OS -1.86253374 38.22433808
OS -1.8542127 38.23450824
OS -1.8449671 38.24375384
OS -1.84404254 38.2446784
OS -1.84219342 38.24560296
OS -1.83941974 38.24837664
OS -1.83479694 38.25115032
OS -1.82924958 38.25484856
OS -1.82277766 38.2585468
OS -1.81538118 38.2631696
OS -1.80613558 38.2677924
OS -1.79596542 38.2724152
OS -1.7848707 38.277038
OS -1.77285142 38.28073624
OS -1.75990758 38.28443448
OS -1.74603918 38.28720816
OS -1.73124622 38.28998184
OS -1.7155287 38.2909064
OS -1.69888662 38.29183096
OS -1.68964102 38.29183096
OS -1.6831691 38.2909064
OE
OB -2.01970894 37.91923328 I
OS -2.01970894 37.91830872
OS -2.01970894 37.91461048
OS -2.01970894 37.90998768
OS -2.01970894 37.90351576
OS -2.0206335 37.89519472
OS -2.0206335 37.88594912
OS -2.02155806 37.8748544
OS -2.02248262 37.86375968
OS -2.0252563 37.83879656
OS -2.02895454 37.81290888
OS -2.0345019 37.78794576
OS -2.03820014 37.77592648
OS -2.04189838 37.76483176
OS -2.04189838 37.7639072
OS -2.04282294 37.76205808
OS -2.04467206 37.7592844
OS -2.04652118 37.75558616
OS -2.05206854 37.745416
OS -2.06038958 37.73247216
OS -2.0714843 37.7176792
OS -2.08442814 37.70288624
OS -2.10107022 37.68716872
OS -2.12141054 37.67330032
OS -2.1223351 37.67330032
OS -2.12418422 37.6714512
OS -2.1269579 37.67052664
OS -2.1315807 37.66775296
OS -2.13712806 37.66497928
OS -2.14452454 37.6622056
OS -2.15192102 37.65943192
OS -2.16116662 37.65573368
OS -2.17133678 37.65203544
OS -2.1824315 37.64926176
OS -2.19445078 37.64648808
OS -2.20831918 37.6437144
OS -2.22218758 37.64186528
OS -2.23698054 37.64001616
OS -2.2702647 37.63816704
OS -2.27858574 37.63816704
OS -2.28505766 37.6390916
OS -2.29245414 37.6390916
OS -2.30169974 37.64001616
OS -2.3118699 37.64094072
OS -2.32204006 37.64186528
OS -2.34515406 37.64556352
OS -2.37011718 37.65111088
OS -2.39415574 37.65850736
OS -2.41726974 37.66867752
OS -2.4181943 37.66867752
OS -2.42004342 37.67052664
OS -2.4228171 37.67237576
OS -2.42651534 37.67422488
OS -2.4366855 37.68162136
OS -2.44870478 37.69179152
OS -2.46257318 37.70473536
OS -2.47551702 37.71952832
OS -2.48846086 37.73801952
OS -2.49863102 37.75835984
OS -2.49863102 37.7592844
OS -2.49955558 37.76113352
OS -2.50048014 37.76483176
OS -2.50232926 37.76945456
OS -2.50417838 37.77500192
OS -2.5060275 37.7823984
OS -2.50880118 37.79071944
OS -2.5106503 37.8008896
OS -2.51249942 37.81198432
OS -2.5152731 37.8240036
OS -2.51712222 37.83694744
OS -2.51897134 37.85081584
OS -2.52082046 37.86653336
OS -2.52174502 37.88317544
OS -2.52266958 37.90074208
OS -2.52266958 37.91923328
OS -2.52266958 38.28905728
OS -2.43761006 38.28905728
OS -2.43761006 37.91923328
OS -2.43761006 37.91830872
OS -2.43761006 37.91553504
OS -2.43761006 37.91091224
OS -2.43761006 37.90536488
OS -2.4366855 37.89889296
OS -2.4366855 37.89057192
OS -2.43576094 37.87300528
OS -2.43391182 37.85266496
OS -2.43113814 37.83232464
OS -2.4274399 37.81290888
OS -2.42559078 37.80458784
OS -2.4228171 37.7962668
OS -2.42189254 37.79441768
OS -2.42004342 37.78979488
OS -2.41542062 37.78332296
OS -2.40987326 37.77407736
OS -2.40340134 37.76483176
OS -2.39415574 37.7546616
OS -2.38306102 37.74449144
OS -2.37011718 37.7361704
OS -2.36826806 37.73524584
OS -2.36364526 37.73247216
OS -2.35532422 37.72969848
OS -2.3442295 37.72600024
OS -2.33128566 37.72137744
OS -2.31464358 37.71860376
OS -2.29707694 37.71583008
OS -2.27766118 37.71490552
OS -2.26841558 37.71490552
OS -2.26286822 37.71583008
OS -2.25454718 37.71583008
OS -2.24622614 37.71675464
OS -2.22588582 37.72045288
OS -2.20369638 37.72507568
OS -2.1824315 37.73247216
OS -2.16209118 37.74264232
OS -2.15284558 37.74911424
OS -2.14452454 37.75651072
OS -2.14359998 37.75743528
OS -2.14267542 37.75835984
OS -2.1408263 37.76113352
OS -2.13805262 37.76483176
OS -2.13527894 37.77037912
OS -2.1315807 37.77592648
OS -2.12788246 37.78424752
OS -2.12418422 37.79256856
OS -2.12048598 37.80273872
OS -2.1177123 37.814758
OS -2.11401406 37.8286264
OS -2.11124038 37.84341936
OS -2.1084667 37.86006144
OS -2.10661758 37.87762808
OS -2.10476846 37.8979684
OS -2.10476846 37.91923328
OS -2.10476846 38.28905728
OS -2.01970894 38.28905728
OS -2.01970894 37.91923328
OE
SE
S P 0
OB -2.9784421 -38.48662356 I
OS -2.97104562 -38.48754812
OS -2.96180002 -38.48939724
OS -2.95162986 -38.49124636
OS -2.93961058 -38.49402004
OS -2.92851586 -38.49679372
OS -2.91557202 -38.50141652
OS -2.90355274 -38.50603932
OS -2.8906089 -38.51251124
OS -2.87766506 -38.51990772
OS -2.86472122 -38.52822876
OS -2.85270194 -38.53839892
OS -2.84160722 -38.54949364
OS -2.84068266 -38.5504182
OS -2.83883354 -38.55226732
OS -2.83605986 -38.55596556
OS -2.83236162 -38.56151292
OS -2.82773882 -38.56798484
OS -2.82311602 -38.57538132
OS -2.81756866 -38.58462692
OS -2.8120213 -38.59572164
OS -2.80647394 -38.60774092
OS -2.80092658 -38.62068476
OS -2.79630378 -38.63547772
OS -2.79168098 -38.65119524
OS -2.78798274 -38.66876188
OS -2.78520906 -38.68725308
OS -2.78335994 -38.70666884
OS -2.78243538 -38.72793372
OS -2.78243538 -38.72885828
OS -2.78243538 -38.73255652
OS -2.78243538 -38.73902844
OS -2.78335994 -38.74827404
OS -3.13006994 -38.74827404
OS -3.13006994 -38.7491986
OS -3.13006994 -38.75197228
OS -3.12914538 -38.75567052
OS -3.12914538 -38.76121788
OS -3.12822082 -38.7676898
OS -3.1263717 -38.77508628
OS -3.12359802 -38.79172836
OS -3.11805066 -38.81021956
OS -3.11065418 -38.83055988
OS -3.10048402 -38.84905108
OS -3.08754018 -38.86569316
OS -3.08661562 -38.86569316
OS -3.08569106 -38.86754228
OS -3.0801437 -38.87216508
OS -3.07182266 -38.878637
OS -3.06072794 -38.88510892
OS -3.04593498 -38.8925054
OS -3.0292929 -38.89897732
OS -3.0108017 -38.90360012
OS -3.00063154 -38.90452468
OS -2.98953682 -38.90544924
OS -2.98214034 -38.90544924
OS -2.9738193 -38.90452468
OS -2.96364914 -38.90267556
OS -2.95255442 -38.89990188
OS -2.93961058 -38.89620364
OS -2.9275913 -38.89065628
OS -2.91557202 -38.8832598
OS -2.91464746 -38.88233524
OS -2.91002466 -38.878637
OS -2.9044773 -38.87308964
OS -2.89800538 -38.86569316
OS -2.8906089 -38.855523
OS -2.88228786 -38.84257916
OS -2.87396682 -38.8277862
OS -2.86657034 -38.81021956
OS -2.78520906 -38.82038972
OS -2.78520906 -38.82131428
OS -2.78613362 -38.8231634
OS -2.78705818 -38.82686164
OS -2.7889073 -38.832409
OS -2.79168098 -38.83795636
OS -2.79445466 -38.84535284
OS -2.80185114 -38.86107036
OS -2.81109674 -38.878637
OS -2.82404058 -38.8971282
OS -2.83883354 -38.91469484
OS -2.85732474 -38.93133692
OS -2.8582493 -38.93133692
OS -2.86009842 -38.93318604
OS -2.8628721 -38.93503516
OS -2.86657034 -38.93780884
OS -2.8721177 -38.94058252
OS -2.87766506 -38.9433562
OS -2.88506154 -38.94705444
OS -2.89338258 -38.95075268
OS -2.90262818 -38.95445092
OS -2.91187378 -38.95814916
OS -2.93498778 -38.96369652
OS -2.96087546 -38.96831932
OS -2.98953682 -38.97016844
OS -2.99970698 -38.97016844
OS -3.0061789 -38.96924388
OS -3.01449994 -38.96831932
OS -3.0246701 -38.9664702
OS -3.03576482 -38.96462108
OS -3.0477841 -38.96277196
OS -3.07367178 -38.95537548
OS -3.08754018 -38.94982812
OS -3.10048402 -38.94428076
OS -3.11435242 -38.93688428
OS -3.12729626 -38.92856324
OS -3.13931554 -38.91931764
OS -3.15133482 -38.90822292
OS -3.15225938 -38.90729836
OS -3.1541085 -38.90544924
OS -3.15688218 -38.901751
OS -3.16058042 -38.89620364
OS -3.16520322 -38.88973172
OS -3.16982602 -38.88233524
OS -3.17537338 -38.87308964
OS -3.18092074 -38.86291948
OS -3.1864681 -38.8509002
OS -3.19201546 -38.83795636
OS -3.19663826 -38.8231634
OS -3.20126106 -38.80744588
OS -3.2049593 -38.7908038
OS -3.20773298 -38.7723126
OS -3.2095821 -38.75289684
OS -3.21050666 -38.73255652
OS -3.21050666 -38.73163196
OS -3.21050666 -38.72700916
OS -3.21050666 -38.7214618
OS -3.2095821 -38.71314076
OS -3.20865754 -38.7029706
OS -3.20773298 -38.69187588
OS -3.20588386 -38.67893204
OS -3.20311018 -38.6659882
OS -3.1957137 -38.63640228
OS -3.1910909 -38.62160932
OS -3.18554354 -38.6058918
OS -3.17814706 -38.59109884
OS -3.16982602 -38.57723044
OS -3.16058042 -38.56336204
OS -3.15041026 -38.5504182
OS -3.1494857 -38.54949364
OS -3.14763658 -38.54764452
OS -3.14393834 -38.54487084
OS -3.13931554 -38.54024804
OS -3.13376818 -38.53562524
OS -3.1263717 -38.53007788
OS -3.11805066 -38.52360596
OS -3.1078805 -38.5180586
OS -3.09771034 -38.51158668
OS -3.08569106 -38.50603932
OS -3.07274722 -38.50049196
OS -3.05887882 -38.49586916
OS -3.04408586 -38.49124636
OS -3.02836834 -38.48847268
OS -3.01172626 -38.48662356
OS -2.99415962 -38.485699
OS -2.98491402 -38.485699
OS -2.9784421 -38.48662356
OE
OB -2.50136914 -38.48662356 I
OS -2.49119898 -38.48847268
OS -2.4791797 -38.49217092
OS -2.46623586 -38.49679372
OS -2.4514429 -38.50326564
OS -2.43572538 -38.51158668
OS -2.46438674 -38.58370236
OS -2.4653113 -38.5827778
OS -2.46900954 -38.58092868
OS -2.4745569 -38.578155
OS -2.48195338 -38.57538132
OS -2.49027442 -38.57260764
OS -2.50044458 -38.56983396
OS -2.51061474 -38.56798484
OS -2.5207849 -38.56706028
OS -2.5254077 -38.56706028
OS -2.5300305 -38.56798484
OS -2.53650242 -38.5689094
OS -2.54297434 -38.57075852
OS -2.55129538 -38.5735322
OS -2.55961642 -38.57723044
OS -2.5670129 -38.5827778
OS -2.56793746 -38.58370236
OS -2.57071114 -38.58555148
OS -2.57348482 -38.58924972
OS -2.57810762 -38.59387252
OS -2.58273042 -38.60034444
OS -2.58735322 -38.60774092
OS -2.59197602 -38.61606196
OS -2.59567426 -38.62623212
OS -2.59659882 -38.62808124
OS -2.59752338 -38.6336286
OS -2.5993725 -38.64194964
OS -2.60214618 -38.65304436
OS -2.60491986 -38.66691276
OS -2.60676898 -38.68263028
OS -2.60769354 -38.69927236
OS -2.6086181 -38.71776356
OS -2.6086181 -38.95999828
OS -2.6872057 -38.95999828
OS -2.6872057 -38.49586916
OS -2.61601458 -38.49586916
OS -2.61601458 -38.56613572
OS -2.61509002 -38.56521116
OS -2.61139178 -38.55873924
OS -2.60676898 -38.5504182
OS -2.5993725 -38.54024804
OS -2.59197602 -38.53007788
OS -2.58365498 -38.51898316
OS -2.57533394 -38.50973756
OS -2.5670129 -38.50234108
OS -2.56608834 -38.50141652
OS -2.56331466 -38.4995674
OS -2.5577673 -38.49679372
OS -2.55221994 -38.49402004
OS -2.54482346 -38.49124636
OS -2.53557786 -38.48847268
OS -2.52633226 -38.48662356
OS -2.5161621 -38.485699
OS -2.50969018 -38.485699
OS -2.50136914 -38.48662356
OE
OB -3.92519154 -38.48662356 I
OS -3.9168705 -38.48754812
OS -3.9076249 -38.48939724
OS -3.89745474 -38.49124636
OS -3.88543546 -38.49309548
OS -3.86047234 -38.50141652
OS -3.8475285 -38.50603932
OS -3.83458466 -38.51251124
OS -3.82164082 -38.51898316
OS -3.80869698 -38.52822876
OS -3.7966777 -38.53747436
OS -3.78465842 -38.54856908
OS -3.78373386 -38.54949364
OS -3.78188474 -38.55134276
OS -3.77911106 -38.555041
OS -3.77541282 -38.5596638
OS -3.77079002 -38.56613572
OS -3.76524266 -38.57445676
OS -3.7596953 -38.58370236
OS -3.75414794 -38.59387252
OS -3.74860058 -38.60496724
OS -3.74305322 -38.61883564
OS -3.73750586 -38.63270404
OS -3.73288306 -38.64842156
OS -3.72918482 -38.66506364
OS -3.72641114 -38.68263028
OS -3.72456202 -38.70112148
OS -3.72363746 -38.7214618
OS -3.72363746 -38.72238636
OS -3.72363746 -38.72516004
OS -3.72363746 -38.72978284
OS -3.72363746 -38.73625476
OS -3.72456202 -38.74365124
OS -3.72548658 -38.75289684
OS -3.72548658 -38.76214244
OS -3.7273357 -38.7723126
OS -3.73010938 -38.7954266
OS -3.73565674 -38.8185406
OS -3.74212866 -38.8416546
OS -3.75137426 -38.86291948
OS -3.75137426 -38.86384404
OS -3.75229882 -38.8647686
OS -3.75414794 -38.86754228
OS -3.75599706 -38.87124052
OS -3.76246898 -38.88048612
OS -3.77079002 -38.89158084
OS -3.78188474 -38.90452468
OS -3.79575314 -38.91746852
OS -3.81147066 -38.93041236
OS -3.82996186 -38.94243164
OS -3.83088642 -38.94243164
OS -3.83181098 -38.9433562
OS -3.83458466 -38.94520532
OS -3.83920746 -38.94705444
OS -3.84383026 -38.94890356
OS -3.84937762 -38.95075268
OS -3.86324602 -38.95630004
OS -3.87896354 -38.96092284
OS -3.8983793 -38.96554564
OS -3.91871962 -38.96924388
OS -3.94090906 -38.97016844
OS -3.95015466 -38.97016844
OS -3.95755114 -38.96924388
OS -3.96587218 -38.96831932
OS -3.97511778 -38.9664702
OS -3.9862125 -38.96462108
OS -3.99730722 -38.96277196
OS -4.02227034 -38.95537548
OS -4.03613874 -38.94982812
OS -4.04908258 -38.94428076
OS -4.06202642 -38.93688428
OS -4.07497026 -38.92856324
OS -4.08698954 -38.91931764
OS -4.09900882 -38.90822292
OS -4.09993338 -38.90729836
OS -4.1017825 -38.90544924
OS -4.10455618 -38.901751
OS -4.10825442 -38.89620364
OS -4.11287722 -38.88973172
OS -4.11750002 -38.88233524
OS -4.12304738 -38.87308964
OS -4.12859474 -38.86199492
OS -4.1341421 -38.84997564
OS -4.13968946 -38.83610724
OS -4.14431226 -38.82131428
OS -4.14893506 -38.80559676
OS -4.1526333 -38.78803012
OS -4.15540698 -38.76953892
OS -4.1572561 -38.7491986
OS -4.15818066 -38.72793372
OS -4.15818066 -38.7260846
OS -4.15818066 -38.72238636
OS -4.1572561 -38.71591444
OS -4.1572561 -38.70666884
OS -4.15633154 -38.69649868
OS -4.15448242 -38.68355484
OS -4.1526333 -38.670611
OS -4.14893506 -38.65581804
OS -4.14523682 -38.64102508
OS -4.14061402 -38.62530756
OS -4.13506666 -38.60866548
OS -4.12767018 -38.59294796
OS -4.1202737 -38.578155
OS -4.11010354 -38.56336204
OS -4.09993338 -38.54949364
OS -4.08698954 -38.53747436
OS -4.08606498 -38.5365498
OS -4.08421586 -38.53562524
OS -4.08051762 -38.53285156
OS -4.07589482 -38.52915332
OS -4.07034746 -38.52545508
OS -4.06295098 -38.52083228
OS -4.0555545 -38.51620948
OS -4.0463089 -38.51158668
OS -4.03613874 -38.50696388
OS -4.02504402 -38.50234108
OS -4.0000809 -38.49402004
OS -3.97141954 -38.48754812
OS -3.95662658 -38.48662356
OS -3.94090906 -38.485699
OS -3.93166346 -38.485699
OS -3.92519154 -38.48662356
OE
OB -3.43055194 -38.95999828 I
OS -3.5054413 -38.95999828
OS -3.68018314 -38.49586916
OS -3.59697274 -38.49586916
OS -3.49712026 -38.77416172
OS -3.49712026 -38.77508628
OS -3.4961957 -38.77601084
OS -3.49527114 -38.77878452
OS -3.49434658 -38.7815582
OS -3.4915729 -38.7908038
OS -3.48787466 -38.80282308
OS -3.48325186 -38.81669148
OS -3.4777045 -38.832409
OS -3.4730817 -38.84997564
OS -3.46753434 -38.86754228
OS -3.46660978 -38.86569316
OS -3.46568522 -38.86107036
OS -3.46291154 -38.85367388
OS -3.46013786 -38.84257916
OS -3.45551506 -38.83055988
OS -3.45089226 -38.81484236
OS -3.44442034 -38.79820028
OS -3.43794842 -38.77970908
OS -3.33532226 -38.49586916
OS -3.25396098 -38.49586916
OS -3.43055194 -38.95999828
OE
OB -1.48897594 -38.96739476 I
OS -1.48897594 -38.96831932
OS -1.4899005 -38.971093
OS -1.49174962 -38.97479124
OS -1.49359874 -38.97941404
OS -1.49637242 -38.98588596
OS -1.4991461 -38.99328244
OS -1.50561802 -39.00899996
OS -1.51208994 -39.0265666
OS -1.51948642 -39.04413324
OS -1.5268829 -39.05985076
OS -1.53058114 -39.06632268
OS -1.53335482 -39.0727946
OS -1.53427938 -39.07464372
OS -1.53705306 -39.07926652
OS -1.54167586 -39.08573844
OS -1.54722322 -39.09405948
OS -1.5546197 -39.10330508
OS -1.56294074 -39.11255068
OS -1.57126178 -39.12179628
OS -1.58143194 -39.12919276
OS -1.5823565 -39.13011732
OS -1.58605474 -39.13196644
OS -1.5916021 -39.13474012
OS -1.59992314 -39.13843836
OS -1.60916874 -39.1421366
OS -1.62026346 -39.14491028
OS -1.63228274 -39.1467594
OS -1.64615114 -39.14768396
OS -1.64984938 -39.14768396
OS -1.65447218 -39.1467594
OS -1.6609441 -39.1467594
OS -1.66834058 -39.14491028
OS -1.67666162 -39.14306116
OS -1.68590722 -39.14121204
OS -1.69607738 -39.1375138
OS -1.70439842 -39.06447356
OS -1.70347386 -39.06447356
OS -1.69977562 -39.06539812
OS -1.69515282 -39.06632268
OS -1.68960546 -39.0681718
OS -1.6748125 -39.07094548
OS -1.66001954 -39.07187004
OS -1.65539674 -39.07187004
OS -1.65077394 -39.07094548
OS -1.64522658 -39.07094548
OS -1.63135818 -39.0681718
OS -1.62488626 -39.06539812
OS -1.61841434 -39.06262444
OS -1.61748978 -39.06262444
OS -1.61564066 -39.06077532
OS -1.61286698 -39.0589262
OS -1.60916874 -39.05615252
OS -1.6008477 -39.04875604
OS -1.59345122 -39.03858588
OS -1.59345122 -39.03766132
OS -1.5916021 -39.0358122
OS -1.58975298 -39.03211396
OS -1.58790386 -39.0265666
OS -1.58420562 -39.01917012
OS -1.58050738 -39.0080754
OS -1.57496002 -38.99513156
OS -1.56941266 -38.97941404
OS -1.56941266 -38.97848948
OS -1.56756354 -38.97479124
OS -1.56571442 -38.96831932
OS -1.56201618 -38.95999828
OS -1.73768258 -38.49586916
OS -1.65447218 -38.49586916
OS -1.55739338 -38.76491612
OS -1.55739338 -38.76584068
OS -1.55646882 -38.76676524
OS -1.55554426 -38.76953892
OS -1.5546197 -38.77416172
OS -1.55277058 -38.77878452
OS -1.55092146 -38.78433188
OS -1.54629866 -38.79727572
OS -1.5407513 -38.81299324
OS -1.53520394 -38.83148444
OS -1.52965658 -38.8509002
OS -1.52410922 -38.87216508
OS -1.52410922 -38.87124052
OS -1.52318466 -38.8693914
OS -1.5222601 -38.86661772
OS -1.52133554 -38.86291948
OS -1.52041098 -38.85829668
OS -1.51856186 -38.85274932
OS -1.51486362 -38.83888092
OS -1.51024082 -38.8231634
OS -1.5037689 -38.8046722
OS -1.49822154 -38.786181
OS -1.49082506 -38.76676524
OS -1.39097258 -38.49586916
OS -1.31238498 -38.49586916
OS -1.48897594 -38.96739476
OE
OB -1.17462554 -38.42745172 I
OS -1.19589042 -38.54671996
OS -1.2448921 -38.54671996
OS -1.26430786 -38.42745172
OS -1.26430786 -38.32020276
OS -1.17462554 -38.32020276
OS -1.17462554 -38.42745172
OE
OB -2.31183434 -38.95999828 I
OS -2.39042194 -38.95999828
OS -2.39042194 -38.32020276
OS -2.31183434 -38.32020276
OS -2.31183434 -38.95999828
OE
OB -1.97344538 -38.48662356 I
OS -1.95957698 -38.48754812
OS -1.94385946 -38.48939724
OS -1.92814194 -38.49217092
OS -1.91242442 -38.49586916
OS -1.89763146 -38.50049196
OS -1.89578234 -38.50141652
OS -1.89115954 -38.50326564
OS -1.88468762 -38.50603932
OS -1.87636658 -38.50973756
OS -1.86712098 -38.51528492
OS -1.85787538 -38.52083228
OS -1.84955434 -38.52822876
OS -1.84215786 -38.53562524
OS -1.8412333 -38.5365498
OS -1.83938418 -38.53932348
OS -1.8366105 -38.54394628
OS -1.83291226 -38.54949364
OS -1.82828946 -38.55781468
OS -1.82459122 -38.56613572
OS -1.82089298 -38.57630588
OS -1.8181193 -38.58832516
OS -1.8181193 -38.58924972
OS -1.81719474 -38.5920234
OS -1.81627018 -38.59757076
OS -1.81534562 -38.60496724
OS -1.81534562 -38.6151374
OS -1.81442106 -38.62715668
OS -1.8134965 -38.6428742
OS -1.8134965 -38.66044084
OS -1.8134965 -38.76584068
OS -1.8134965 -38.76676524
OS -1.8134965 -38.77046348
OS -1.8134965 -38.77601084
OS -1.8134965 -38.78340732
OS -1.8134965 -38.79172836
OS -1.8134965 -38.80189852
OS -1.81257194 -38.82408796
OS -1.81257194 -38.84720196
OS -1.81164738 -38.87031596
OS -1.81072282 -38.88048612
OS -1.81072282 -38.88973172
OS -1.80979826 -38.89805276
OS -1.8088737 -38.90452468
OS -1.8088737 -38.90544924
OS -1.80794914 -38.90914748
OS -1.80702458 -38.91469484
OS -1.8042509 -38.92209132
OS -1.80240178 -38.93041236
OS -1.79870354 -38.93965796
OS -1.79408074 -38.94982812
OS -1.78945794 -38.95999828
OS -1.87174378 -38.95999828
OS -1.87266834 -38.95907372
OS -1.8735929 -38.95537548
OS -1.87544202 -38.95075268
OS -1.8782157 -38.9433562
OS -1.88098938 -38.93503516
OS -1.8828385 -38.924865
OS -1.88468762 -38.91377028
OS -1.88653674 -38.901751
OS -1.8874613 -38.901751
OS -1.88838586 -38.90360012
OS -1.89393322 -38.90822292
OS -1.90225426 -38.91469484
OS -1.91334898 -38.92301588
OS -1.92721738 -38.93133692
OS -1.94108578 -38.94058252
OS -1.95587874 -38.94890356
OS -1.97159626 -38.95537548
OS -1.97344538 -38.95630004
OS -1.97899274 -38.9572246
OS -1.98731378 -38.95999828
OS -1.99748394 -38.96277196
OS -2.01042778 -38.96554564
OS -2.02522074 -38.96739476
OS -2.04186282 -38.96924388
OS -2.0585049 -38.97016844
OS -2.06590138 -38.97016844
OS -2.07144874 -38.96924388
OS -2.07792066 -38.96924388
OS -2.08531714 -38.96831932
OS -2.10195922 -38.96554564
OS -2.12045042 -38.96092284
OS -2.14079074 -38.95445092
OS -2.15928194 -38.94520532
OS -2.17592402 -38.93318604
OS -2.17777314 -38.93133692
OS -2.18239594 -38.92671412
OS -2.18886786 -38.91839308
OS -2.19626434 -38.90729836
OS -2.20366082 -38.89342996
OS -2.21013274 -38.87771244
OS -2.21475554 -38.85829668
OS -2.2156801 -38.84905108
OS -2.21660466 -38.83795636
OS -2.21660466 -38.83610724
OS -2.21660466 -38.832409
OS -2.2156801 -38.82593708
OS -2.21475554 -38.81761604
OS -2.21290642 -38.80744588
OS -2.21013274 -38.79727572
OS -2.2064345 -38.786181
OS -2.2018117 -38.77601084
OS -2.20088714 -38.77508628
OS -2.19903802 -38.77138804
OS -2.19533978 -38.76584068
OS -2.19071698 -38.75936876
OS -2.18516962 -38.75197228
OS -2.17777314 -38.7445758
OS -2.17037666 -38.73717932
OS -2.16113106 -38.7307074
OS -2.1602065 -38.72978284
OS -2.15650826 -38.72793372
OS -2.15188546 -38.72423548
OS -2.14448898 -38.72053724
OS -2.13616794 -38.716839
OS -2.12599778 -38.7122162
OS -2.11582762 -38.70851796
OS -2.10380834 -38.70481972
OS -2.10288378 -38.70481972
OS -2.09918554 -38.70389516
OS -2.09363818 -38.70204604
OS -2.0862417 -38.70112148
OS -2.0769961 -38.69927236
OS -2.06497682 -38.69742324
OS -2.05110842 -38.69464956
OS -2.03446634 -38.69280044
OS -2.03354178 -38.69280044
OS -2.02984354 -38.69187588
OS -2.02522074 -38.69187588
OS -2.01874882 -38.69095132
OS -2.01135234 -38.69002676
OS -2.00210674 -38.68817764
OS -1.99193658 -38.68725308
OS -1.98084186 -38.68540396
OS -1.95865242 -38.68078116
OS -1.93461386 -38.67615836
OS -1.91334898 -38.670611
OS -1.90317882 -38.66783732
OS -1.89393322 -38.66506364
OS -1.89393322 -38.66413908
OS -1.89393322 -38.66228996
OS -1.89300866 -38.6567426
OS -1.89300866 -38.65027068
OS -1.89300866 -38.64657244
OS -1.89300866 -38.64472332
OS -1.89300866 -38.64379876
OS -1.89300866 -38.6428742
OS -1.89300866 -38.63732684
OS -1.89393322 -38.62808124
OS -1.89578234 -38.61791108
OS -1.89855602 -38.60681636
OS -1.90317882 -38.59572164
OS -1.90872618 -38.58555148
OS -1.91612266 -38.57723044
OS -1.91704722 -38.57630588
OS -1.92167002 -38.57260764
OS -1.9290665 -38.5689094
OS -1.9383121 -38.56336204
OS -1.95125594 -38.55873924
OS -1.9660489 -38.55411644
OS -1.9845401 -38.55134276
OS -2.00580498 -38.5504182
OS -2.01505058 -38.5504182
OS -2.02429618 -38.55134276
OS -2.03724002 -38.55319188
OS -2.05018386 -38.555041
OS -2.06405226 -38.55873924
OS -2.0769961 -38.56336204
OS -2.08809082 -38.56983396
OS -2.08901538 -38.57075852
OS -2.09271362 -38.5735322
OS -2.09733642 -38.578155
OS -2.10288378 -38.58555148
OS -2.10843114 -38.59479708
OS -2.11490306 -38.60681636
OS -2.12045042 -38.62160932
OS -2.12599778 -38.6382514
OS -2.20273626 -38.62808124
OS -2.20273626 -38.62715668
OS -2.2018117 -38.62623212
OS -2.2018117 -38.62345844
OS -2.20088714 -38.6197602
OS -2.19811346 -38.61143916
OS -2.19441522 -38.59941988
OS -2.18979242 -38.5874006
OS -2.18424506 -38.57445676
OS -2.17684858 -38.56151292
OS -2.16852754 -38.54949364
OS -2.16760298 -38.54856908
OS -2.16390474 -38.54487084
OS -2.15835738 -38.53932348
OS -2.1509609 -38.531927
OS -2.14079074 -38.52453052
OS -2.12877146 -38.51713404
OS -2.11490306 -38.508813
OS -2.09918554 -38.50234108
OS -2.09826098 -38.50234108
OS -2.09733642 -38.50141652
OS -2.09456274 -38.50049196
OS -2.0908645 -38.4995674
OS -2.0816189 -38.49679372
OS -2.06867506 -38.49402004
OS -2.0538821 -38.49124636
OS -2.0353909 -38.48847268
OS -2.01597514 -38.48662356
OS -1.9937857 -38.485699
OS -1.98361554 -38.485699
OS -1.97344538 -38.48662356
OE
OB -5.41743138 -38.48662356 I
OS -5.40911034 -38.48754812
OS -5.39986474 -38.48939724
OS -5.38969458 -38.49124636
OS -5.3776753 -38.49309548
OS -5.35271218 -38.50141652
OS -5.33976834 -38.50603932
OS -5.3268245 -38.51251124
OS -5.31388066 -38.51898316
OS -5.30093682 -38.52822876
OS -5.28891754 -38.53747436
OS -5.27689826 -38.54856908
OS -5.2759737 -38.54949364
OS -5.27412458 -38.55134276
OS -5.2713509 -38.555041
OS -5.26765266 -38.5596638
OS -5.26302986 -38.56613572
OS -5.2574825 -38.57445676
OS -5.25193514 -38.58370236
OS -5.24638778 -38.59387252
OS -5.24084042 -38.60496724
OS -5.23529306 -38.61883564
OS -5.2297457 -38.63270404
OS -5.2251229 -38.64842156
OS -5.22142466 -38.66506364
OS -5.21865098 -38.68263028
OS -5.21680186 -38.70112148
OS -5.2158773 -38.7214618
OS -5.2158773 -38.72238636
OS -5.2158773 -38.72516004
OS -5.2158773 -38.72978284
OS -5.2158773 -38.73625476
OS -5.21680186 -38.74365124
OS -5.21772642 -38.75289684
OS -5.21772642 -38.76214244
OS -5.21957554 -38.7723126
OS -5.22234922 -38.7954266
OS -5.22789658 -38.8185406
OS -5.2343685 -38.8416546
OS -5.2436141 -38.86291948
OS -5.2436141 -38.86384404
OS -5.24453866 -38.8647686
OS -5.24638778 -38.86754228
OS -5.2482369 -38.87124052
OS -5.25470882 -38.88048612
OS -5.26302986 -38.89158084
OS -5.27412458 -38.90452468
OS -5.28799298 -38.91746852
OS -5.3037105 -38.93041236
OS -5.3222017 -38.94243164
OS -5.32312626 -38.94243164
OS -5.32405082 -38.9433562
OS -5.3268245 -38.94520532
OS -5.3314473 -38.94705444
OS -5.3360701 -38.94890356
OS -5.34161746 -38.95075268
OS -5.35548586 -38.95630004
OS -5.37120338 -38.96092284
OS -5.39061914 -38.96554564
OS -5.41095946 -38.96924388
OS -5.4331489 -38.97016844
OS -5.4423945 -38.97016844
OS -5.44979098 -38.96924388
OS -5.45811202 -38.96831932
OS -5.46735762 -38.9664702
OS -5.47845234 -38.96462108
OS -5.48954706 -38.96277196
OS -5.51451018 -38.95537548
OS -5.52837858 -38.94982812
OS -5.54132242 -38.94428076
OS -5.55426626 -38.93688428
OS -5.5672101 -38.92856324
OS -5.57922938 -38.91931764
OS -5.59124866 -38.90822292
OS -5.59217322 -38.90729836
OS -5.59402234 -38.90544924
OS -5.59679602 -38.901751
OS -5.60049426 -38.89620364
OS -5.60511706 -38.88973172
OS -5.60973986 -38.88233524
OS -5.61528722 -38.87308964
OS -5.62083458 -38.86199492
OS -5.62638194 -38.84997564
OS -5.6319293 -38.83610724
OS -5.6365521 -38.82131428
OS -5.6411749 -38.80559676
OS -5.64487314 -38.78803012
OS -5.64764682 -38.76953892
OS -5.64949594 -38.7491986
OS -5.6504205 -38.72793372
OS -5.6504205 -38.7260846
OS -5.6504205 -38.72238636
OS -5.64949594 -38.71591444
OS -5.64949594 -38.70666884
OS -5.64857138 -38.69649868
OS -5.64672226 -38.68355484
OS -5.64487314 -38.670611
OS -5.6411749 -38.65581804
OS -5.63747666 -38.64102508
OS -5.63285386 -38.62530756
OS -5.6273065 -38.60866548
OS -5.61991002 -38.59294796
OS -5.61251354 -38.578155
OS -5.60234338 -38.56336204
OS -5.59217322 -38.54949364
OS -5.57922938 -38.53747436
OS -5.57830482 -38.5365498
OS -5.5764557 -38.53562524
OS -5.57275746 -38.53285156
OS -5.56813466 -38.52915332
OS -5.5625873 -38.52545508
OS -5.55519082 -38.52083228
OS -5.54779434 -38.51620948
OS -5.53854874 -38.51158668
OS -5.52837858 -38.50696388
OS -5.51728386 -38.50234108
OS -5.49232074 -38.49402004
OS -5.46365938 -38.48754812
OS -5.44886642 -38.48662356
OS -5.4331489 -38.485699
OS -5.4239033 -38.485699
OS -5.41743138 -38.48662356
OE
OB -4.90337602 -38.48662356 I
OS -4.8969041 -38.48754812
OS -4.8830357 -38.48939724
OS -4.86639362 -38.49309548
OS -4.84882698 -38.49864284
OS -4.83126034 -38.50696388
OS -4.8136937 -38.51713404
OS -4.81276914 -38.51713404
OS -4.81184458 -38.51898316
OS -4.80629722 -38.5226814
OS -4.79797618 -38.53007788
OS -4.78780602 -38.53932348
OS -4.7767113 -38.55134276
OS -4.76561658 -38.56613572
OS -4.75452186 -38.58370236
OS -4.74527626 -38.60311812
OS -4.74527626 -38.60404268
OS -4.7443517 -38.6058918
OS -4.74342714 -38.60866548
OS -4.74157802 -38.61236372
OS -4.7397289 -38.61791108
OS -4.73787978 -38.624383
OS -4.73325698 -38.63917596
OS -4.72863418 -38.65766716
OS -4.72493594 -38.67800748
OS -4.72216226 -38.70112148
OS -4.7212377 -38.72516004
OS -4.7212377 -38.7260846
OS -4.7212377 -38.72793372
OS -4.7212377 -38.73163196
OS -4.7212377 -38.73717932
OS -4.72216226 -38.74365124
OS -4.72216226 -38.75104772
OS -4.72401138 -38.7676898
OS -4.72770962 -38.78803012
OS -4.73233242 -38.809295
OS -4.73880434 -38.83148444
OS -4.74712538 -38.85367388
OS -4.74712538 -38.85459844
OS -4.74804994 -38.85644756
OS -4.74989906 -38.85922124
OS -4.75174818 -38.86291948
OS -4.7582201 -38.87308964
OS -4.76654114 -38.88603348
OS -4.7767113 -38.89990188
OS -4.78965514 -38.91377028
OS -4.8044481 -38.92763868
OS -4.82201474 -38.94058252
OS -4.8229393 -38.94058252
OS -4.82386386 -38.94150708
OS -4.82663754 -38.9433562
OS -4.83033578 -38.94520532
OS -4.83958138 -38.94982812
OS -4.85252522 -38.95537548
OS -4.86824274 -38.96092284
OS -4.88488482 -38.96554564
OS -4.90430058 -38.96924388
OS -4.92371634 -38.97016844
OS -4.93018826 -38.97016844
OS -4.93758474 -38.96924388
OS -4.94683034 -38.96831932
OS -4.95792506 -38.9664702
OS -4.96994434 -38.96369652
OS -4.98196362 -38.95999828
OS -4.9939829 -38.95445092
OS -4.99490746 -38.95352636
OS -4.99953026 -38.95167724
OS -5.00507762 -38.947979
OS -5.0124741 -38.94243164
OS -5.01987058 -38.93688428
OS -5.02911618 -38.9294878
OS -5.03743722 -38.92116676
OS -5.0448337 -38.91192116
OS -5.0448337 -39.1375138
OS -5.1234213 -39.1375138
OS -5.1234213 -38.49586916
OS -5.05223018 -38.49586916
OS -5.05223018 -38.55689012
OS -5.05130562 -38.555041
OS -5.04760738 -38.55134276
OS -5.04298458 -38.54487084
OS -5.0355881 -38.53747436
OS -5.02726706 -38.52822876
OS -5.01802146 -38.51990772
OS -5.00692674 -38.51158668
OS -4.99583202 -38.5041902
OS -4.9939829 -38.50326564
OS -4.99028466 -38.50141652
OS -4.98288818 -38.49864284
OS -4.97364258 -38.4949446
OS -4.96254786 -38.49124636
OS -4.94960402 -38.48847268
OS -4.93481106 -38.48662356
OS -4.91816898 -38.485699
OS -4.90799882 -38.485699
OS -4.90337602 -38.48662356
OE
OB -5.77800978 -38.49586916 I
OS -5.69849762 -38.49586916
OS -5.69849762 -38.55689012
OS -5.77800978 -38.55689012
OS -5.77800978 -38.82963532
OS -5.77800978 -38.83148444
OS -5.77800978 -38.83518268
OS -5.77800978 -38.84073004
OS -5.77708522 -38.84720196
OS -5.77616066 -38.86199492
OS -5.7752361 -38.86846684
OS -5.77431154 -38.87308964
OS -5.77338698 -38.87493876
OS -5.7706133 -38.878637
OS -5.76691506 -38.8832598
OS -5.76044314 -38.8878826
OS -5.75859402 -38.88880716
OS -5.75397122 -38.89065628
OS -5.74565018 -38.8925054
OS -5.7336309 -38.89342996
OS -5.7243853 -38.89342996
OS -5.7197625 -38.8925054
OS -5.71329058 -38.8925054
OS -5.7058941 -38.89158084
OS -5.69849762 -38.89065628
OS -5.68832746 -38.95999828
OS -5.69017658 -38.95999828
OS -5.69387482 -38.96092284
OS -5.70034674 -38.9618474
OS -5.70866778 -38.96277196
OS -5.71791338 -38.96462108
OS -5.72808354 -38.96554564
OS -5.74842386 -38.9664702
OS -5.75582034 -38.9664702
OS -5.76321682 -38.96554564
OS -5.77246242 -38.96462108
OS -5.78355714 -38.96369652
OS -5.79465186 -38.96092284
OS -5.80482202 -38.95814916
OS -5.81499218 -38.95352636
OS -5.81591674 -38.9526018
OS -5.81869042 -38.95075268
OS -5.82238866 -38.947979
OS -5.82793602 -38.9433562
OS -5.83255882 -38.9387334
OS -5.83810618 -38.93226148
OS -5.84365354 -38.92578956
OS -5.84735178 -38.91746852
OS -5.84735178 -38.91654396
OS -5.8492009 -38.91284572
OS -5.85012546 -38.9063738
OS -5.85197458 -38.8971282
OS -5.8538237 -38.88510892
OS -5.85474826 -38.87771244
OS -5.85474826 -38.8693914
OS -5.85567282 -38.85922124
OS -5.85659738 -38.84905108
OS -5.85659738 -38.83795636
OS -5.85659738 -38.82501252
OS -5.85659738 -38.55689012
OS -5.91484466 -38.55689012
OS -5.91484466 -38.49586916
OS -5.85659738 -38.49586916
OS -5.85659738 -38.38122372
OS -5.77800978 -38.33407116
OS -5.77800978 -38.49586916
OE
OB -5.97031826 -38.42745172 I
OS -5.99158314 -38.54671996
OS -6.04058482 -38.54671996
OS -6.06000058 -38.42745172
OS -6.06000058 -38.32020276
OS -5.97031826 -38.32020276
OS -5.97031826 -38.42745172
OE
OB -4.17852098 -39.1375138 I
OS -4.69904826 -39.1375138
OS -4.69904826 -39.08111564
OS -4.17852098 -39.08111564
OS -4.17852098 -39.1375138
OE
OB -5.4331489 -38.5504182 H
OS -5.43869626 -38.5504182
OS -5.44331906 -38.55134276
OS -5.45348922 -38.55226732
OS -5.46735762 -38.55596556
OS -5.48307514 -38.56151292
OS -5.49971722 -38.5689094
OS -5.51543474 -38.58000412
OS -5.52375578 -38.5874006
OS -5.53115226 -38.59479708
OS -5.53115226 -38.59572164
OS -5.53300138 -38.5966462
OS -5.5348505 -38.59941988
OS -5.53762418 -38.60311812
OS -5.54039786 -38.60774092
OS -5.54317154 -38.61328828
OS -5.54686978 -38.62068476
OS -5.55056802 -38.62808124
OS -5.55426626 -38.63732684
OS -5.5579645 -38.64657244
OS -5.56073818 -38.65766716
OS -5.56351186 -38.66968644
OS -5.56628554 -38.68263028
OS -5.56813466 -38.69649868
OS -5.56905922 -38.7122162
OS -5.56998378 -38.72793372
OS -5.56998378 -38.72885828
OS -5.56998378 -38.73163196
OS -5.56998378 -38.73625476
OS -5.56905922 -38.74272668
OS -5.56905922 -38.75012316
OS -5.56813466 -38.7584442
OS -5.56536098 -38.77785996
OS -5.56073818 -38.8000494
OS -5.5533417 -38.82223884
OS -5.5440961 -38.84350372
OS -5.53762418 -38.85274932
OS -5.53115226 -38.86199492
OS -5.5302277 -38.86199492
OS -5.52930314 -38.86384404
OS -5.52375578 -38.86846684
OS -5.51543474 -38.87586332
OS -5.50434002 -38.8832598
OS -5.49047162 -38.89158084
OS -5.47382954 -38.89897732
OS -5.45441378 -38.90360012
OS -5.44424362 -38.90452468
OS -5.4331489 -38.90544924
OS -5.42760154 -38.90544924
OS -5.42297874 -38.90452468
OS -5.41280858 -38.90267556
OS -5.39894018 -38.89990188
OS -5.38414722 -38.89435452
OS -5.36750514 -38.88695804
OS -5.35178762 -38.87586332
OS -5.34346658 -38.86846684
OS -5.3360701 -38.86107036
OS -5.33514554 -38.8601458
OS -5.33422098 -38.85922124
OS -5.33237186 -38.85644756
OS -5.32959818 -38.85274932
OS -5.3268245 -38.84812652
OS -5.32312626 -38.84257916
OS -5.31942802 -38.83518268
OS -5.31572978 -38.8277862
OS -5.31203154 -38.8185406
OS -5.30925786 -38.80837044
OS -5.30555962 -38.79727572
OS -5.30278594 -38.78525644
OS -5.30001226 -38.77138804
OS -5.29816314 -38.75751964
OS -5.29631402 -38.74180212
OS -5.29631402 -38.72516004
OS -5.29631402 -38.72423548
OS -5.29631402 -38.7214618
OS -5.29631402 -38.716839
OS -5.29723858 -38.71129164
OS -5.29723858 -38.70389516
OS -5.29816314 -38.69557412
OS -5.30093682 -38.67615836
OS -5.30555962 -38.65581804
OS -5.3129561 -38.6336286
OS -5.32312626 -38.61328828
OS -5.32867362 -38.60311812
OS -5.3360701 -38.59479708
OS -5.3360701 -38.59387252
OS -5.33791922 -38.59294796
OS -5.34346658 -38.5874006
OS -5.35178762 -38.58092868
OS -5.36288234 -38.57260764
OS -5.37675074 -38.5642866
OS -5.39339282 -38.55689012
OS -5.41188402 -38.55226732
OS -5.42205418 -38.55134276
OS -5.4331489 -38.5504182
OE
OB -3.94090906 -38.5504182 H
OS -3.94645642 -38.5504182
OS -3.95107922 -38.55134276
OS -3.96124938 -38.55226732
OS -3.97511778 -38.55596556
OS -3.9908353 -38.56151292
OS -4.00747738 -38.5689094
OS -4.0231949 -38.58000412
OS -4.03151594 -38.5874006
OS -4.03891242 -38.59479708
OS -4.03891242 -38.59572164
OS -4.04076154 -38.5966462
OS -4.04261066 -38.59941988
OS -4.04538434 -38.60311812
OS -4.04815802 -38.60774092
OS -4.0509317 -38.61328828
OS -4.05462994 -38.62068476
OS -4.05832818 -38.62808124
OS -4.06202642 -38.63732684
OS -4.06572466 -38.64657244
OS -4.06849834 -38.65766716
OS -4.07127202 -38.66968644
OS -4.0740457 -38.68263028
OS -4.07589482 -38.69649868
OS -4.07681938 -38.7122162
OS -4.07774394 -38.72793372
OS -4.07774394 -38.72885828
OS -4.07774394 -38.73163196
OS -4.07774394 -38.73625476
OS -4.07681938 -38.74272668
OS -4.07681938 -38.75012316
OS -4.07589482 -38.7584442
OS -4.07312114 -38.77785996
OS -4.06849834 -38.8000494
OS -4.06110186 -38.82223884
OS -4.05185626 -38.84350372
OS -4.04538434 -38.85274932
OS -4.03891242 -38.86199492
OS -4.03798786 -38.86199492
OS -4.0370633 -38.86384404
OS -4.03151594 -38.86846684
OS -4.0231949 -38.87586332
OS -4.01210018 -38.8832598
OS -3.99823178 -38.89158084
OS -3.9815897 -38.89897732
OS -3.96217394 -38.90360012
OS -3.95200378 -38.90452468
OS -3.94090906 -38.90544924
OS -3.9353617 -38.90544924
OS -3.9307389 -38.90452468
OS -3.92056874 -38.90267556
OS -3.90670034 -38.89990188
OS -3.89190738 -38.89435452
OS -3.8752653 -38.88695804
OS -3.85954778 -38.87586332
OS -3.85122674 -38.86846684
OS -3.84383026 -38.86107036
OS -3.8429057 -38.8601458
OS -3.84198114 -38.85922124
OS -3.84013202 -38.85644756
OS -3.83735834 -38.85274932
OS -3.83458466 -38.84812652
OS -3.83088642 -38.84257916
OS -3.82718818 -38.83518268
OS -3.82348994 -38.8277862
OS -3.8197917 -38.8185406
OS -3.81701802 -38.80837044
OS -3.81331978 -38.79727572
OS -3.8105461 -38.78525644
OS -3.80777242 -38.77138804
OS -3.8059233 -38.75751964
OS -3.80407418 -38.74180212
OS -3.80407418 -38.72516004
OS -3.80407418 -38.72423548
OS -3.80407418 -38.7214618
OS -3.80407418 -38.716839
OS -3.80499874 -38.71129164
OS -3.80499874 -38.70389516
OS -3.8059233 -38.69557412
OS -3.80869698 -38.67615836
OS -3.81331978 -38.65581804
OS -3.82071626 -38.6336286
OS -3.83088642 -38.61328828
OS -3.83643378 -38.60311812
OS -3.84383026 -38.59479708
OS -3.84383026 -38.59387252
OS -3.84567938 -38.59294796
OS -3.85122674 -38.5874006
OS -3.85954778 -38.58092868
OS -3.8706425 -38.57260764
OS -3.8845109 -38.5642866
OS -3.90115298 -38.55689012
OS -3.91964418 -38.55226732
OS -3.92981434 -38.55134276
OS -3.94090906 -38.5504182
OE
OB -4.92556546 -38.54764452 H
OS -4.93018826 -38.54764452
OS -4.9338865 -38.54856908
OS -4.9431321 -38.5504182
OS -4.95515138 -38.55319188
OS -4.96901978 -38.55873924
OS -4.98381274 -38.56706028
OS -4.99213378 -38.57260764
OS -4.99953026 -38.57907956
OS -5.00692674 -38.58647604
OS -5.01432322 -38.59479708
OS -5.01432322 -38.59572164
OS -5.01617234 -38.5966462
OS -5.01802146 -38.59941988
OS -5.01987058 -38.60311812
OS -5.02264426 -38.60866548
OS -5.0263425 -38.61421284
OS -5.03004074 -38.62160932
OS -5.03281442 -38.6290058
OS -5.03651266 -38.6382514
OS -5.0402109 -38.64842156
OS -5.04298458 -38.65951628
OS -5.04668282 -38.67153556
OS -5.04853194 -38.68540396
OS -5.05038106 -38.69927236
OS -5.05223018 -38.71406532
OS -5.05223018 -38.7307074
OS -5.05223018 -38.73163196
OS -5.05223018 -38.73440564
OS -5.05223018 -38.73902844
OS -5.05130562 -38.74550036
OS -5.05130562 -38.75289684
OS -5.05038106 -38.76121788
OS -5.04760738 -38.78063364
OS -5.04298458 -38.80282308
OS -5.03743722 -38.82408796
OS -5.02819162 -38.84535284
OS -5.02264426 -38.85459844
OS -5.01617234 -38.86291948
OS -5.01432322 -38.8647686
OS -5.00970042 -38.8693914
OS -5.00230394 -38.87678788
OS -4.99213378 -38.88418436
OS -4.97918994 -38.89158084
OS -4.96439698 -38.89897732
OS -4.9477549 -38.90360012
OS -4.9385093 -38.90452468
OS -4.9292637 -38.90544924
OS -4.92371634 -38.90544924
OS -4.9200181 -38.90452468
OS -4.9107725 -38.90267556
OS -4.89782866 -38.89990188
OS -4.88396026 -38.89435452
OS -4.8691673 -38.88695804
OS -4.85437434 -38.87586332
OS -4.84697786 -38.8693914
OS -4.83958138 -38.86199492
OS -4.83958138 -38.86107036
OS -4.83773226 -38.8601458
OS -4.83588314 -38.85737212
OS -4.83403402 -38.85367388
OS -4.83033578 -38.84905108
OS -4.8275621 -38.84257916
OS -4.82386386 -38.83610724
OS -4.82016562 -38.8277862
OS -4.81739194 -38.81946516
OS -4.8136937 -38.80837044
OS -4.80999546 -38.79727572
OS -4.80722178 -38.78525644
OS -4.80537266 -38.77138804
OS -4.80352354 -38.75659508
OS -4.80167442 -38.74087756
OS -4.80167442 -38.72423548
OS -4.80167442 -38.72331092
OS -4.80167442 -38.72053724
OS -4.80167442 -38.71591444
OS -4.80259898 -38.70944252
OS -4.80259898 -38.70204604
OS -4.80352354 -38.693725
OS -4.80629722 -38.67430924
OS -4.81092002 -38.65304436
OS -4.81739194 -38.63177948
OS -4.82663754 -38.6105146
OS -4.8321849 -38.60034444
OS -4.83865682 -38.5920234
OS -4.83865682 -38.59109884
OS -4.84050594 -38.59017428
OS -4.84512874 -38.58462692
OS -4.85252522 -38.578155
OS -4.86269538 -38.56983396
OS -4.87563922 -38.56151292
OS -4.89043218 -38.55411644
OS -4.90707426 -38.54949364
OS -4.91631986 -38.54856908
OS -4.92556546 -38.54764452
OE
OB -2.99323506 -38.5504182 H
OS -2.99878242 -38.5504182
OS -3.00248066 -38.55134276
OS -3.01265082 -38.55226732
OS -3.0246701 -38.555041
OS -3.03946306 -38.5596638
OS -3.05518058 -38.56613572
OS -3.06997354 -38.57538132
OS -3.0847665 -38.5874006
OS -3.08661562 -38.58924972
OS -3.09031386 -38.59387252
OS -3.09678578 -38.60219356
OS -3.1032577 -38.61328828
OS -3.11065418 -38.62623212
OS -3.1171261 -38.6428742
OS -3.12267346 -38.66228996
OS -3.12544714 -38.68355484
OS -2.86564578 -38.68355484
OS -2.86564578 -38.68263028
OS -2.86564578 -38.68078116
OS -2.86657034 -38.67800748
OS -2.86657034 -38.67430924
OS -2.86841946 -38.66321452
OS -2.87119314 -38.65119524
OS -2.87581594 -38.63640228
OS -2.88043874 -38.62253388
OS -2.88783522 -38.60866548
OS -2.89615626 -38.5966462
OS -2.89615626 -38.59572164
OS -2.89800538 -38.59479708
OS -2.90262818 -38.58924972
OS -2.91094922 -38.58185324
OS -2.92204394 -38.5735322
OS -2.93591234 -38.56521116
OS -2.95255442 -38.55781468
OS -2.97197018 -38.55226732
OS -2.98214034 -38.55134276
OS -2.99323506 -38.5504182
OE
OB -1.89300866 -38.72700916 H
OS -1.89393322 -38.72700916
OS -1.89485778 -38.72793372
OS -1.89763146 -38.72885828
OS -1.9013297 -38.72978284
OS -1.9059525 -38.73163196
OS -1.91149986 -38.73348108
OS -1.91797178 -38.7353302
OS -1.92536826 -38.73717932
OS -1.9336893 -38.739953
OS -1.94385946 -38.74180212
OS -1.95402962 -38.7445758
OS -1.9660489 -38.74734948
OS -1.97899274 -38.75012316
OS -1.99193658 -38.75289684
OS -2.00672954 -38.75474596
OS -2.02244706 -38.75751964
OS -2.02429618 -38.75751964
OS -2.02984354 -38.7584442
OS -2.03908914 -38.76029332
OS -2.0492593 -38.76214244
OS -2.06035402 -38.76399156
OS -2.07144874 -38.76676524
OS -2.0816189 -38.76953892
OS -2.0908645 -38.77323716
OS -2.09178906 -38.77323716
OS -2.09456274 -38.77508628
OS -2.09826098 -38.7769354
OS -2.10195922 -38.77970908
OS -2.11305394 -38.78710556
OS -2.12229954 -38.79820028
OS -2.12229954 -38.79912484
OS -2.12414866 -38.80097396
OS -2.12507322 -38.8046722
OS -2.12692234 -38.809295
OS -2.12877146 -38.81484236
OS -2.13062058 -38.82038972
OS -2.13154514 -38.8277862
OS -2.1324697 -38.83518268
OS -2.1324697 -38.83610724
OS -2.1324697 -38.84073004
OS -2.13154514 -38.8462774
OS -2.12969602 -38.85367388
OS -2.12692234 -38.86199492
OS -2.12229954 -38.87031596
OS -2.11675218 -38.87956156
OS -2.1093557 -38.8878826
OS -2.10843114 -38.88880716
OS -2.1047329 -38.89065628
OS -2.09918554 -38.89435452
OS -2.09178906 -38.89805276
OS -2.0816189 -38.901751
OS -2.06959962 -38.90544924
OS -2.05573122 -38.90729836
OS -2.03908914 -38.90822292
OS -2.03169266 -38.90822292
OS -2.02244706 -38.90729836
OS -2.0122769 -38.90544924
OS -1.99933306 -38.90360012
OS -1.98638922 -38.89990188
OS -1.97252082 -38.89527908
OS -1.95865242 -38.88880716
OS -1.9568033 -38.8878826
OS -1.95310506 -38.88510892
OS -1.94663314 -38.88048612
OS -1.93923666 -38.8740142
OS -1.93091562 -38.86661772
OS -1.92167002 -38.85737212
OS -1.91427354 -38.8462774
OS -1.90687706 -38.83425812
OS -1.9059525 -38.83333356
OS -1.90502794 -38.82963532
OS -1.90317882 -38.8231634
OS -1.90040514 -38.81484236
OS -1.89763146 -38.80374764
OS -1.89578234 -38.7908038
OS -1.89485778 -38.77508628
OS -1.89393322 -38.75659508
OS -1.89300866 -38.72700916
OE
SE
S P 0
OB -4.66714078 -36.5016923 I
OS -4.65465922 -36.5016923
OS -4.62553558 -36.50307914
OS -4.5950251 -36.50723966
OS -4.56174094 -36.51140018
OS -4.53123046 -36.51833438
OS -4.51597522 -36.5224949
OS -4.50349366 -36.52665542
OS -4.50210682 -36.52665542
OS -4.50071998 -36.52804226
OS -4.49239894 -36.53220278
OS -4.47991738 -36.53775014
OS -4.46466214 -36.54745802
OS -4.44802006 -36.55993958
OS -4.42999114 -36.57658166
OS -4.41334906 -36.59599742
OS -4.39670698 -36.61818686
OS -4.39670698 -36.6195737
OS -4.39532014 -36.62096054
OS -4.38977278 -36.62928158
OS -4.38422542 -36.64314998
OS -4.37590438 -36.6611789
OS -4.36897018 -36.6819815
OS -4.36203598 -36.70694462
OS -4.35787546 -36.73329458
OS -4.35648862 -36.76241822
OS -4.35648862 -36.76380506
OS -4.35648862 -36.76657874
OS -4.35648862 -36.7721261
OS -4.35787546 -36.7790603
OS -4.35787546 -36.78876818
OS -4.3592623 -36.79847606
OS -4.36480966 -36.82205234
OS -4.3731307 -36.84978914
OS -4.38422542 -36.87891278
OS -4.4008675 -36.90803642
OS -4.41196222 -36.92190482
OS -4.42305694 -36.93577322
OS -4.42444378 -36.93716006
OS -4.42583062 -36.9385469
OS -4.42999114 -36.94270742
OS -4.4355385 -36.94686794
OS -4.4424727 -36.9524153
OS -4.45079374 -36.95796266
OS -4.46188846 -36.96489686
OS -4.47298318 -36.9732179
OS -4.48685158 -36.9801521
OS -4.50210682 -36.9870863
OS -4.5187489 -36.99540734
OS -4.53677782 -37.00234154
OS -4.55758042 -37.0078889
OS -4.57838302 -37.0148231
OS -4.6019593 -37.01898362
OS -4.62692242 -37.02314414
OS -4.62414874 -37.02453098
OS -4.61860138 -37.02730466
OS -4.61028034 -37.03285202
OS -4.59918562 -37.03839938
OS -4.5742225 -37.05365462
OS -4.56174094 -37.0633625
OS -4.55064622 -37.07168354
OS -4.54787254 -37.07445722
OS -4.54093834 -37.08139142
OS -4.52984362 -37.09248614
OS -4.51597522 -37.10635454
OS -4.50071998 -37.1257703
OS -4.48269106 -37.1465729
OS -4.46466214 -37.17153602
OS -4.44524638 -37.19927282
OS -4.28021242 -37.45999874
OS -4.43831218 -37.45999874
OS -4.56451462 -37.26029378
OS -4.56451462 -37.25890694
OS -4.5672883 -37.25613326
OS -4.57006198 -37.25197274
OS -4.5742225 -37.24642538
OS -4.58393038 -37.23117014
OS -4.59641194 -37.21175438
OS -4.61166718 -37.19095178
OS -4.62692242 -37.16876234
OS -4.64217766 -37.14795974
OS -4.65604606 -37.12854398
OS -4.6574329 -37.12715714
OS -4.66159342 -37.12160978
OS -4.66852762 -37.11328874
OS -4.6782355 -37.10358086
OS -4.6990381 -37.08277826
OS -4.71013282 -37.07307038
OS -4.72122754 -37.06474934
OS -4.72261438 -37.0633625
OS -4.72538806 -37.06197566
OS -4.73093542 -37.05920198
OS -4.73925646 -37.05504146
OS -4.7475775 -37.05088094
OS -4.75728538 -37.04672042
OS -4.77947482 -37.03978622
OS -4.78086166 -37.03978622
OS -4.78363534 -37.03839938
OS -4.7891827 -37.03839938
OS -4.7961169 -37.03701254
OS -4.80582478 -37.0356257
OS -4.8169195 -37.0356257
OS -4.83217474 -37.03423886
OS -4.99582186 -37.03423886
OS -4.99582186 -37.45999874
OS -5.12341114 -37.45999874
OS -5.12341114 -36.50030546
OS -4.6782355 -36.50030546
OS -4.66714078 -36.5016923
OE
OB -1.0100437 -37.45999874 I
OS -1.13208562 -37.45999874
OS -1.13208562 -36.65701838
OS -1.4122273 -37.45999874
OS -1.52594818 -37.45999874
OS -1.80331618 -36.64314998
OS -1.80331618 -37.45999874
OS -1.9253581 -37.45999874
OS -1.9253581 -36.50030546
OS -1.73536102 -36.50030546
OS -1.50791926 -37.1812439
OS -1.50791926 -37.18263074
OS -1.50653242 -37.18540442
OS -1.50514558 -37.18956494
OS -1.5023719 -37.19649914
OS -1.49682454 -37.21314122
OS -1.48989034 -37.23394382
OS -1.48295614 -37.2575201
OS -1.4746351 -37.28109638
OS -1.4677009 -37.30328582
OS -1.46215354 -37.32270158
OS -1.4607667 -37.3199279
OS -1.45937986 -37.3129937
OS -1.45521934 -37.30051214
OS -1.44967198 -37.28387006
OS -1.44273778 -37.26168062
OS -1.4330299 -37.23533066
OS -1.42332202 -37.20482018
OS -1.41084046 -37.16876234
OS -1.18062502 -36.50030546
OS -1.0100437 -36.50030546
OS -1.0100437 -37.45999874
OE
OB -2.02382374 -37.45999874 I
OS -2.1680551 -37.45999874
OS -2.28038914 -37.16876234
OS -2.68257274 -37.16876234
OS -2.78658574 -37.45999874
OS -2.92110922 -37.45999874
OS -2.55498346 -36.50030546
OS -2.41629946 -36.50030546
OS -2.02382374 -37.45999874
OE
OB -3.02928274 -37.45999874 I
OS -3.16103254 -37.45999874
OS -3.66306862 -36.70694462
OS -3.66306862 -37.45999874
OS -3.78511054 -37.45999874
OS -3.78511054 -36.50030546
OS -3.65474758 -36.50030546
OS -3.15132466 -37.25474642
OS -3.15132466 -36.50030546
OS -3.02928274 -36.50030546
OS -3.02928274 -37.45999874
OE
OB -5.3231161 -36.61402634 I
OS -5.89033366 -36.61402634
OS -5.89033366 -36.90664958
OS -5.35917394 -36.90664958
OS -5.35917394 -37.02037046
OS -5.89033366 -37.02037046
OS -5.89033366 -37.34627786
OS -5.30092666 -37.34627786
OS -5.30092666 -37.45999874
OS -6.01792294 -37.45999874
OS -6.01792294 -36.50030546
OS -5.3231161 -36.50030546
OS -5.3231161 -36.61402634
OE
OB -0.10721086 -36.61402634 I
OS -0.67442842 -36.61402634
OS -0.67442842 -36.90664958
OS -0.1432687 -36.90664958
OS -0.1432687 -37.02037046
OS -0.67442842 -37.02037046
OS -0.67442842 -37.34627786
OS -0.08502142 -37.34627786
OS -0.08502142 -37.45999874
OS -0.8020177 -37.45999874
OS -0.8020177 -36.50030546
OS -0.10721086 -36.50030546
OS -0.10721086 -36.61402634
OE
OB -8.43241138 -37.34627786 I
OS -7.95949894 -37.34627786
OS -7.95949894 -37.45999874
OS -8.56000066 -37.45999874
OS -8.56000066 -36.50030546
OS -8.43241138 -36.50030546
OS -8.43241138 -37.34627786
OE
OB -6.51718534 -37.05365462 I
OS -6.51718534 -37.45999874
OS -6.64477462 -37.45999874
OS -6.64477462 -37.05365462
OS -7.0150609 -36.50030546
OS -6.86112166 -36.50030546
OS -6.67251142 -36.79154186
OS -6.67251142 -36.7929287
OS -6.66973774 -36.79570238
OS -6.66696406 -36.7998629
OS -6.66419038 -36.80541026
OS -6.65864302 -36.81234446
OS -6.65309566 -36.8206655
OS -6.6406141 -36.8414681
OS -6.62535886 -36.86643122
OS -6.60871678 -36.89416802
OS -6.59068786 -36.92329166
OS -6.57404578 -36.95380214
OS -6.57404578 -36.9524153
OS -6.57265894 -36.94964162
OS -6.56988526 -36.9454811
OS -6.56572474 -36.93993374
OS -6.56156422 -36.93299954
OS -6.55601686 -36.9246785
OS -6.5435353 -36.9038759
OS -6.52828006 -36.87891278
OS -6.51025114 -36.84978914
OS -6.48944854 -36.81789182
OS -6.4672591 -36.78322082
OS -6.28280938 -36.50030546
OS -6.1344175 -36.50030546
OS -6.51718534 -37.05365462
OE
OB -7.01644774 -37.45999874 I
OS -7.1606791 -37.45999874
OS -7.27301314 -37.16876234
OS -7.67519674 -37.16876234
OS -7.77920974 -37.45999874
OS -7.91373322 -37.45999874
OS -7.54760746 -36.50030546
OS -7.40892346 -36.50030546
OS -7.01644774 -37.45999874
OE
OB -7.48103914 -36.60015794 H
OS -7.48103914 -36.60154478
OS -7.48242598 -36.60431846
OS -7.48242598 -36.60986582
OS -7.48519966 -36.61541318
OS -7.4865865 -36.62512106
OS -7.48936018 -36.63482894
OS -7.49490754 -36.65840522
OS -7.50184174 -36.68614202
OS -7.51154962 -36.7166525
OS -7.5212575 -36.74993666
OS -7.53373906 -36.78460766
OS -7.63775206 -37.06474934
OS -7.3132315 -37.06474934
OS -7.41308398 -36.80124974
OS -7.41308398 -36.7998629
OS -7.41447082 -36.79570238
OS -7.4172445 -36.78876818
OS -7.42001818 -36.78044714
OS -7.4241787 -36.77073926
OS -7.42833922 -36.7582577
OS -7.43249974 -36.7443893
OS -7.4380471 -36.7305209
OS -7.44914182 -36.69862358
OS -7.46023654 -36.66533942
OS -7.47133126 -36.63205526
OS -7.48103914 -36.60015794
OE
OB -4.69349074 -36.60709214 H
OS -4.99582186 -36.60709214
OS -4.99582186 -36.9246785
OS -4.71013282 -36.9246785
OS -4.69349074 -36.92329166
OS -4.67407498 -36.92190482
OS -4.65188554 -36.92051798
OS -4.6296961 -36.9177443
OS -4.60750666 -36.91358378
OS -4.5880909 -36.90803642
OS -4.58531722 -36.90664958
OS -4.57976986 -36.9038759
OS -4.57144882 -36.89971538
OS -4.5603541 -36.89416802
OS -4.54787254 -36.88584698
OS -4.53539098 -36.8761391
OS -4.52290942 -36.86365754
OS -4.51320154 -36.84978914
OS -4.5118147 -36.8484023
OS -4.50904102 -36.84285494
OS -4.5048805 -36.8345339
OS -4.49933314 -36.82343918
OS -4.49517262 -36.81095762
OS -4.4910121 -36.79708922
OS -4.48823842 -36.78044714
OS -4.48685158 -36.76380506
OS -4.48685158 -36.76241822
OS -4.48685158 -36.76103138
OS -4.48823842 -36.75271034
OS -4.48962526 -36.74022878
OS -4.49239894 -36.7235867
OS -4.49933314 -36.70694462
OS -4.50765418 -36.68752886
OS -4.52013574 -36.66949994
OS -4.53677782 -36.65147102
OS -4.5395515 -36.65008418
OS -4.5464857 -36.64453682
OS -4.55758042 -36.63760262
OS -4.57560934 -36.62928158
OS -4.59641194 -36.62096054
OS -4.62414874 -36.61402634
OS -4.65604606 -36.60847898
OS -4.69349074 -36.60709214
OE
OB -2.48841514 -36.60015794 H
OS -2.48841514 -36.60154478
OS -2.48980198 -36.60431846
OS -2.48980198 -36.60986582
OS -2.49257566 -36.61541318
OS -2.4939625 -36.62512106
OS -2.49673618 -36.63482894
OS -2.50228354 -36.65840522
OS -2.50921774 -36.68614202
OS -2.51892562 -36.7166525
OS -2.5286335 -36.74993666
OS -2.54111506 -36.78460766
OS -2.64512806 -37.06474934
OS -2.3206075 -37.06474934
OS -2.42045998 -36.80124974
OS -2.42045998 -36.7998629
OS -2.42184682 -36.79570238
OS -2.4246205 -36.78876818
OS -2.42739418 -36.78044714
OS -2.4315547 -36.77073926
OS -2.43571522 -36.7582577
OS -2.43987574 -36.7443893
OS -2.4454231 -36.7305209
OS -2.45651782 -36.69862358
OS -2.46761254 -36.66533942
OS -2.47870726 -36.63205526
OS -2.48841514 -36.60015794
OE
SE
S P 0
OB 10.53049202 -3.1249366 I
OS 10.54158674 -3.12632344
OS 10.55545514 -3.12909712
OS 10.57071038 -3.1318708
OS 10.5887393 -3.13603132
OS 10.60538138 -3.14019184
OS 10.62479714 -3.14712604
OS 10.64282606 -3.15406024
OS 10.66224182 -3.16376812
OS 10.68165758 -3.17486284
OS 10.70107334 -3.1873444
OS 10.71910226 -3.20259964
OS 10.73574434 -3.21924172
OS 10.73713118 -3.22062856
OS 10.73990486 -3.22340224
OS 10.74406538 -3.2289496
OS 10.74961274 -3.23727064
OS 10.75654694 -3.24697852
OS 10.76348114 -3.25807324
OS 10.77180218 -3.27194164
OS 10.78012322 -3.28858372
OS 10.78844426 -3.30661264
OS 10.7967653 -3.3260284
OS 10.8036995 -3.34821784
OS 10.8106337 -3.37179412
OS 10.81618106 -3.39814408
OS 10.82034158 -3.42588088
OS 10.82311526 -3.45500452
OS 10.8245021 -3.48690184
OS 10.8245021 -3.48828868
OS 10.8245021 -3.49383604
OS 10.8245021 -3.50354392
OS 10.82311526 -3.51741232
OS 10.30305026 -3.51741232
OS 10.30305026 -3.51879916
OS 10.30305026 -3.52295968
OS 10.3044371 -3.52850704
OS 10.3044371 -3.53682808
OS 10.30582394 -3.54653596
OS 10.30859762 -3.55763068
OS 10.31275814 -3.5825938
OS 10.32107918 -3.6103306
OS 10.3321739 -3.64084108
OS 10.34742914 -3.66857788
OS 10.3668449 -3.693541
OS 10.36823174 -3.693541
OS 10.36961858 -3.69631468
OS 10.37793962 -3.70324888
OS 10.39042118 -3.71295676
OS 10.40706326 -3.72266464
OS 10.4292527 -3.73375936
OS 10.45421582 -3.74346724
OS 10.48195262 -3.75040144
OS 10.49720786 -3.75178828
OS 10.51384994 -3.75317512
OS 10.52494466 -3.75317512
OS 10.53742622 -3.75178828
OS 10.55268146 -3.7490146
OS 10.56932354 -3.74485408
OS 10.5887393 -3.73930672
OS 10.60676822 -3.73098568
OS 10.62479714 -3.71989096
OS 10.62618398 -3.71850412
OS 10.63311818 -3.71295676
OS 10.64143922 -3.70463572
OS 10.6511471 -3.693541
OS 10.66224182 -3.67828576
OS 10.67472338 -3.65887
OS 10.68720494 -3.63668056
OS 10.69829966 -3.6103306
OS 10.82034158 -3.62558584
OS 10.82034158 -3.62697268
OS 10.81895474 -3.62974636
OS 10.8175679 -3.63529372
OS 10.81479422 -3.64361476
OS 10.8106337 -3.6519358
OS 10.80647318 -3.66303052
OS 10.79537846 -3.6866068
OS 10.78151006 -3.71295676
OS 10.7620943 -3.74069356
OS 10.73990486 -3.76704352
OS 10.71216806 -3.79200664
OS 10.71078122 -3.79200664
OS 10.70800754 -3.79478032
OS 10.70384702 -3.797554
OS 10.69829966 -3.80171452
OS 10.68997862 -3.80587504
OS 10.68165758 -3.81003556
OS 10.67056286 -3.81558292
OS 10.6580813 -3.82113028
OS 10.6442129 -3.82667764
OS 10.6303445 -3.832225
OS 10.5956735 -3.84054604
OS 10.55684198 -3.84748024
OS 10.51384994 -3.85025392
OS 10.4985947 -3.85025392
OS 10.48888682 -3.84886708
OS 10.47640526 -3.84748024
OS 10.46115002 -3.84470656
OS 10.44450794 -3.84193288
OS 10.42647902 -3.8391592
OS 10.3876475 -3.82806448
OS 10.3668449 -3.81974344
OS 10.34742914 -3.8114224
OS 10.32662654 -3.80032768
OS 10.30721078 -3.78784612
OS 10.28918186 -3.77397772
OS 10.27115294 -3.75733564
OS 10.2697661 -3.7559488
OS 10.26699242 -3.75317512
OS 10.2628319 -3.74762776
OS 10.25728454 -3.73930672
OS 10.25035034 -3.72959884
OS 10.24341614 -3.71850412
OS 10.2350951 -3.70463572
OS 10.22677406 -3.68938048
OS 10.21845302 -3.67135156
OS 10.21013198 -3.6519358
OS 10.20319778 -3.62974636
OS 10.19626358 -3.60617008
OS 10.19071622 -3.58120696
OS 10.1865557 -3.55347016
OS 10.18378202 -3.52434652
OS 10.18239518 -3.49383604
OS 10.18239518 -3.4924492
OS 10.18239518 -3.485515
OS 10.18239518 -3.47719396
OS 10.18378202 -3.4647124
OS 10.18516886 -3.44945716
OS 10.1865557 -3.43281508
OS 10.18932938 -3.41339932
OS 10.1934899 -3.39398356
OS 10.20458462 -3.34960468
OS 10.21151882 -3.32741524
OS 10.21983986 -3.30383896
OS 10.23093458 -3.28164952
OS 10.24341614 -3.26084692
OS 10.25728454 -3.24004432
OS 10.27253978 -3.22062856
OS 10.27392662 -3.21924172
OS 10.2767003 -3.21646804
OS 10.28224766 -3.21230752
OS 10.28918186 -3.20537332
OS 10.2975029 -3.19843912
OS 10.30859762 -3.19011808
OS 10.32107918 -3.1804102
OS 10.33633442 -3.17208916
OS 10.35158966 -3.16238128
OS 10.36961858 -3.15406024
OS 10.38903434 -3.1457392
OS 10.40983694 -3.138805
OS 10.43202638 -3.1318708
OS 10.45560266 -3.12771028
OS 10.48056578 -3.1249366
OS 10.50691574 -3.12354976
OS 10.52078414 -3.12354976
OS 10.53049202 -3.1249366
OE
OB 11.24610146 -3.1249366 I
OS 11.2613567 -3.12771028
OS 11.27938562 -3.13325764
OS 11.29880138 -3.14019184
OS 11.32099082 -3.14989972
OS 11.3445671 -3.16238128
OS 11.30157506 -3.2705548
OS 11.30018822 -3.26916796
OS 11.29464086 -3.26639428
OS 11.28631982 -3.26223376
OS 11.2752251 -3.25807324
OS 11.26274354 -3.25391272
OS 11.2474883 -3.2497522
OS 11.23223306 -3.24697852
OS 11.21697782 -3.24559168
OS 11.21004362 -3.24559168
OS 11.20310942 -3.24697852
OS 11.19340154 -3.24836536
OS 11.18369366 -3.25113904
OS 11.1712121 -3.25529956
OS 11.15873054 -3.26084692
OS 11.14763582 -3.26916796
OS 11.14624898 -3.2705548
OS 11.14208846 -3.27332848
OS 11.13792794 -3.27887584
OS 11.13099374 -3.28581004
OS 11.12405954 -3.29551792
OS 11.11712534 -3.30661264
OS 11.11019114 -3.3190942
OS 11.10464378 -3.33434944
OS 11.10325694 -3.33712312
OS 11.1018701 -3.34544416
OS 11.09909642 -3.35792572
OS 11.0949359 -3.3745678
OS 11.09077538 -3.3953704
OS 11.0880017 -3.41894668
OS 11.08661486 -3.4439098
OS 11.08522802 -3.4716466
OS 11.08522802 -3.83499868
OS 10.96734662 -3.83499868
OS 10.96734662 -3.138805
OS 11.0741333 -3.138805
OS 11.0741333 -3.24420484
OS 11.07552014 -3.242818
OS 11.0810675 -3.23311012
OS 11.0880017 -3.22062856
OS 11.09909642 -3.20537332
OS 11.11019114 -3.19011808
OS 11.1226727 -3.173476
OS 11.13515426 -3.1596076
OS 11.14763582 -3.14851288
OS 11.14902266 -3.14712604
OS 11.15318318 -3.14435236
OS 11.16150422 -3.14019184
OS 11.16982526 -3.13603132
OS 11.18091998 -3.1318708
OS 11.19478838 -3.12771028
OS 11.20865678 -3.1249366
OS 11.22391202 -3.12354976
OS 11.2336199 -3.12354976
OS 11.24610146 -3.1249366
OE
OB 9.98685074 -3.138805 I
OS 10.10611898 -3.138805
OS 10.10611898 -3.23033644
OS 9.98685074 -3.23033644
OS 9.98685074 -3.63945424
OS 9.98685074 -3.64222792
OS 9.98685074 -3.64777528
OS 9.98685074 -3.65609632
OS 9.98823758 -3.6658042
OS 9.98962442 -3.68799364
OS 9.99101126 -3.69770152
OS 9.9923981 -3.70463572
OS 9.99378494 -3.7074094
OS 9.99794546 -3.71295676
OS 10.00349282 -3.71989096
OS 10.0132007 -3.72682516
OS 10.01597438 -3.728212
OS 10.02290858 -3.73098568
OS 10.03539014 -3.73375936
OS 10.05341906 -3.7351462
OS 10.06728746 -3.7351462
OS 10.07422166 -3.73375936
OS 10.08392954 -3.73375936
OS 10.09502426 -3.73237252
OS 10.10611898 -3.73098568
OS 10.12137422 -3.83499868
OS 10.11860054 -3.83499868
OS 10.11305318 -3.83638552
OS 10.1033453 -3.83777236
OS 10.09086374 -3.8391592
OS 10.07699534 -3.84193288
OS 10.0617401 -3.84331972
OS 10.03122962 -3.84470656
OS 10.0201349 -3.84470656
OS 10.00904018 -3.84331972
OS 9.99517178 -3.84193288
OS 9.9785297 -3.84054604
OS 9.96188762 -3.83638552
OS 9.94663238 -3.832225
OS 9.93137714 -3.8252908
OS 9.9299903 -3.82390396
OS 9.92582978 -3.82113028
OS 9.92028242 -3.81696976
OS 9.91196138 -3.81003556
OS 9.90502718 -3.80310136
OS 9.89670614 -3.79339348
OS 9.8883851 -3.7836856
OS 9.88283774 -3.77120404
OS 9.88283774 -3.7698172
OS 9.88006406 -3.76426984
OS 9.87867722 -3.75456196
OS 9.87590354 -3.74069356
OS 9.87312986 -3.72266464
OS 9.87174302 -3.71156992
OS 9.87174302 -3.69908836
OS 9.87035618 -3.68383312
OS 9.86896934 -3.66857788
OS 9.86896934 -3.6519358
OS 9.86896934 -3.63252004
OS 9.86896934 -3.23033644
OS 9.78159842 -3.23033644
OS 9.78159842 -3.138805
OS 9.86896934 -3.138805
OS 9.86896934 -2.96683684
OS 9.98685074 -2.896108
OS 9.98685074 -3.138805
OE
OB 8.6332949 -3.12493914 I
OS 8.64300278 -3.12632598
OS 8.65548434 -3.12909966
OS 8.66935274 -3.13187334
OS 8.68460798 -3.13603386
OS 8.69986322 -3.14158122
OS 8.7165053 -3.14851542
OS 8.73314738 -3.15683646
OS 8.7511763 -3.16654434
OS 8.76781838 -3.17763906
OS 8.78446046 -3.19150746
OS 8.80110254 -3.2067627
OS 8.81635778 -3.22479162
OS 8.81635778 -3.13880754
OS 8.9245313 -3.13880754
OS 8.9245313 -3.7406961
OS 8.9245313 -3.74208294
OS 8.9245313 -3.7476303
OS 8.9245313 -3.75595134
OS 8.9245313 -3.76704606
OS 8.92314446 -3.77952762
OS 8.92314446 -3.79478286
OS 8.92175762 -3.81142494
OS 8.92037078 -3.82945386
OS 8.91621026 -3.86689854
OS 8.9106629 -3.90573006
OS 8.90650238 -3.92375898
OS 8.90234186 -3.94040106
OS 8.8967945 -3.9556563
OS 8.89124714 -3.9695247
OS 8.89124714 -3.97091154
OS 8.8898603 -3.97229838
OS 8.88431294 -3.98061942
OS 8.87737874 -3.99310098
OS 8.86628402 -4.00835622
OS 8.85102878 -4.0249983
OS 8.83299986 -4.04302722
OS 8.81081042 -4.06105614
OS 8.7858473 -4.07631138
OS 8.78446046 -4.07631138
OS 8.78307362 -4.07769822
OS 8.7789131 -4.0804719
OS 8.77336574 -4.08185874
OS 8.76643154 -4.08601926
OS 8.7581105 -4.08879294
OS 8.7373079 -4.09572714
OS 8.71234478 -4.10404818
OS 8.6818343 -4.10959554
OS 8.6471633 -4.1151429
OS 8.60971862 -4.11652974
OS 8.59723706 -4.11652974
OS 8.58891602 -4.1151429
OS 8.5778213 -4.1151429
OS 8.56672658 -4.11375606
OS 8.55285818 -4.11236922
OS 8.53760294 -4.10959554
OS 8.50570562 -4.10266134
OS 8.47242146 -4.09295346
OS 8.4391373 -4.07908506
OS 8.40862682 -4.0596693
OS 8.40723998 -4.05828246
OS 8.40585314 -4.05689562
OS 8.39614526 -4.04857458
OS 8.38505054 -4.03609302
OS 8.37118214 -4.0180641
OS 8.35731374 -3.99448782
OS 8.34483218 -3.96536418
OS 8.34067166 -3.9487221
OS 8.33789798 -3.93069318
OS 8.3351243 -3.91266426
OS 8.3351243 -3.89186166
OS 8.45023202 -3.9071169
OS 8.45023202 -3.90989058
OS 8.45161886 -3.91543794
OS 8.45439254 -3.92514582
OS 8.45716622 -3.93762738
OS 8.46271358 -3.95010894
OS 8.46964778 -3.9625905
OS 8.47796882 -3.97507206
OS 8.48906354 -3.98477994
OS 8.49183722 -3.98616678
OS 8.49738458 -3.9903273
OS 8.50709246 -3.99587466
OS 8.52096086 -4.00142202
OS 8.53760294 -4.00835622
OS 8.55840554 -4.01390358
OS 8.58336866 -4.0180641
OS 8.60971862 -4.01945094
OS 8.62358702 -4.01945094
OS 8.63745542 -4.0180641
OS 8.65687118 -4.01529042
OS 8.67628694 -4.0111299
OS 8.69708954 -4.00558254
OS 8.71789214 -3.9972615
OS 8.73592106 -3.98616678
OS 8.7373079 -3.98477994
OS 8.74285526 -3.98061942
OS 8.7511763 -3.97229838
OS 8.76088418 -3.9625905
OS 8.77059206 -3.9487221
OS 8.78029994 -3.93346686
OS 8.79000782 -3.91543794
OS 8.79694202 -3.89463534
OS 8.79694202 -3.8932485
OS 8.79832886 -3.88770114
OS 8.7997157 -3.87660642
OS 8.80110254 -3.86273802
OS 8.80248938 -3.85303014
OS 8.80248938 -3.84193542
OS 8.80387622 -3.82945386
OS 8.80387622 -3.81558546
OS 8.80387622 -3.80033022
OS 8.80526306 -3.7823013
OS 8.80526306 -3.76427238
OS 8.80526306 -3.74346978
OS 8.80387622 -3.74485662
OS 8.80110254 -3.7476303
OS 8.79694202 -3.75179082
OS 8.79139466 -3.75733818
OS 8.78446046 -3.76427238
OS 8.77475258 -3.77259342
OS 8.76365786 -3.78091446
OS 8.75256314 -3.7892355
OS 8.7234395 -3.80587758
OS 8.69154218 -3.82113282
OS 8.67351326 -3.82668018
OS 8.6540975 -3.8308407
OS 8.6332949 -3.83361438
OS 8.6124923 -3.83500122
OS 8.6055581 -3.83500122
OS 8.5986239 -3.83361438
OS 8.58891602 -3.83361438
OS 8.57643446 -3.83222754
OS 8.56256606 -3.82945386
OS 8.54731082 -3.82668018
OS 8.53066874 -3.82251966
OS 8.51263982 -3.8169723
OS 8.4946109 -3.8100381
OS 8.47658198 -3.80171706
OS 8.45716622 -3.79200918
OS 8.4391373 -3.77952762
OS 8.42110838 -3.76565922
OS 8.4044663 -3.75040398
OS 8.38921106 -3.73237506
OS 8.38782422 -3.73098822
OS 8.38643738 -3.72821454
OS 8.38227686 -3.72128034
OS 8.3767295 -3.71434614
OS 8.37118214 -3.70325142
OS 8.36424794 -3.6921567
OS 8.35731374 -3.6782883
OS 8.35037954 -3.66164622
OS 8.34344534 -3.64500414
OS 8.33651114 -3.62558838
OS 8.32957694 -3.60617262
OS 8.32402958 -3.58398318
OS 8.3143217 -3.53683062
OS 8.31293486 -3.51048066
OS 8.31154802 -3.4841307
OS 8.31154802 -3.48274386
OS 8.31154802 -3.47997018
OS 8.31154802 -3.47442282
OS 8.31154802 -3.46748862
OS 8.31293486 -3.45778074
OS 8.31293486 -3.44807286
OS 8.31570854 -3.42310974
OS 8.31986906 -3.39537294
OS 8.32680326 -3.36486246
OS 8.3351243 -3.33296514
OS 8.34760586 -3.30106782
OS 8.34760586 -3.29968098
OS 8.3489927 -3.2969073
OS 8.35176638 -3.29274678
OS 8.35454006 -3.28719942
OS 8.3628611 -3.27194418
OS 8.37395582 -3.25252842
OS 8.38921106 -3.23172582
OS 8.40723998 -3.21092322
OS 8.42804258 -3.18873378
OS 8.45161886 -3.17070486
OS 8.4530057 -3.17070486
OS 8.45439254 -3.16931802
OS 8.45855306 -3.16654434
OS 8.46410042 -3.16377066
OS 8.47796882 -3.15544962
OS 8.49738458 -3.14712858
OS 8.52096086 -3.13880754
OS 8.54869766 -3.1304865
OS 8.57920814 -3.12493914
OS 8.6124923 -3.1235523
OS 8.62497386 -3.1235523
OS 8.6332949 -3.12493914
OE
OB 9.22131506 -3.21924426 I
OS 9.2227019 -3.21785742
OS 9.22547558 -3.21508374
OS 9.2296361 -3.21092322
OS 9.2365703 -3.20398902
OS 9.2435045 -3.19705482
OS 9.25321238 -3.18873378
OS 9.26569394 -3.18041274
OS 9.2781755 -3.17070486
OS 9.2920439 -3.16238382
OS 9.30729914 -3.15406278
OS 9.34335698 -3.13880754
OS 9.36277274 -3.13187334
OS 9.38357534 -3.12771282
OS 9.40576478 -3.12493914
OS 9.42795422 -3.1235523
OS 9.44043578 -3.1235523
OS 9.45569102 -3.12493914
OS 9.47371994 -3.12771282
OS 9.49452254 -3.13048396
OS 9.51671198 -3.13603132
OS 9.53890142 -3.14435236
OS 9.56109086 -3.15406024
OS 9.56386454 -3.15544708
OS 9.57079874 -3.1596076
OS 9.58050662 -3.1665418
OS 9.59298818 -3.17624968
OS 9.60546974 -3.18873124
OS 9.61933814 -3.20259964
OS 9.6318197 -3.21924172
OS 9.64291442 -3.23865748
OS 9.64430126 -3.24143116
OS 9.64707494 -3.24836536
OS 9.65123546 -3.26084692
OS 9.65539598 -3.27887584
OS 9.6595565 -3.30106528
OS 9.66371702 -3.32741524
OS 9.6664907 -3.35931256
OS 9.66787754 -3.3953704
OS 9.66787754 -3.83499868
OS 9.54999614 -3.83499868
OS 9.54999614 -3.39398356
OS 9.54999614 -3.39259672
OS 9.54999614 -3.38982304
OS 9.54999614 -3.38566252
OS 9.54999614 -3.38011516
OS 9.5486093 -3.36485992
OS 9.54583562 -3.34544416
OS 9.54028826 -3.32464156
OS 9.53335406 -3.30383896
OS 9.52364618 -3.28303636
OS 9.51116462 -3.26639428
OS 9.50977778 -3.26500744
OS 9.50423042 -3.25946008
OS 9.49590938 -3.25252588
OS 9.48342782 -3.24559168
OS 9.46817258 -3.23727318
OS 9.45014366 -3.23172582
OS 9.42795422 -3.22617846
OS 9.4029911 -3.22479162
OS 9.39467006 -3.22479162
OS 9.38496218 -3.22617846
OS 9.37109378 -3.2275653
OS 9.35722538 -3.23172582
OS 9.3405833 -3.23588634
OS 9.32394122 -3.24282054
OS 9.3059123 -3.25252842
OS 9.30452546 -3.25391526
OS 9.2989781 -3.25807578
OS 9.29065706 -3.26362314
OS 9.28094918 -3.27194418
OS 9.26985446 -3.2830389
OS 9.25875974 -3.29552046
OS 9.24905186 -3.3107757
OS 9.24073082 -3.32741778
OS 9.23934398 -3.33019146
OS 9.23795714 -3.33573882
OS 9.23518346 -3.34683354
OS 9.23102294 -3.36070194
OS 9.22686242 -3.37873086
OS 9.22408874 -3.4009203
OS 9.2227019 -3.42588342
OS 9.22131506 -3.45500706
OS 9.22131506 -3.83500122
OS 9.10343366 -3.83500122
OS 9.10343366 -2.87530794
OS 9.22131506 -2.87530794
OS 9.22131506 -3.21924426
OE
OB 11.86879262 -2.86005016 I
OS 11.88127418 -2.861437
OS 11.89652942 -2.86282384
OS 11.91178466 -2.86421068
OS 11.92981358 -2.8683712
OS 11.96725826 -2.87669224
OS 12.00886346 -2.8891738
OS 12.02966606 -2.89749484
OS 12.04908182 -2.90720272
OS 12.06849758 -2.91968428
OS 12.08791334 -2.93216584
OS 12.08930018 -2.93355268
OS 12.09207386 -2.93493952
OS 12.09762122 -2.93910004
OS 12.10455542 -2.94603424
OS 12.11148962 -2.95296844
OS 12.1211975 -2.96267632
OS 12.13090538 -2.97377104
OS 12.1420001 -2.98486576
OS 12.15309482 -2.99873416
OS 12.16418954 -3.01537624
OS 12.1766711 -3.03201832
OS 12.18776582 -3.05004724
OS 12.1974737 -3.07084984
OS 12.20856842 -3.09165244
OS 12.21688946 -3.11384188
OS 12.2252105 -3.138805
OS 12.1003949 -3.16792864
OS 12.1003949 -3.1665418
OS 12.09900806 -3.16376812
OS 12.09623438 -3.15822076
OS 12.0934607 -3.15128656
OS 12.09068702 -3.14296552
OS 12.0865265 -3.1318708
OS 12.07543178 -3.10968136
OS 12.06156338 -3.08471824
OS 12.0449213 -3.05975512
OS 12.0241187 -3.03617884
OS 12.00192926 -3.01537624
OS 11.99915558 -3.01260256
OS 11.99083454 -3.0070552
OS 11.97696614 -3.000121
OS 11.95893722 -2.99041312
OS 11.93536094 -2.98209208
OS 11.90901098 -2.97377104
OS 11.87711366 -2.96822368
OS 11.84244266 -2.96683684
OS 11.83134794 -2.96683684
OS 11.82441374 -2.96822368
OS 11.81470586 -2.96822368
OS 11.80361114 -2.96961052
OS 11.77726118 -2.97377104
OS 11.74813754 -2.9793184
OS 11.71762706 -2.98902628
OS 11.68572974 -3.00289468
OS 11.6566061 -3.0209236
OS 11.65521926 -3.0209236
OS 11.65383242 -3.02369728
OS 11.64412454 -3.03063148
OS 11.63164298 -3.0417262
OS 11.61638774 -3.05836828
OS 11.59835882 -3.07917088
OS 11.58171674 -3.10274716
OS 11.5664615 -3.1318708
OS 11.5525931 -3.16376812
OS 11.5525931 -3.16515496
OS 11.55120626 -3.16792864
OS 11.54981942 -3.17208916
OS 11.54843258 -3.17902336
OS 11.5456589 -3.1873444
OS 11.54288522 -3.19705228
OS 11.5387247 -3.22062856
OS 11.53317734 -3.24836536
OS 11.52762998 -3.27887584
OS 11.5248563 -3.31216
OS 11.52346946 -3.34821784
OS 11.52346946 -3.34960468
OS 11.52346946 -3.3537652
OS 11.52346946 -3.3606994
OS 11.52346946 -3.36902044
OS 11.5248563 -3.37872832
OS 11.5248563 -3.39120988
OS 11.52624314 -3.40507828
OS 11.52762998 -3.42033352
OS 11.5317905 -3.45361768
OS 11.5387247 -3.48967552
OS 11.54704574 -3.52573336
OS 11.55814046 -3.5617912
OS 11.55814046 -3.56317804
OS 11.5595273 -3.56595172
OS 11.56230098 -3.57011224
OS 11.56507466 -3.57704644
OS 11.5733957 -3.59368852
OS 11.58587726 -3.61310428
OS 11.6011325 -3.63529372
OS 11.62054826 -3.65887
OS 11.6427377 -3.6796726
OS 11.66908766 -3.69908836
OS 11.6704745 -3.69908836
OS 11.67324818 -3.7004752
OS 11.6774087 -3.70324888
OS 11.68295606 -3.70602256
OS 11.68989026 -3.70879624
OS 11.6982113 -3.71295676
OS 11.71762706 -3.7212778
OS 11.74259018 -3.72959884
OS 11.77032698 -3.73653304
OS 11.80083746 -3.7420804
OS 11.83273478 -3.74346724
OS 11.84244266 -3.74346724
OS 11.8507637 -3.7420804
OS 11.86047158 -3.7420804
OS 11.87017946 -3.74069356
OS 11.89514258 -3.7351462
OS 11.92426622 -3.728212
OS 11.95338986 -3.71711728
OS 11.98390034 -3.70186204
OS 11.99915558 -3.693541
OS 12.01302398 -3.68244628
OS 12.01441082 -3.68105944
OS 12.01579766 -3.6796726
OS 12.01995818 -3.67551208
OS 12.02550554 -3.67135156
OS 12.0310529 -3.66441736
OS 12.0379871 -3.65609632
OS 12.04630814 -3.64777528
OS 12.05324234 -3.63668056
OS 12.06156338 -3.624199
OS 12.07127126 -3.6103306
OS 12.0795923 -3.5964622
OS 12.08791334 -3.57982012
OS 12.09484754 -3.5617912
OS 12.10178174 -3.54237544
OS 12.10871594 -3.52157284
OS 12.1142633 -3.4993834
OS 12.24185258 -3.53128072
OS 12.24185258 -3.53266756
OS 12.24046574 -3.53821492
OS 12.23769206 -3.54653596
OS 12.23353154 -3.55763068
OS 12.22937102 -3.57011224
OS 12.22382366 -3.58536748
OS 12.21688946 -3.60200956
OS 12.20856842 -3.62003848
OS 12.18915266 -3.65887
OS 12.16418954 -3.69770152
OS 12.1489343 -3.71711728
OS 12.13367906 -3.73653304
OS 12.11703698 -3.75317512
OS 12.09762122 -3.7698172
OS 12.09623438 -3.77120404
OS 12.0934607 -3.77397772
OS 12.0865265 -3.7767514
OS 12.0795923 -3.78229876
OS 12.06849758 -3.78923296
OS 12.05740286 -3.79616716
OS 12.04214762 -3.80310136
OS 12.02689238 -3.81003556
OS 12.00886346 -3.8183566
OS 11.9894477 -3.8252908
OS 11.9686451 -3.832225
OS 11.94645566 -3.8391592
OS 11.92287938 -3.84470656
OS 11.89791626 -3.84748024
OS 11.8715663 -3.85025392
OS 11.8438295 -3.85164076
OS 11.82857426 -3.85164076
OS 11.81747954 -3.85025392
OS 11.80499798 -3.85025392
OS 11.78974274 -3.84886708
OS 11.77310066 -3.8460934
OS 11.7536849 -3.84331972
OS 11.71346654 -3.83638552
OS 11.67186134 -3.8252908
OS 11.63025614 -3.81003556
OS 11.61084038 -3.80032768
OS 11.59142462 -3.78923296
OS 11.59003778 -3.78784612
OS 11.5872641 -3.78645928
OS 11.58171674 -3.78229876
OS 11.57616938 -3.7767514
OS 11.56784834 -3.77120404
OS 11.55814046 -3.762883
OS 11.54704574 -3.75317512
OS 11.53595102 -3.7420804
OS 11.5248563 -3.72959884
OS 11.51237474 -3.71711728
OS 11.48741162 -3.68521996
OS 11.46383534 -3.64777528
OS 11.44303274 -3.60617008
OS 11.44303274 -3.60478324
OS 11.44025906 -3.60062272
OS 11.43887222 -3.59368852
OS 11.4347117 -3.58536748
OS 11.43193802 -3.57427276
OS 11.4277775 -3.56040436
OS 11.42223014 -3.54514912
OS 11.41806962 -3.52850704
OS 11.4139091 -3.51047812
OS 11.40836174 -3.48967552
OS 11.40142754 -3.44668348
OS 11.39588018 -3.39814408
OS 11.3931065 -3.34821784
OS 11.3931065 -3.346831
OS 11.3931065 -3.34128364
OS 11.3931065 -3.3329626
OS 11.39449334 -3.32325472
OS 11.39449334 -3.30938632
OS 11.39588018 -3.29551792
OS 11.39726702 -3.277489
OS 11.4000407 -3.25946008
OS 11.4069749 -3.21924172
OS 11.41668278 -3.17486284
OS 11.43055118 -3.13048396
OS 11.44996694 -3.08749192
OS 11.45135378 -3.08610508
OS 11.45274062 -3.08194456
OS 11.4555143 -3.0763972
OS 11.46106166 -3.069463
OS 11.46660902 -3.05975512
OS 11.47354322 -3.0486604
OS 11.49157214 -3.02369728
OS 11.51514842 -2.99596048
OS 11.54288522 -2.96822368
OS 11.57478254 -2.94048688
OS 11.61222722 -2.9169106
OS 11.61361406 -2.91552376
OS 11.61777458 -2.91413692
OS 11.62332194 -2.91136324
OS 11.63025614 -2.90720272
OS 11.64135086 -2.9030422
OS 11.65244558 -2.89888168
OS 11.66631398 -2.89333432
OS 11.68156922 -2.88778696
OS 11.6982113 -2.8822396
OS 11.71624022 -2.87669224
OS 11.75507174 -2.8683712
OS 11.79945062 -2.861437
OS 11.84521634 -2.85866332
OS 11.85908474 -2.85866332
OS 11.86879262 -2.86005016
OE
OB 15.11538506 -3.83499868 I
OS 14.98224842 -3.83499868
OS 14.6105753 -2.8753054
OS 14.7492593 -2.8753054
OS 14.9988905 -3.57288592
OS 14.9988905 -3.57427276
OS 15.00027734 -3.57704644
OS 15.00166418 -3.58120696
OS 15.00443786 -3.58675432
OS 15.0058247 -3.59507536
OS 15.00859838 -3.6033964
OS 15.01553258 -3.624199
OS 15.02385362 -3.64777528
OS 15.03217466 -3.67412524
OS 15.04881674 -3.72959884
OS 15.04881674 -3.728212
OS 15.05020358 -3.72543832
OS 15.05159042 -3.7212778
OS 15.05297726 -3.71573044
OS 15.05713778 -3.7004752
OS 15.06407198 -3.6796726
OS 15.07100618 -3.65609632
OS 15.07932722 -3.62974636
OS 15.0890351 -3.60200956
OS 15.10012982 -3.57288592
OS 15.36085574 -2.8753054
OS 15.48983186 -2.8753054
OS 15.11538506 -3.83499868
OE
OB 16.00018898 -3.83499868 I
OS 15.88230758 -3.83499868
OS 15.88230758 -3.08471824
OS 15.88092074 -3.08610508
OS 15.87398654 -3.09165244
OS 15.8656655 -3.09997348
OS 15.8517971 -3.10968136
OS 15.83654186 -3.12216292
OS 15.8171261 -3.13603132
OS 15.79493666 -3.15128656
OS 15.76997354 -3.1665418
OS 15.7685867 -3.1665418
OS 15.76719986 -3.16792864
OS 15.75887882 -3.173476
OS 15.74501042 -3.1804102
OS 15.72836834 -3.18873124
OS 15.70895258 -3.19843912
OS 15.68814998 -3.208147
OS 15.66734738 -3.21785488
OS 15.64654478 -3.22617592
OS 15.64654478 -3.11245504
OS 15.64793162 -3.11245504
OS 15.6507053 -3.10968136
OS 15.65625266 -3.10829452
OS 15.66318686 -3.104134
OS 15.6715079 -3.09997348
OS 15.68121578 -3.09442612
OS 15.70479206 -3.08055772
OS 15.73252886 -3.06530248
OS 15.76026566 -3.04588672
OS 15.7893893 -3.02369728
OS 15.81851294 -3.000121
OS 15.81989978 -2.99873416
OS 15.82128662 -2.99734732
OS 15.82544714 -2.9931868
OS 15.8309945 -2.98902628
OS 15.84347606 -2.97515788
OS 15.86011814 -2.9585158
OS 15.87676022 -2.93910004
OS 15.89478914 -2.9169106
OS 15.91004438 -2.89472116
OS 15.92391278 -2.87114488
OS 16.00018898 -2.87114488
OS 16.00018898 -3.83499868
OE
OB 14.13488918 -3.83499868 I
OS 14.02532882 -3.83499868
OS 14.02532882 -3.74762776
OS 14.02394198 -3.7490146
OS 14.02255514 -3.75178828
OS 14.01839462 -3.75733564
OS 14.01284726 -3.76426984
OS 14.00591306 -3.77120404
OS 13.99759202 -3.77952508
OS 13.98788414 -3.78923296
OS 13.97540258 -3.79894084
OS 13.96292102 -3.80864872
OS 13.94905262 -3.8183566
OS 13.93241054 -3.82667764
OS 13.91438162 -3.83361184
OS 13.8963527 -3.84054604
OS 13.8755501 -3.8460934
OS 13.85336066 -3.84886708
OS 13.82978438 -3.85025392
OS 13.82146334 -3.85025392
OS 13.81591598 -3.84886708
OS 13.7992739 -3.84748024
OS 13.77985814 -3.84470656
OS 13.75628186 -3.8391592
OS 13.7299319 -3.83083816
OS 13.70358194 -3.81974344
OS 13.67723198 -3.8044882
OS 13.67584514 -3.8044882
OS 13.6744583 -3.80171452
OS 13.66613726 -3.79616716
OS 13.6536557 -3.78507244
OS 13.63840046 -3.77120404
OS 13.62037154 -3.75317512
OS 13.60234262 -3.73098568
OS 13.5843137 -3.70602256
OS 13.56905846 -3.67689892
OS 13.56905846 -3.67551208
OS 13.56767162 -3.6727384
OS 13.56628478 -3.66857788
OS 13.5635111 -3.66303052
OS 13.56073742 -3.65470948
OS 13.5565769 -3.6450016
OS 13.55380322 -3.63529372
OS 13.55102954 -3.62281216
OS 13.54409534 -3.59507536
OS 13.53716114 -3.56317804
OS 13.53300062 -3.5271202
OS 13.53161378 -3.48828868
OS 13.53161378 -3.48690184
OS 13.53161378 -3.48412816
OS 13.53161378 -3.4785808
OS 13.53161378 -3.47025976
OS 13.53300062 -3.46193872
OS 13.53300062 -3.450844
OS 13.5357743 -3.42588088
OS 13.53993482 -3.39675724
OS 13.54686902 -3.36485992
OS 13.55519006 -3.33157576
OS 13.56628478 -3.29967844
OS 13.56628478 -3.2982916
OS 13.56767162 -3.29551792
OS 13.5704453 -3.2913574
OS 13.57321898 -3.28581004
OS 13.58154002 -3.2705548
OS 13.59263474 -3.25113904
OS 13.60650314 -3.23033644
OS 13.62453206 -3.20953384
OS 13.64533466 -3.1873444
OS 13.67029778 -3.16931548
OS 13.67168462 -3.16931548
OS 13.67307146 -3.16792864
OS 13.67723198 -3.16515496
OS 13.68277934 -3.16238128
OS 13.69664774 -3.15544708
OS 13.7160635 -3.1457392
OS 13.73825294 -3.13741816
OS 13.7646029 -3.13048396
OS 13.79372654 -3.1249366
OS 13.82423702 -3.12354976
OS 13.83533174 -3.12354976
OS 13.84642646 -3.1249366
OS 13.8616817 -3.12632344
OS 13.87971062 -3.13048396
OS 13.89912638 -3.13464448
OS 13.91854214 -3.14157868
OS 13.93657106 -3.15128656
OS 13.93934474 -3.1526734
OS 13.9448921 -3.15544708
OS 13.95321314 -3.16238128
OS 13.96430786 -3.16931548
OS 13.97817626 -3.17902336
OS 13.99065782 -3.19150492
OS 14.00452622 -3.20398648
OS 14.01700778 -3.21924172
OS 14.01700778 -2.8753054
OS 14.13488918 -2.8753054
OS 14.13488918 -3.83499868
OE
OB 12.70783082 -3.1249366 I
OS 12.72863342 -3.12632344
OS 12.7522097 -3.12909712
OS 12.77578598 -3.13325764
OS 12.79936226 -3.138805
OS 12.8215517 -3.1457392
OS 12.82432538 -3.14712604
OS 12.83125958 -3.14989972
OS 12.84096746 -3.15406024
OS 12.85344902 -3.1596076
OS 12.86731742 -3.16792864
OS 12.88118582 -3.17624968
OS 12.89366738 -3.1873444
OS 12.9047621 -3.19843912
OS 12.90614894 -3.19982596
OS 12.90892262 -3.20398648
OS 12.91308314 -3.21092068
OS 12.9186305 -3.21924172
OS 12.9255647 -3.23172328
OS 12.93111206 -3.24420484
OS 12.93665942 -3.25946008
OS 12.94081994 -3.277489
OS 12.94081994 -3.27887584
OS 12.94220678 -3.28303636
OS 12.94359362 -3.2913574
OS 12.94498046 -3.30245212
OS 12.94498046 -3.31770736
OS 12.9463673 -3.33573628
OS 12.94775414 -3.35931256
OS 12.94775414 -3.38566252
OS 12.94775414 -3.54376228
OS 12.94775414 -3.54514912
OS 12.94775414 -3.55069648
OS 12.94775414 -3.55901752
OS 12.94775414 -3.57011224
OS 12.94775414 -3.5825938
OS 12.94775414 -3.59784904
OS 12.94914098 -3.6311332
OS 12.94914098 -3.6658042
OS 12.95052782 -3.7004752
OS 12.95191466 -3.71573044
OS 12.95191466 -3.72959884
OS 12.9533015 -3.7420804
OS 12.95468834 -3.75178828
OS 12.95468834 -3.75317512
OS 12.95607518 -3.75872248
OS 12.95746202 -3.76704352
OS 12.96162254 -3.77813824
OS 12.96439622 -3.7906198
OS 12.96994358 -3.8044882
OS 12.97687778 -3.81974344
OS 12.98381198 -3.83499868
OS 12.86038322 -3.83499868
OS 12.85899638 -3.83361184
OS 12.85760954 -3.82806448
OS 12.85483586 -3.82113028
OS 12.85067534 -3.81003556
OS 12.84651482 -3.797554
OS 12.84374114 -3.78229876
OS 12.84096746 -3.76565668
OS 12.83819378 -3.74762776
OS 12.83680694 -3.74762776
OS 12.8354201 -3.75040144
OS 12.82709906 -3.75733564
OS 12.8146175 -3.76704352
OS 12.79797542 -3.77952508
OS 12.77717282 -3.79200664
OS 12.75637022 -3.80587504
OS 12.73418078 -3.8183566
OS 12.7106045 -3.82806448
OS 12.70783082 -3.82945132
OS 12.69950978 -3.83083816
OS 12.68702822 -3.83499868
OS 12.67177298 -3.8391592
OS 12.65235722 -3.84331972
OS 12.63016778 -3.8460934
OS 12.60520466 -3.84886708
OS 12.58024154 -3.85025392
OS 12.56914682 -3.85025392
OS 12.56082578 -3.84886708
OS 12.5511179 -3.84886708
OS 12.54002318 -3.84748024
OS 12.51506006 -3.84331972
OS 12.48732326 -3.83638552
OS 12.45681278 -3.82667764
OS 12.42907598 -3.81280924
OS 12.40411286 -3.79478032
OS 12.40133918 -3.79200664
OS 12.39440498 -3.78507244
OS 12.3846971 -3.77259088
OS 12.37360238 -3.7559488
OS 12.36250766 -3.7351462
OS 12.35279978 -3.71156992
OS 12.34586558 -3.68244628
OS 12.34447874 -3.66857788
OS 12.3430919 -3.6519358
OS 12.3430919 -3.64916212
OS 12.3430919 -3.64361476
OS 12.34447874 -3.63390688
OS 12.34586558 -3.62142532
OS 12.34863926 -3.60617008
OS 12.35279978 -3.59091484
OS 12.35834714 -3.57427276
OS 12.36528134 -3.55901752
OS 12.36666818 -3.55763068
OS 12.36944186 -3.55208332
OS 12.37498922 -3.54376228
OS 12.38192342 -3.5340544
OS 12.39024446 -3.52295968
OS 12.40133918 -3.51186496
OS 12.4124339 -3.50077024
OS 12.4263023 -3.49106236
OS 12.42768914 -3.48967552
OS 12.4332365 -3.48690184
OS 12.4401707 -3.48135448
OS 12.45126542 -3.47580712
OS 12.46374698 -3.47025976
OS 12.47900222 -3.46332556
OS 12.49425746 -3.4577782
OS 12.51228638 -3.45223084
OS 12.51367322 -3.45223084
OS 12.51922058 -3.450844
OS 12.52754162 -3.44807032
OS 12.53863634 -3.44668348
OS 12.55250474 -3.4439098
OS 12.57053366 -3.44113612
OS 12.59133626 -3.4369756
OS 12.61629938 -3.43420192
OS 12.61768622 -3.43420192
OS 12.62323358 -3.43281508
OS 12.63016778 -3.43281508
OS 12.63987566 -3.43142824
OS 12.65097038 -3.4300414
OS 12.66483878 -3.42726772
OS 12.68009402 -3.42588088
OS 12.6967361 -3.4231072
OS 12.73002026 -3.416173
OS 12.7660781 -3.4092388
OS 12.79797542 -3.40091776
OS 12.81323066 -3.39675724
OS 12.82709906 -3.39259672
OS 12.82709906 -3.39120988
OS 12.82709906 -3.3884362
OS 12.8284859 -3.38011516
OS 12.8284859 -3.37040728
OS 12.8284859 -3.36485992
OS 12.8284859 -3.36208624
OS 12.8284859 -3.3606994
OS 12.8284859 -3.35931256
OS 12.8284859 -3.35099152
OS 12.82709906 -3.33712312
OS 12.82432538 -3.32186788
OS 12.82016486 -3.3052258
OS 12.81323066 -3.28858372
OS 12.80490962 -3.27332848
OS 12.7938149 -3.26084692
OS 12.79242806 -3.25946008
OS 12.78549386 -3.25391272
OS 12.77439914 -3.24836536
OS 12.76053074 -3.24004432
OS 12.74111498 -3.23311012
OS 12.71892554 -3.22617592
OS 12.69118874 -3.2220154
OS 12.65929142 -3.22062856
OS 12.64542302 -3.22062856
OS 12.63155462 -3.2220154
OS 12.61213886 -3.22478908
OS 12.5927231 -3.22756276
OS 12.5719205 -3.23311012
OS 12.55250474 -3.24004432
OS 12.53586266 -3.2497522
OS 12.53447582 -3.25113904
OS 12.52892846 -3.25529956
OS 12.52199426 -3.26223376
OS 12.51367322 -3.27332848
OS 12.50535218 -3.28719688
OS 12.4956443 -3.3052258
OS 12.48732326 -3.32741524
OS 12.47900222 -3.35237836
OS 12.3638945 -3.33712312
OS 12.3638945 -3.33573628
OS 12.36528134 -3.33434944
OS 12.36528134 -3.33018892
OS 12.36666818 -3.32464156
OS 12.3708287 -3.31216
OS 12.37637606 -3.29413108
OS 12.38331026 -3.27610216
OS 12.3916313 -3.2566864
OS 12.40272602 -3.23727064
OS 12.41520758 -3.21924172
OS 12.41659442 -3.21785488
OS 12.42214178 -3.21230752
OS 12.43046282 -3.20398648
OS 12.44155754 -3.19289176
OS 12.45681278 -3.18179704
OS 12.4748417 -3.17070232
OS 12.4956443 -3.15822076
OS 12.51922058 -3.14851288
OS 12.52060742 -3.14851288
OS 12.52199426 -3.14712604
OS 12.52615478 -3.1457392
OS 12.53170214 -3.14435236
OS 12.54557054 -3.14019184
OS 12.5649863 -3.13603132
OS 12.58717574 -3.1318708
OS 12.61491254 -3.12771028
OS 12.64403618 -3.1249366
OS 12.67732034 -3.12354976
OS 12.69257558 -3.12354976
OS 12.70783082 -3.1249366
OE
OB 13.40679818 -3.1249366 I
OS 13.42205342 -3.12771028
OS 13.44008234 -3.13325764
OS 13.4594981 -3.14019184
OS 13.48168754 -3.14989972
OS 13.50526382 -3.16238128
OS 13.46227178 -3.2705548
OS 13.46088494 -3.26916796
OS 13.45533758 -3.26639428
OS 13.44701654 -3.26223376
OS 13.43592182 -3.25807324
OS 13.42344026 -3.25391272
OS 13.40818502 -3.2497522
OS 13.39292978 -3.24697852
OS 13.37767454 -3.24559168
OS 13.37074034 -3.24559168
OS 13.36380614 -3.24697852
OS 13.35409826 -3.24836536
OS 13.34439038 -3.25113904
OS 13.33190882 -3.25529956
OS 13.31942726 -3.26084692
OS 13.30833254 -3.26916796
OS 13.3069457 -3.2705548
OS 13.30278518 -3.27332848
OS 13.29862466 -3.27887584
OS 13.29169046 -3.28581004
OS 13.28475626 -3.29551792
OS 13.27782206 -3.30661264
OS 13.27088786 -3.3190942
OS 13.2653405 -3.33434944
OS 13.26395366 -3.33712312
OS 13.26256682 -3.34544416
OS 13.25979314 -3.35792572
OS 13.25563262 -3.3745678
OS 13.2514721 -3.3953704
OS 13.24869842 -3.41894668
OS 13.24731158 -3.4439098
OS 13.24592474 -3.4716466
OS 13.24592474 -3.83499868
OS 13.12804334 -3.83499868
OS 13.12804334 -3.138805
OS 13.23483002 -3.138805
OS 13.23483002 -3.24420484
OS 13.23621686 -3.242818
OS 13.24176422 -3.23311012
OS 13.24869842 -3.22062856
OS 13.25979314 -3.20537332
OS 13.27088786 -3.19011808
OS 13.28336942 -3.173476
OS 13.29585098 -3.1596076
OS 13.30833254 -3.14851288
OS 13.30971938 -3.14712604
OS 13.3138799 -3.14435236
OS 13.32220094 -3.14019184
OS 13.33052198 -3.13603132
OS 13.3416167 -3.1318708
OS 13.3554851 -3.12771028
OS 13.3693535 -3.1249366
OS 13.38460874 -3.12354976
OS 13.39431662 -3.12354976
OS 13.40679818 -3.1249366
OE
OB 5.33538938 -3.00012354 I
OS 4.9512347 -3.00012354
OS 4.89992162 -3.25946262
OS 4.90130846 -3.25807578
OS 4.90408214 -3.25668894
OS 4.90824266 -3.25391526
OS 4.91517686 -3.24975474
OS 4.9234979 -3.24559422
OS 4.93320578 -3.24004686
OS 4.95539522 -3.22895214
OS 4.98313202 -3.21785742
OS 5.0136425 -3.20814954
OS 5.04692666 -3.20121534
OS 5.06356874 -3.19844166
OS 5.09407922 -3.19844166
OS 5.10240026 -3.1998285
OS 5.11349498 -3.20121534
OS 5.12597654 -3.20260218
OS 5.13984494 -3.20537586
OS 5.15510018 -3.20953638
OS 5.18838434 -3.21924426
OS 5.20641326 -3.22617846
OS 5.22444218 -3.23588634
OS 5.2424711 -3.24559422
OS 5.26050002 -3.25668894
OS 5.2771421 -3.27055734
OS 5.29378418 -3.28581258
OS 5.29517102 -3.28719942
OS 5.2979447 -3.2899731
OS 5.30210522 -3.29413362
OS 5.30765258 -3.30106782
OS 5.31458678 -3.3107757
OS 5.32152098 -3.32048358
OS 5.32984202 -3.33296514
OS 5.33816306 -3.34683354
OS 5.34509726 -3.36208878
OS 5.3534183 -3.37873086
OS 5.3603525 -3.39814662
OS 5.3672867 -3.41756238
OS 5.37283406 -3.43836498
OS 5.37699458 -3.46194126
OS 5.37976826 -3.48551754
OS 5.3811551 -3.51048066
OS 5.3811551 -3.5118675
OS 5.3811551 -3.51602802
OS 5.3811551 -3.52296222
OS 5.37976826 -3.5326701
OS 5.37838142 -3.54376482
OS 5.37699458 -3.55624638
OS 5.3742209 -3.57150162
OS 5.37144722 -3.58675686
OS 5.36312618 -3.6228147
OS 5.34925778 -3.66025938
OS 5.34093674 -3.67967514
OS 5.32984202 -3.69770406
OS 5.3187473 -3.71711982
OS 5.3048789 -3.73514874
OS 5.30349206 -3.73653558
OS 5.30071838 -3.7406961
OS 5.29517102 -3.74624346
OS 5.28823682 -3.75317766
OS 5.27852894 -3.7614987
OS 5.26743422 -3.77259342
OS 5.25356582 -3.7823013
OS 5.23831058 -3.79339602
OS 5.2216685 -3.80449074
OS 5.20225274 -3.81419862
OS 5.18145014 -3.8239065
OS 5.1592607 -3.83361438
OS 5.13568442 -3.84054858
OS 5.10933446 -3.84609594
OS 5.08159766 -3.85025646
OS 5.05247402 -3.8516433
OS 5.03999246 -3.8516433
OS 5.03028458 -3.85025646
OS 5.01918986 -3.84886962
OS 5.0067083 -3.84748278
OS 4.99145306 -3.84609594
OS 4.97619782 -3.84193542
OS 4.94152682 -3.83361438
OS 4.90685582 -3.82113282
OS 4.8888269 -3.81281178
OS 4.87079798 -3.8031039
OS 4.8541559 -3.79200918
OS 4.83751382 -3.77952762
OS 4.83612698 -3.77814078
OS 4.8333533 -3.77675394
OS 4.83057962 -3.77120658
OS 4.82503226 -3.76565922
OS 4.81809806 -3.75872502
OS 4.81116386 -3.75040398
OS 4.80284282 -3.73930926
OS 4.79590862 -3.7268277
OS 4.78758758 -3.71434614
OS 4.77926654 -3.6990909
OS 4.7640113 -3.66580674
OS 4.75152974 -3.62697522
OS 4.74736922 -3.60617262
OS 4.74459554 -3.58398318
OS 4.8680243 -3.5742753
OS 4.8680243 -3.57566214
OS 4.8680243 -3.57843582
OS 4.86941114 -3.58259634
OS 4.87079798 -3.58953054
OS 4.8749585 -3.60478578
OS 4.88050586 -3.62558838
OS 4.8888269 -3.64639098
OS 4.89992162 -3.66996726
OS 4.91379002 -3.69076986
OS 4.9304321 -3.71018562
OS 4.93320578 -3.71157246
OS 4.93875314 -3.71711982
OS 4.94984786 -3.72405402
OS 4.9651031 -3.73237506
OS 4.98174518 -3.7406961
OS 5.00254778 -3.7476303
OS 5.02612406 -3.75317766
OS 5.05247402 -3.7545645
OS 5.06079506 -3.7545645
OS 5.06634242 -3.75317766
OS 5.0829845 -3.75179082
OS 5.10240026 -3.74624346
OS 5.12597654 -3.73930926
OS 5.14955282 -3.72821454
OS 5.17451594 -3.71157246
OS 5.18561066 -3.70186458
OS 5.19670538 -3.69076986
OS 5.19809222 -3.68938302
OS 5.19947906 -3.68799618
OS 5.20225274 -3.68383566
OS 5.20641326 -3.67967514
OS 5.21612114 -3.6644199
OS 5.22721586 -3.64500414
OS 5.23692374 -3.62142786
OS 5.24663162 -3.59230422
OS 5.25356582 -3.55763322
OS 5.2563395 -3.5396043
OS 5.2563395 -3.52018854
OS 5.2563395 -3.5188017
OS 5.2563395 -3.51602802
OS 5.2563395 -3.51048066
OS 5.25495266 -3.50354646
OS 5.25495266 -3.49522542
OS 5.25356582 -3.48551754
OS 5.2494053 -3.4633281
OS 5.2424711 -3.43697814
OS 5.23276322 -3.41062818
OS 5.21889482 -3.38566506
OS 5.19947906 -3.36208878
OS 5.19947906 -3.36070194
OS 5.19670538 -3.3593151
OS 5.18977118 -3.3523809
OS 5.17728962 -3.34267302
OS 5.16064754 -3.3315783
OS 5.1384581 -3.32187042
OS 5.11349498 -3.31216254
OS 5.08437134 -3.30522834
OS 5.06772926 -3.30245466
OS 5.0413793 -3.30245466
OS 5.03028458 -3.3038415
OS 5.01641618 -3.30522834
OS 4.9997741 -3.30938886
OS 4.98313202 -3.31354938
OS 4.9651031 -3.32048358
OS 4.94707418 -3.32880462
OS 4.94568734 -3.33019146
OS 4.94013998 -3.33296514
OS 4.93181894 -3.33989934
OS 4.92072422 -3.34683354
OS 4.9096295 -3.35654142
OS 4.89853478 -3.36902298
OS 4.88605322 -3.38150454
OS 4.87634534 -3.39675978
OS 4.76539814 -3.38150454
OS 4.85831642 -2.8877895
OS 5.33538938 -2.8877895
OS 5.33538938 -3.00012354
OE
OB 6.30617738 -2.87669478 I
OS 6.33391418 -2.87808162
OS 6.36165098 -2.8808553
OS 6.38938778 -2.88501582
OS 6.41296406 -2.88917634
OS 6.4143509 -2.88917634
OS 6.41712458 -2.89056318
OS 6.4212851 -2.89056318
OS 6.42683246 -2.89333686
OS 6.4420877 -2.89749738
OS 6.46150346 -2.90443158
OS 6.4836929 -2.91413946
OS 6.50726918 -2.92662102
OS 6.53084546 -2.94048942
OS 6.5530349 -2.95851834
OS 6.55442174 -2.95990518
OS 6.55580858 -2.96129202
OS 6.5599691 -2.96545254
OS 6.56551646 -2.96961306
OS 6.57938486 -2.98348146
OS 6.59602694 -3.00289722
OS 6.61405586 -3.0264735
OS 6.63347162 -3.0542103
OS 6.65150054 -3.08610762
OS 6.66675578 -3.12216546
OS 6.66675578 -3.1235523
OS 6.66814262 -3.12632598
OS 6.6709163 -3.13187334
OS 6.67230314 -3.14019438
OS 6.67646366 -3.14990226
OS 6.67923734 -3.16099698
OS 6.68201102 -3.17347854
OS 6.68617154 -3.18873378
OS 6.69033206 -3.20398902
OS 6.69310574 -3.22201794
OS 6.70003994 -3.26084946
OS 6.70420046 -3.3038415
OS 6.7055873 -3.35099406
OS 6.7055873 -3.3523809
OS 6.7055873 -3.35515458
OS 6.7055873 -3.36208878
OS 6.7055873 -3.36902298
OS 6.70420046 -3.37873086
OS 6.70420046 -3.38982558
OS 6.70281362 -3.41617554
OS 6.6986531 -3.44668602
OS 6.69449258 -3.47858334
OS 6.68755838 -3.5118675
OS 6.67923734 -3.54515166
OS 6.67923734 -3.5465385
OS 6.6778505 -3.54931218
OS 6.67646366 -3.5534727
OS 6.67507682 -3.55902006
OS 6.66952946 -3.5742753
OS 6.66120842 -3.59369106
OS 6.65288738 -3.6158805
OS 6.64179266 -3.63806994
OS 6.62792426 -3.66164622
OS 6.61405586 -3.68383566
OS 6.61266902 -3.68660934
OS 6.60712166 -3.69354354
OS 6.59880062 -3.70325142
OS 6.5877059 -3.71573298
OS 6.57522434 -3.72960138
OS 6.5599691 -3.74346978
OS 6.54471386 -3.75872502
OS 6.52668494 -3.77120658
OS 6.52391126 -3.77259342
OS 6.5183639 -3.77675394
OS 6.50865602 -3.7823013
OS 6.49478762 -3.7892355
OS 6.47814554 -3.79755654
OS 6.45872978 -3.80449074
OS 6.43654034 -3.81281178
OS 6.41157722 -3.81974598
OS 6.40880354 -3.81974598
OS 6.40464302 -3.82113282
OS 6.4004825 -3.82251966
OS 6.3866141 -3.8239065
OS 6.36719834 -3.82668018
OS 6.3450089 -3.82945386
OS 6.31865894 -3.83222754
OS 6.2895353 -3.83361438
OS 6.25763798 -3.83500122
OS 5.91231482 -3.83500122
OS 5.91231482 -2.87530794
OS 6.28121426 -2.87530794
OS 6.30617738 -2.87669478
OE
OB 4.4935775 -3.49661226 I
OS 4.62394046 -3.49661226
OS 4.62394046 -3.60478578
OS 4.4935775 -3.60478578
OS 4.4935775 -3.83500122
OS 4.3756961 -3.83500122
OS 4.3756961 -3.60478578
OS 3.95825726 -3.60478578
OS 3.95825726 -3.49661226
OS 4.39788554 -2.87530794
OS 4.4935775 -2.87530794
OS 4.4935775 -3.49661226
OE
OB 2.61579614 -2.8600527 I
OS 2.62550402 -2.8600527
OS 2.65185398 -2.86282638
OS 2.68097762 -2.8669869
OS 2.7114881 -2.8739211
OS 2.74477226 -2.88224214
OS 2.77528274 -2.89333686
OS 2.77666958 -2.89333686
OS 2.77944326 -2.8947237
OS 2.78360378 -2.89749738
OS 2.78915114 -2.90027106
OS 2.80301954 -2.90720526
OS 2.82104846 -2.91968682
OS 2.84185106 -2.93355522
OS 2.86265366 -2.95158414
OS 2.88206942 -2.97238674
OS 2.90009834 -2.99596302
OS 2.90009834 -2.99734986
OS 2.90148518 -2.9987367
OS 2.90425886 -3.00289722
OS 2.90703254 -3.00705774
OS 2.91396674 -3.02092614
OS 2.92228778 -3.03895506
OS 2.93199566 -3.0611445
OS 2.93892986 -3.08749446
OS 2.94586406 -3.11523126
OS 2.94863774 -3.14574174
OS 2.82659582 -3.15544962
OS 2.82659582 -3.15406278
OS 2.82659582 -3.1512891
OS 2.82520898 -3.14712858
OS 2.82382214 -3.14019438
OS 2.81966162 -3.12493914
OS 2.81411426 -3.10413654
OS 2.80579322 -3.0819471
OS 2.79331166 -3.05975766
OS 2.77805642 -3.03895506
OS 2.75864066 -3.0195393
OS 2.75586698 -3.01815246
OS 2.74893278 -3.0126051
OS 2.73506438 -3.00428406
OS 2.71703546 -2.99596302
OS 2.69345918 -2.98764198
OS 2.66572238 -2.97932094
OS 2.63105138 -2.97377358
OS 2.59221986 -2.97238674
OS 2.5728041 -2.97238674
OS 2.56448306 -2.97377358
OS 2.55338834 -2.97516042
OS 2.52842522 -2.9779341
OS 2.50068842 -2.98348146
OS 2.47295162 -2.99041566
OS 2.44660166 -3.00151038
OS 2.43550694 -3.00844458
OS 2.42441222 -3.01537878
OS 2.42163854 -3.01676562
OS 2.41609118 -3.02231298
OS 2.40777014 -3.03202086
OS 2.3994491 -3.04311558
OS 2.38974122 -3.05837082
OS 2.38142018 -3.0750129
OS 2.37587282 -3.09442866
OS 2.37309914 -3.1166181
OS 2.37309914 -3.11939178
OS 2.37309914 -3.12493914
OS 2.37448598 -3.13464702
OS 2.37725966 -3.14574174
OS 2.38142018 -3.15961014
OS 2.38835438 -3.17347854
OS 2.39667542 -3.18734694
OS 2.40915698 -3.20121534
OS 2.41054382 -3.20260218
OS 2.41747802 -3.2067627
OS 2.42302538 -3.21092322
OS 2.42857274 -3.2136969
OS 2.43689378 -3.21785742
OS 2.44660166 -3.22340478
OS 2.45908322 -3.2275653
OS 2.47295162 -3.23311266
OS 2.48820686 -3.23866002
OS 2.50623578 -3.24559422
OS 2.52565154 -3.25114158
OS 2.54784098 -3.25807578
OS 2.5728041 -3.26362314
OS 2.6005409 -3.27055734
OS 2.60192774 -3.27055734
OS 2.6074751 -3.27194418
OS 2.61579614 -3.27333102
OS 2.62550402 -3.2761047
OS 2.63798558 -3.27887838
OS 2.65324082 -3.2830389
OS 2.66849606 -3.28719942
OS 2.68513814 -3.29135994
OS 2.72119598 -3.30106782
OS 2.75586698 -3.3107757
OS 2.77250906 -3.31632306
OS 2.7877643 -3.32187042
OS 2.8016327 -3.32603094
OS 2.81272742 -3.3315783
OS 2.81411426 -3.3315783
OS 2.81688794 -3.33296514
OS 2.82104846 -3.33573882
OS 2.82659582 -3.3385125
OS 2.84185106 -3.34683354
OS 2.85987998 -3.35792826
OS 2.88068258 -3.3731835
OS 2.90148518 -3.38982558
OS 2.92090094 -3.40924134
OS 2.93754302 -3.43004394
OS 2.93892986 -3.43281762
OS 2.94447722 -3.43975182
OS 2.95002458 -3.45223338
OS 2.95834562 -3.46887546
OS 2.96527982 -3.48829122
OS 2.97221402 -3.5118675
OS 2.97637454 -3.53821746
OS 2.97776138 -3.56595426
OS 2.97776138 -3.5673411
OS 2.97776138 -3.56872794
OS 2.97776138 -3.57288846
OS 2.97776138 -3.57843582
OS 2.9749877 -3.59369106
OS 2.97221402 -3.61310682
OS 2.96666666 -3.63529626
OS 2.95973246 -3.65887254
OS 2.94863774 -3.68383566
OS 2.9333825 -3.71018562
OS 2.9333825 -3.71157246
OS 2.93199566 -3.7129593
OS 2.92506146 -3.72128034
OS 2.91535358 -3.7337619
OS 2.90148518 -3.7476303
OS 2.88345626 -3.76427238
OS 2.86126682 -3.7823013
OS 2.8363037 -3.79894338
OS 2.80718006 -3.81419862
OS 2.80579322 -3.81419862
OS 2.80301954 -3.81558546
OS 2.79885902 -3.8169723
OS 2.79331166 -3.81974598
OS 2.78499062 -3.82251966
OS 2.77528274 -3.82668018
OS 2.7530933 -3.83222754
OS 2.72674334 -3.83916174
OS 2.69484602 -3.84609594
OS 2.66017502 -3.85025646
OS 2.62273034 -3.8516433
OS 2.6005409 -3.8516433
OS 2.58944618 -3.85025646
OS 2.57696462 -3.85025646
OS 2.56309622 -3.84886962
OS 2.54645414 -3.84748278
OS 2.51178314 -3.84193542
OS 2.4757253 -3.83638806
OS 2.43966746 -3.82668018
OS 2.40499646 -3.81419862
OS 2.40360962 -3.81419862
OS 2.40083594 -3.81281178
OS 2.39667542 -3.8100381
OS 2.39112806 -3.80726442
OS 2.37448598 -3.79894338
OS 2.35507022 -3.78646182
OS 2.33288078 -3.76981974
OS 2.3093045 -3.75040398
OS 2.28711506 -3.7268277
OS 2.26631246 -3.70047774
OS 2.26631246 -3.6990909
OS 2.26353878 -3.69631722
OS 2.26215194 -3.6921567
OS 2.25799142 -3.68660934
OS 2.25521774 -3.67967514
OS 2.25105722 -3.6713541
OS 2.24134934 -3.6505515
OS 2.23164146 -3.62420154
OS 2.22332042 -3.5950779
OS 2.21777306 -3.56179374
OS 2.21499938 -3.52712274
OS 2.33426762 -3.51602802
OS 2.33426762 -3.51741486
OS 2.33426762 -3.5188017
OS 2.33565446 -3.52296222
OS 2.33565446 -3.52850958
OS 2.33842814 -3.54099114
OS 2.34258866 -3.55902006
OS 2.34813602 -3.57704898
OS 2.35368338 -3.59785158
OS 2.36339126 -3.61726734
OS 2.37309914 -3.63529626
OS 2.37448598 -3.6366831
OS 2.3786465 -3.64223046
OS 2.3855807 -3.65193834
OS 2.39667542 -3.66164622
OS 2.41054382 -3.67412778
OS 2.42579906 -3.68660934
OS 2.44660166 -3.6990909
OS 2.4687911 -3.71018562
OS 2.47017794 -3.71018562
OS 2.47156478 -3.71157246
OS 2.4757253 -3.7129593
OS 2.47988582 -3.71434614
OS 2.49375422 -3.71850666
OS 2.51178314 -3.72405402
OS 2.53397258 -3.72960138
OS 2.5589357 -3.7337619
OS 2.5866725 -3.73653558
OS 2.61718298 -3.73792242
OS 2.62966454 -3.73792242
OS 2.64353294 -3.73653558
OS 2.66017502 -3.73514874
OS 2.67959078 -3.73237506
OS 2.70178022 -3.72960138
OS 2.72396966 -3.72405402
OS 2.74477226 -3.71711982
OS 2.74754594 -3.71573298
OS 2.75448014 -3.7129593
OS 2.76418802 -3.70741194
OS 2.77666958 -3.70186458
OS 2.78915114 -3.6921567
OS 2.80301954 -3.68244882
OS 2.81688794 -3.6713541
OS 2.82798266 -3.6574857
OS 2.8293695 -3.65609886
OS 2.83214318 -3.6505515
OS 2.8363037 -3.6436173
OS 2.84185106 -3.63252258
OS 2.84739842 -3.62142786
OS 2.85155894 -3.60755946
OS 2.85433262 -3.59230422
OS 2.85571946 -3.57566214
OS 2.85571946 -3.5742753
OS 2.85571946 -3.5673411
OS 2.85433262 -3.55902006
OS 2.85294578 -3.54792534
OS 2.84878526 -3.53683062
OS 2.84462474 -3.52296222
OS 2.83769054 -3.50909382
OS 2.82798266 -3.49661226
OS 2.82659582 -3.49522542
OS 2.8224353 -3.4910649
OS 2.81688794 -3.48551754
OS 2.80718006 -3.4771965
OS 2.79608534 -3.46887546
OS 2.7808301 -3.45916758
OS 2.76280118 -3.4494597
OS 2.74199858 -3.44113866
OS 2.74061174 -3.43975182
OS 2.73367754 -3.43836498
OS 2.72258282 -3.43420446
OS 2.71564862 -3.43281762
OS 2.70594074 -3.43004394
OS 2.69623286 -3.42588342
OS 2.6837513 -3.42310974
OS 2.6698829 -3.41894922
OS 2.65324082 -3.4147887
OS 2.63659874 -3.41062818
OS 2.61718298 -3.40508082
OS 2.59499354 -3.39953346
OS 2.57141726 -3.3939861
OS 2.57003042 -3.3939861
OS 2.5658699 -3.39259926
OS 2.5589357 -3.39121242
OS 2.55061466 -3.38843874
OS 2.53951994 -3.38566506
OS 2.52703838 -3.38289138
OS 2.49930158 -3.37457034
OS 2.4687911 -3.36486246
OS 2.43689378 -3.35515458
OS 2.40915698 -3.3454467
OS 2.39667542 -3.33989934
OS 2.3855807 -3.33435198
OS 2.38419386 -3.33435198
OS 2.38280702 -3.33296514
OS 2.37448598 -3.32741778
OS 2.36200442 -3.32048358
OS 2.34813602 -3.30938886
OS 2.33149394 -3.2969073
OS 2.31485186 -3.28165206
OS 2.29820978 -3.26362314
OS 2.28434138 -3.24420738
OS 2.28295454 -3.2414337
OS 2.27879402 -3.2344995
OS 2.27324666 -3.22340478
OS 2.2676993 -3.20953638
OS 2.26215194 -3.19150746
OS 2.25660458 -3.17070486
OS 2.25244406 -3.14851542
OS 2.25105722 -3.12493914
OS 2.25105722 -3.1235523
OS 2.25105722 -3.12216546
OS 2.25105722 -3.11800494
OS 2.25105722 -3.11245758
OS 2.2538309 -3.09858918
OS 2.25660458 -3.08056026
OS 2.2607651 -3.05975766
OS 2.2676993 -3.03618138
OS 2.27740718 -3.0126051
OS 2.29127558 -2.98902882
OS 2.29127558 -2.98764198
OS 2.29266242 -2.98625514
OS 2.29959662 -2.9779341
OS 2.3093045 -2.96683938
OS 2.32178606 -2.95297098
OS 2.33842814 -2.93771574
OS 2.35923074 -2.92107366
OS 2.38419386 -2.90581842
OS 2.41193066 -2.89195002
OS 2.4133175 -2.89195002
OS 2.41609118 -2.89056318
OS 2.4202517 -2.88917634
OS 2.42579906 -2.88640266
OS 2.43273326 -2.88362898
OS 2.44244114 -2.8808553
OS 2.46324374 -2.87530794
OS 2.4895937 -2.86976058
OS 2.52010418 -2.86421322
OS 2.5520015 -2.8600527
OS 2.58805934 -2.85866586
OS 2.60608826 -2.85866586
OS 2.61579614 -2.8600527
OE
OB 3.94438886 -3.83500122 I
OS 3.8001575 -3.83500122
OS 3.68782346 -3.54376482
OS 3.28563986 -3.54376482
OS 3.18162686 -3.83500122
OS 3.04710338 -3.83500122
OS 3.41322914 -2.87530794
OS 3.55191314 -2.87530794
OS 3.94438886 -3.83500122
OE
OB 7.18959446 -3.12493914 I
OS 7.21039706 -3.12632598
OS 7.23397334 -3.12909966
OS 7.25754962 -3.13326018
OS 7.2811259 -3.13880754
OS 7.30331534 -3.14574174
OS 7.30608902 -3.14712858
OS 7.31302322 -3.14990226
OS 7.3227311 -3.15406278
OS 7.33521266 -3.15961014
OS 7.34908106 -3.16793118
OS 7.36294946 -3.17625222
OS 7.37543102 -3.18734694
OS 7.38652574 -3.19844166
OS 7.38791258 -3.1998285
OS 7.39068626 -3.20398902
OS 7.39484678 -3.21092322
OS 7.40039414 -3.21924426
OS 7.40732834 -3.23172582
OS 7.4128757 -3.24420738
OS 7.41842306 -3.25946262
OS 7.42258358 -3.27749154
OS 7.42258358 -3.27887838
OS 7.42397042 -3.2830389
OS 7.42535726 -3.29135994
OS 7.4267441 -3.30245466
OS 7.4267441 -3.3177099
OS 7.42813094 -3.33573882
OS 7.42951778 -3.3593151
OS 7.42951778 -3.38566506
OS 7.42951778 -3.54376482
OS 7.42951778 -3.54515166
OS 7.42951778 -3.55069902
OS 7.42951778 -3.55902006
OS 7.42951778 -3.57011478
OS 7.42951778 -3.58259634
OS 7.42951778 -3.59785158
OS 7.43090462 -3.63113574
OS 7.43090462 -3.66580674
OS 7.43229146 -3.70047774
OS 7.4336783 -3.71573298
OS 7.4336783 -3.72960138
OS 7.43506514 -3.74208294
OS 7.43645198 -3.75179082
OS 7.43645198 -3.75317766
OS 7.43783882 -3.75872502
OS 7.43922566 -3.76704606
OS 7.44338618 -3.77814078
OS 7.44615986 -3.79062234
OS 7.45170722 -3.80449074
OS 7.45864142 -3.81974598
OS 7.46557562 -3.83500122
OS 7.34214686 -3.83500122
OS 7.34076002 -3.83361438
OS 7.33937318 -3.82806702
OS 7.3365995 -3.82113282
OS 7.33243898 -3.8100381
OS 7.32827846 -3.79755654
OS 7.32550478 -3.7823013
OS 7.3227311 -3.76565922
OS 7.31995742 -3.7476303
OS 7.31857058 -3.7476303
OS 7.31718374 -3.75040398
OS 7.3088627 -3.75733818
OS 7.29638114 -3.76704606
OS 7.27973906 -3.77952762
OS 7.25893646 -3.79200918
OS 7.23813386 -3.80587758
OS 7.21594442 -3.81835914
OS 7.19236814 -3.82806702
OS 7.18959446 -3.82945386
OS 7.18127342 -3.8308407
OS 7.16879186 -3.83500122
OS 7.15353662 -3.83916174
OS 7.13412086 -3.84332226
OS 7.11193142 -3.84609594
OS 7.0869683 -3.84886962
OS 7.06200518 -3.85025646
OS 7.05091046 -3.85025646
OS 7.04258942 -3.84886962
OS 7.03288154 -3.84886962
OS 7.02178682 -3.84748278
OS 6.9968237 -3.84332226
OS 6.9690869 -3.83638806
OS 6.93857642 -3.82668018
OS 6.91083962 -3.81281178
OS 6.8858765 -3.79478286
OS 6.88310282 -3.79200918
OS 6.87616862 -3.78507498
OS 6.86646074 -3.77259342
OS 6.85536602 -3.75595134
OS 6.8442713 -3.73514874
OS 6.83456342 -3.71157246
OS 6.82762922 -3.68244882
OS 6.82624238 -3.66858042
OS 6.82485554 -3.65193834
OS 6.82485554 -3.64916466
OS 6.82485554 -3.6436173
OS 6.82624238 -3.63390942
OS 6.82762922 -3.62142786
OS 6.8304029 -3.60617262
OS 6.83456342 -3.59091738
OS 6.84011078 -3.5742753
OS 6.84704498 -3.55902006
OS 6.84843182 -3.55763322
OS 6.8512055 -3.55208586
OS 6.85675286 -3.54376482
OS 6.86368706 -3.53405694
OS 6.8720081 -3.52296222
OS 6.88310282 -3.5118675
OS 6.89419754 -3.50077278
OS 6.90806594 -3.4910649
OS 6.90945278 -3.48967806
OS 6.91500014 -3.48690438
OS 6.92193434 -3.48135702
OS 6.93302906 -3.47580966
OS 6.94551062 -3.4702623
OS 6.96076586 -3.4633281
OS 6.9760211 -3.45778074
OS 6.99405002 -3.45223338
OS 6.99543686 -3.45223338
OS 7.00098422 -3.45084654
OS 7.00930526 -3.44807286
OS 7.02039998 -3.44668602
OS 7.03426838 -3.44391234
OS 7.0522973 -3.44113866
OS 7.0730999 -3.43697814
OS 7.09806302 -3.43420446
OS 7.09944986 -3.43420446
OS 7.10499722 -3.43281762
OS 7.11193142 -3.43281762
OS 7.1216393 -3.43143078
OS 7.13273402 -3.43004394
OS 7.14660242 -3.42727026
OS 7.16185766 -3.42588342
OS 7.17849974 -3.42310974
OS 7.2117839 -3.41617554
OS 7.24784174 -3.40924134
OS 7.27973906 -3.4009203
OS 7.2949943 -3.39675978
OS 7.3088627 -3.39259926
OS 7.3088627 -3.39121242
OS 7.3088627 -3.38843874
OS 7.31024954 -3.3801177
OS 7.31024954 -3.37040982
OS 7.31024954 -3.36486246
OS 7.31024954 -3.36208878
OS 7.31024954 -3.36070194
OS 7.31024954 -3.3593151
OS 7.31024954 -3.35099406
OS 7.3088627 -3.33712566
OS 7.30608902 -3.32187042
OS 7.3019285 -3.30522834
OS 7.2949943 -3.28858626
OS 7.28667326 -3.27333102
OS 7.27557854 -3.26084946
OS 7.2741917 -3.25946262
OS 7.2672575 -3.25391526
OS 7.25616278 -3.2483679
OS 7.24229438 -3.24004686
OS 7.22287862 -3.23311266
OS 7.20068918 -3.22617846
OS 7.17295238 -3.22201794
OS 7.14105506 -3.2206311
OS 7.12718666 -3.2206311
OS 7.11331826 -3.22201794
OS 7.0939025 -3.22479162
OS 7.07448674 -3.2275653
OS 7.05368414 -3.23311266
OS 7.03426838 -3.24004686
OS 7.0176263 -3.24975474
OS 7.01623946 -3.25114158
OS 7.0106921 -3.2553021
OS 7.0037579 -3.2622363
OS 6.99543686 -3.27333102
OS 6.98711582 -3.28719942
OS 6.97740794 -3.30522834
OS 6.9690869 -3.32741778
OS 6.96076586 -3.3523809
OS 6.84565814 -3.33712566
OS 6.84565814 -3.33573882
OS 6.84704498 -3.33435198
OS 6.84704498 -3.33019146
OS 6.84843182 -3.3246441
OS 6.85259234 -3.31216254
OS 6.8581397 -3.29413362
OS 6.8650739 -3.2761047
OS 6.87339494 -3.25668894
OS 6.88448966 -3.23727318
OS 6.89697122 -3.21924426
OS 6.89835806 -3.21785742
OS 6.90390542 -3.21231006
OS 6.91222646 -3.20398902
OS 6.92332118 -3.1928943
OS 6.93857642 -3.18179958
OS 6.95660534 -3.17070486
OS 6.97740794 -3.1582233
OS 7.00098422 -3.14851542
OS 7.00237106 -3.14851542
OS 7.0037579 -3.14712858
OS 7.00791842 -3.14574174
OS 7.01346578 -3.1443549
OS 7.02733418 -3.14019438
OS 7.04674994 -3.13603386
OS 7.06893938 -3.13187334
OS 7.09667618 -3.12771282
OS 7.12579982 -3.12493914
OS 7.15908398 -3.1235523
OS 7.17433922 -3.1235523
OS 7.18959446 -3.12493914
OE
OB 8.17286402 -3.83500122 I
OS 8.06746418 -3.83500122
OS 8.06746418 -3.7337619
OS 8.06607734 -3.73514874
OS 8.06330366 -3.73930926
OS 8.05914314 -3.74485662
OS 8.05220894 -3.75179082
OS 8.0438879 -3.76011186
OS 8.03418002 -3.77120658
OS 8.0230853 -3.78091446
OS 8.0092169 -3.79200918
OS 7.99396166 -3.8031039
OS 7.97731958 -3.81281178
OS 7.95929066 -3.82251966
OS 7.9398749 -3.83222754
OS 7.91768546 -3.83916174
OS 7.89549602 -3.8447091
OS 7.8705329 -3.84886962
OS 7.84556978 -3.85025646
OS 7.8358619 -3.85025646
OS 7.82338034 -3.84886962
OS 7.8081251 -3.84748278
OS 7.79009618 -3.8447091
OS 7.77068042 -3.84054858
OS 7.75126466 -3.83500122
OS 7.73046206 -3.82668018
OS 7.72768838 -3.82529334
OS 7.72214102 -3.82251966
OS 7.71243314 -3.8169723
OS 7.70133842 -3.8100381
OS 7.68747002 -3.80171706
OS 7.67498846 -3.79200918
OS 7.6625069 -3.78091446
OS 7.65141218 -3.7684329
OS 7.65002534 -3.76704606
OS 7.64725166 -3.7614987
OS 7.64309114 -3.7545645
OS 7.63754378 -3.74346978
OS 7.63060958 -3.73098822
OS 7.62506222 -3.71573298
OS 7.61951486 -3.6990909
OS 7.61535434 -3.68106198
OS 7.61535434 -3.67967514
OS 7.6139675 -3.67412778
OS 7.61258066 -3.66580674
OS 7.61258066 -3.65471202
OS 7.61119382 -3.63806994
OS 7.60980698 -3.62004102
OS 7.60842014 -3.59646474
OS 7.60842014 -3.57011478
OS 7.60842014 -3.13880754
OS 7.72630154 -3.13880754
OS 7.72630154 -3.5257359
OS 7.72630154 -3.52712274
OS 7.72630154 -3.52989642
OS 7.72630154 -3.53405694
OS 7.72630154 -3.54099114
OS 7.72630154 -3.55624638
OS 7.72768838 -3.57566214
OS 7.72768838 -3.59646474
OS 7.72907522 -3.61726734
OS 7.73046206 -3.63529626
OS 7.73323574 -3.6505515
OS 7.73323574 -3.65193834
OS 7.73600942 -3.6574857
OS 7.7387831 -3.66580674
OS 7.74294362 -3.67690146
OS 7.74987782 -3.68799618
OS 7.75819886 -3.70047774
OS 7.76790674 -3.71157246
OS 7.7803883 -3.72266718
OS 7.78177514 -3.72405402
OS 7.7873225 -3.7268277
OS 7.7942567 -3.73098822
OS 7.80535142 -3.73514874
OS 7.81783298 -3.7406961
OS 7.83308822 -3.74485662
OS 7.8497303 -3.7476303
OS 7.86914606 -3.74901714
OS 7.87885394 -3.74901714
OS 7.88856182 -3.7476303
OS 7.90104338 -3.74624346
OS 7.91629862 -3.74208294
OS 7.9329407 -3.73792242
OS 7.95096962 -3.73098822
OS 7.96899854 -3.72266718
OS 7.97177222 -3.72128034
OS 7.97731958 -3.71711982
OS 7.98564062 -3.71157246
OS 7.9953485 -3.70325142
OS 8.00644322 -3.6921567
OS 8.01753794 -3.67967514
OS 8.02724582 -3.66580674
OS 8.03556686 -3.64916466
OS 8.0369537 -3.64639098
OS 8.03834054 -3.64084362
OS 8.04111422 -3.6297489
OS 8.04527474 -3.61449366
OS 8.04943526 -3.5950779
OS 8.05220894 -3.57150162
OS 8.05359578 -3.54376482
OS 8.05498262 -3.5118675
OS 8.05498262 -3.13880754
OS 8.17286402 -3.13880754
OS 8.17286402 -3.83500122
OE
OB 13.83671858 -3.22062856 H
OS 13.82978438 -3.22062856
OS 13.82423702 -3.2220154
OS 13.80898178 -3.22340224
OS 13.79095286 -3.2289496
OS 13.77015026 -3.2358838
OS 13.74796082 -3.24836536
OS 13.72577138 -3.2636206
OS 13.71467666 -3.27471532
OS 13.70496878 -3.28581004
OS 13.70496878 -3.28719688
OS 13.7021951 -3.28858372
OS 13.70080826 -3.29274424
OS 13.69664774 -3.2982916
OS 13.69248722 -3.3052258
OS 13.6883267 -3.31354684
OS 13.68416618 -3.32325472
OS 13.67861882 -3.33434944
OS 13.67307146 -3.34821784
OS 13.66891094 -3.36347308
OS 13.66475042 -3.38011516
OS 13.6605899 -3.39814408
OS 13.65781622 -3.41755984
OS 13.65504254 -3.43974928
OS 13.65226886 -3.46332556
OS 13.65226886 -3.48828868
OS 13.65226886 -3.48967552
OS 13.65226886 -3.49383604
OS 13.65226886 -3.50077024
OS 13.6536557 -3.51047812
OS 13.6536557 -3.52157284
OS 13.65504254 -3.5340544
OS 13.65920306 -3.56317804
OS 13.66613726 -3.59507536
OS 13.67584514 -3.62835952
OS 13.68971354 -3.66025684
OS 13.69803458 -3.67412524
OS 13.70774246 -3.68799364
OS 13.7091293 -3.68799364
OS 13.71051614 -3.69076732
OS 13.71745034 -3.69770152
OS 13.7299319 -3.70879624
OS 13.74518714 -3.71989096
OS 13.7646029 -3.73237252
OS 13.78817918 -3.74346724
OS 13.8131423 -3.75040144
OS 13.8270107 -3.75178828
OS 13.8408791 -3.75317512
OS 13.8478133 -3.75317512
OS 13.85336066 -3.75178828
OS 13.8686159 -3.75040144
OS 13.88664482 -3.74485408
OS 13.90744742 -3.73791988
OS 13.92963686 -3.72682516
OS 13.9518263 -3.71156992
OS 13.96292102 -3.70186204
OS 13.9726289 -3.69076732
OS 13.9726289 -3.68938048
OS 13.97540258 -3.68799364
OS 13.97817626 -3.68383312
OS 13.98094994 -3.67828576
OS 13.98511046 -3.67135156
OS 13.99065782 -3.66441736
OS 13.99481834 -3.65332264
OS 14.0003657 -3.64222792
OS 14.00591306 -3.62974636
OS 14.01007358 -3.61587796
OS 14.01562094 -3.59923588
OS 14.01978146 -3.5825938
OS 14.02255514 -3.56317804
OS 14.02532882 -3.54376228
OS 14.0281025 -3.52157284
OS 14.0281025 -3.49799656
OS 14.0281025 -3.49660972
OS 14.0281025 -3.49106236
OS 14.0281025 -3.48412816
OS 14.02671566 -3.47442028
OS 14.02671566 -3.46332556
OS 14.02532882 -3.44945716
OS 14.02394198 -3.43420192
OS 14.0211683 -3.41755984
OS 14.0142341 -3.38427568
OS 14.00452622 -3.34960468
OS 13.99065782 -3.31632052
OS 13.98233678 -3.30245212
OS 13.9726289 -3.28858372
OS 13.9726289 -3.28719688
OS 13.96985522 -3.28581004
OS 13.96292102 -3.277489
OS 13.95043946 -3.26639428
OS 13.93518422 -3.25391272
OS 13.91576846 -3.24143116
OS 13.89219218 -3.23172328
OS 13.86584222 -3.22340224
OS 13.85197382 -3.2220154
OS 13.83671858 -3.22062856
OE
OB 10.50830258 -3.22062856 H
OS 10.49998154 -3.22062856
OS 10.49443418 -3.2220154
OS 10.47917894 -3.22340224
OS 10.46115002 -3.22756276
OS 10.43896058 -3.23449696
OS 10.4153843 -3.24420484
OS 10.39319486 -3.25807324
OS 10.37100542 -3.27610216
OS 10.36823174 -3.27887584
OS 10.36268438 -3.28581004
OS 10.3529765 -3.2982916
OS 10.34326862 -3.31493368
OS 10.3321739 -3.33434944
OS 10.32246602 -3.35931256
OS 10.31414498 -3.3884362
OS 10.30998446 -3.42033352
OS 10.6996865 -3.42033352
OS 10.6996865 -3.41894668
OS 10.6996865 -3.416173
OS 10.69829966 -3.41201248
OS 10.69829966 -3.40646512
OS 10.69552598 -3.38982304
OS 10.69136546 -3.37179412
OS 10.68443126 -3.34960468
OS 10.67749706 -3.32880208
OS 10.66640234 -3.30799948
OS 10.65392078 -3.28997056
OS 10.65392078 -3.28858372
OS 10.6511471 -3.28719688
OS 10.6442129 -3.27887584
OS 10.63173134 -3.26778112
OS 10.61508926 -3.25529956
OS 10.59428666 -3.242818
OS 10.56932354 -3.23172328
OS 10.5401999 -3.22340224
OS 10.52494466 -3.2220154
OS 10.50830258 -3.22062856
OE
OB 8.63606858 -3.2206311 H
OS 8.61387914 -3.2206311
OS 8.60833178 -3.22201794
OS 8.59307654 -3.22340478
OS 8.57504762 -3.22895214
OS 8.55285818 -3.23588634
OS 8.53066874 -3.2483679
OS 8.5084793 -3.26362314
OS 8.49738458 -3.27471786
OS 8.48628986 -3.28581258
OS 8.48628986 -3.28719942
OS 8.48351618 -3.28858626
OS 8.4807425 -3.29274678
OS 8.47796882 -3.29829414
OS 8.4738083 -3.3038415
OS 8.46964778 -3.31216254
OS 8.46410042 -3.32187042
OS 8.4599399 -3.33296514
OS 8.45439254 -3.3454467
OS 8.44884518 -3.36070194
OS 8.44468466 -3.37595718
OS 8.44052414 -3.39259926
OS 8.43775046 -3.41201502
OS 8.43497678 -3.43143078
OS 8.4322031 -3.45223338
OS 8.4322031 -3.47580966
OS 8.4322031 -3.4771965
OS 8.4322031 -3.48135702
OS 8.4322031 -3.48829122
OS 8.43358994 -3.4979991
OS 8.43358994 -3.50909382
OS 8.43497678 -3.52296222
OS 8.4391373 -3.55208586
OS 8.4460715 -3.58537002
OS 8.45439254 -3.61726734
OS 8.46826094 -3.64916466
OS 8.47658198 -3.66303306
OS 8.48628986 -3.67551462
OS 8.48906354 -3.6782883
OS 8.49599774 -3.6852225
OS 8.50709246 -3.69493038
OS 8.52373454 -3.7060251
OS 8.5431503 -3.71850666
OS 8.56672658 -3.72821454
OS 8.59307654 -3.73514874
OS 8.60694494 -3.73653558
OS 8.62220018 -3.73792242
OS 8.63052122 -3.73792242
OS 8.63606858 -3.73653558
OS 8.65132382 -3.73514874
OS 8.67073958 -3.72960138
OS 8.69154218 -3.72266718
OS 8.71511846 -3.71157246
OS 8.7373079 -3.69631722
OS 8.74840262 -3.68660934
OS 8.75949734 -3.67551462
OS 8.75949734 -3.67412778
OS 8.76227102 -3.67274094
OS 8.7650447 -3.66858042
OS 8.76781838 -3.66303306
OS 8.7719789 -3.6574857
OS 8.77752626 -3.64916466
OS 8.78168678 -3.63945678
OS 8.78723414 -3.62697522
OS 8.7927815 -3.61449366
OS 8.79694202 -3.60062526
OS 8.80248938 -3.58398318
OS 8.8066499 -3.56595426
OS 8.80942358 -3.54792534
OS 8.81219726 -3.52712274
OS 8.81497094 -3.50354646
OS 8.81497094 -3.47997018
OS 8.81497094 -3.47858334
OS 8.81497094 -3.47442282
OS 8.81497094 -3.46748862
OS 8.8135841 -3.45916758
OS 8.8135841 -3.44807286
OS 8.81219726 -3.4355913
OS 8.80803674 -3.4078545
OS 8.80110254 -3.37595718
OS 8.79139466 -3.34405986
OS 8.77752626 -3.31216254
OS 8.76781838 -3.29829414
OS 8.7581105 -3.28581258
OS 8.7581105 -3.28442574
OS 8.75533682 -3.2830389
OS 8.74840262 -3.2761047
OS 8.73592106 -3.26500998
OS 8.71927898 -3.25252842
OS 8.69986322 -3.2414337
OS 8.67628694 -3.23033898
OS 8.64993698 -3.22340478
OS 8.63606858 -3.2206311
OE
OB 3.47979746 -2.97516042 H
OS 3.47979746 -2.97654726
OS 3.47841062 -2.97932094
OS 3.47841062 -2.9848683
OS 3.47563694 -2.99041566
OS 3.4742501 -3.00012354
OS 3.47147642 -3.00983142
OS 3.46592906 -3.0334077
OS 3.45899486 -3.0611445
OS 3.44928698 -3.09165498
OS 3.4395791 -3.12493914
OS 3.42709754 -3.15961014
OS 3.32308454 -3.43975182
OS 3.6476051 -3.43975182
OS 3.54775262 -3.17625222
OS 3.54775262 -3.17486538
OS 3.54636578 -3.17070486
OS 3.5435921 -3.16377066
OS 3.54081842 -3.15544962
OS 3.5366579 -3.14574174
OS 3.53249738 -3.13326018
OS 3.52833686 -3.11939178
OS 3.5227895 -3.10552338
OS 3.51169478 -3.07362606
OS 3.50060006 -3.0403419
OS 3.48950534 -3.00705774
OS 3.47979746 -2.97516042
OE
OB 12.8284859 -3.485515 H
OS 12.82709906 -3.485515
OS 12.82571222 -3.48690184
OS 12.8215517 -3.48828868
OS 12.81600434 -3.48967552
OS 12.80907014 -3.4924492
OS 12.8007491 -3.49522288
OS 12.79104122 -3.49799656
OS 12.7799465 -3.50077024
OS 12.76746494 -3.50493076
OS 12.7522097 -3.50770444
OS 12.73695446 -3.51186496
OS 12.71892554 -3.51602548
OS 12.69950978 -3.520186
OS 12.68009402 -3.52434652
OS 12.65790458 -3.5271202
OS 12.6343283 -3.53128072
OS 12.63155462 -3.53128072
OS 12.62323358 -3.53266756
OS 12.60936518 -3.53544124
OS 12.59410994 -3.53821492
OS 12.57746786 -3.5409886
OS 12.56082578 -3.54514912
OS 12.54557054 -3.54930964
OS 12.53170214 -3.554857
OS 12.5303153 -3.554857
OS 12.52615478 -3.55763068
OS 12.52060742 -3.56040436
OS 12.51506006 -3.56456488
OS 12.49841798 -3.5756596
OS 12.48454958 -3.59230168
OS 12.48454958 -3.59368852
OS 12.4817759 -3.5964622
OS 12.48038906 -3.60200956
OS 12.47761538 -3.60894376
OS 12.4748417 -3.6172648
OS 12.47206802 -3.62558584
OS 12.47068118 -3.63668056
OS 12.46929434 -3.64777528
OS 12.46929434 -3.64916212
OS 12.46929434 -3.65609632
OS 12.47068118 -3.66441736
OS 12.47345486 -3.67551208
OS 12.47761538 -3.68799364
OS 12.48454958 -3.7004752
OS 12.49287062 -3.7143436
OS 12.50396534 -3.72682516
OS 12.50535218 -3.728212
OS 12.51089954 -3.73098568
OS 12.51922058 -3.73653304
OS 12.5303153 -3.7420804
OS 12.54557054 -3.74762776
OS 12.56359946 -3.75317512
OS 12.58440206 -3.7559488
OS 12.60936518 -3.75733564
OS 12.6204599 -3.75733564
OS 12.6343283 -3.7559488
OS 12.64958354 -3.75317512
OS 12.6689993 -3.75040144
OS 12.68841506 -3.74485408
OS 12.70921766 -3.73791988
OS 12.73002026 -3.728212
OS 12.73279394 -3.72682516
OS 12.7383413 -3.72266464
OS 12.74804918 -3.71573044
OS 12.7591439 -3.70602256
OS 12.77162546 -3.69492784
OS 12.78549386 -3.68105944
OS 12.79658858 -3.66441736
OS 12.8076833 -3.64638844
OS 12.80907014 -3.6450016
OS 12.81045698 -3.63945424
OS 12.81323066 -3.62974636
OS 12.81739118 -3.6172648
OS 12.8215517 -3.60062272
OS 12.82432538 -3.58120696
OS 12.82571222 -3.55763068
OS 12.82709906 -3.52989388
OS 12.8284859 -3.485515
OE
OB 7.31024954 -3.48551754 H
OS 7.3088627 -3.48551754
OS 7.30747586 -3.48690438
OS 7.30331534 -3.48829122
OS 7.29776798 -3.48967806
OS 7.29083378 -3.49245174
OS 7.28251274 -3.49522542
OS 7.27280486 -3.4979991
OS 7.26171014 -3.50077278
OS 7.24922858 -3.5049333
OS 7.23397334 -3.50770698
OS 7.2187181 -3.5118675
OS 7.20068918 -3.51602802
OS 7.18127342 -3.52018854
OS 7.16185766 -3.52434906
OS 7.13966822 -3.52712274
OS 7.11609194 -3.53128326
OS 7.11331826 -3.53128326
OS 7.10499722 -3.5326701
OS 7.09112882 -3.53544378
OS 7.07587358 -3.53821746
OS 7.0592315 -3.54099114
OS 7.04258942 -3.54515166
OS 7.02733418 -3.54931218
OS 7.01346578 -3.55485954
OS 7.01207894 -3.55485954
OS 7.00791842 -3.55763322
OS 7.00237106 -3.5604069
OS 6.9968237 -3.56456742
OS 6.98018162 -3.57566214
OS 6.96631322 -3.59230422
OS 6.96631322 -3.59369106
OS 6.96353954 -3.59646474
OS 6.9621527 -3.6020121
OS 6.95937902 -3.6089463
OS 6.95660534 -3.61726734
OS 6.95383166 -3.62558838
OS 6.95244482 -3.6366831
OS 6.95105798 -3.64777782
OS 6.95105798 -3.64916466
OS 6.95105798 -3.65609886
OS 6.95244482 -3.6644199
OS 6.9552185 -3.67551462
OS 6.95937902 -3.68799618
OS 6.96631322 -3.70047774
OS 6.97463426 -3.71434614
OS 6.98572898 -3.7268277
OS 6.98711582 -3.72821454
OS 6.99266318 -3.73098822
OS 7.00098422 -3.73653558
OS 7.01207894 -3.74208294
OS 7.02733418 -3.7476303
OS 7.0453631 -3.75317766
OS 7.0661657 -3.75595134
OS 7.09112882 -3.75733818
OS 7.10222354 -3.75733818
OS 7.11609194 -3.75595134
OS 7.13134718 -3.75317766
OS 7.15076294 -3.75040398
OS 7.1701787 -3.74485662
OS 7.1909813 -3.73792242
OS 7.2117839 -3.72821454
OS 7.21455758 -3.7268277
OS 7.22010494 -3.72266718
OS 7.22981282 -3.71573298
OS 7.24090754 -3.7060251
OS 7.2533891 -3.69493038
OS 7.2672575 -3.68106198
OS 7.27835222 -3.6644199
OS 7.28944694 -3.64639098
OS 7.29083378 -3.64500414
OS 7.29222062 -3.63945678
OS 7.2949943 -3.6297489
OS 7.29915482 -3.61726734
OS 7.30331534 -3.60062526
OS 7.30608902 -3.5812095
OS 7.30747586 -3.55763322
OS 7.3088627 -3.52989642
OS 7.31024954 -3.48551754
OE
OB 4.3756961 -3.06669186 H
OS 4.07336498 -3.49661226
OS 4.3756961 -3.49661226
OS 4.3756961 -3.06669186
OE
OB 6.2617985 -2.98902882 H
OS 6.0399041 -2.98902882
OS 6.0399041 -3.72128034
OS 6.26734586 -3.72128034
OS 6.27705374 -3.7198935
OS 6.29785634 -3.71850666
OS 6.32143262 -3.71711982
OS 6.34639574 -3.71434614
OS 6.37135886 -3.71018562
OS 6.39216146 -3.70463826
OS 6.39493514 -3.70325142
OS 6.40186934 -3.70186458
OS 6.41157722 -3.69770406
OS 6.42405878 -3.6921567
OS 6.43792718 -3.68383566
OS 6.45179558 -3.67551462
OS 6.46566398 -3.66580674
OS 6.47953238 -3.65471202
OS 6.48091922 -3.65193834
OS 6.48646658 -3.64639098
OS 6.49478762 -3.6366831
OS 6.5044955 -3.6228147
OS 6.51559022 -3.60478578
OS 6.52807178 -3.58398318
OS 6.5391665 -3.5604069
OS 6.54887438 -3.53405694
OS 6.54887438 -3.5326701
OS 6.55026122 -3.52989642
OS 6.55164806 -3.5257359
OS 6.5530349 -3.52018854
OS 6.55442174 -3.51325434
OS 6.55719542 -3.50354646
OS 6.5599691 -3.49383858
OS 6.56274278 -3.48274386
OS 6.5669033 -3.45500706
OS 6.57106382 -3.42310974
OS 6.5738375 -3.3870519
OS 6.57522434 -3.34822038
OS 6.57522434 -3.34683354
OS 6.57522434 -3.34128618
OS 6.57522434 -3.33435198
OS 6.5738375 -3.32325726
OS 6.5738375 -3.3107757
OS 6.57245066 -3.2969073
OS 6.57106382 -3.28026522
OS 6.56967698 -3.26362314
OS 6.56274278 -3.22617846
OS 6.55442174 -3.18734694
OS 6.54194018 -3.1512891
OS 6.53361914 -3.13326018
OS 6.5252981 -3.11800494
OS 6.5252981 -3.1166181
OS 6.52252442 -3.11384442
OS 6.51975074 -3.1096839
OS 6.51697706 -3.10413654
OS 6.50588234 -3.09026814
OS 6.49201394 -3.07362606
OS 6.47398502 -3.05559714
OS 6.45318242 -3.03756822
OS 6.42960614 -3.02231298
OS 6.40464302 -3.00983142
OS 6.40186934 -3.00844458
OS 6.39493514 -3.00705774
OS 6.38245358 -3.00289722
OS 6.36442466 -2.9987367
OS 6.34223522 -2.99596302
OS 6.31449842 -2.9918025
OS 6.29785634 -2.99041566
OS 6.27982742 -2.99041566
OS 6.2617985 -2.98902882
OE
SE
S P 0
OB 12.70078232 0.7551039 I
OS 12.70078232 0.75371706
OS 12.70078232 0.74955654
OS 12.70078232 0.74400918
OS 12.70078232 0.73568814
OS 12.69939548 0.72459342
OS 12.69939548 0.7134987
OS 12.6966218 0.68714874
OS 12.69384812 0.65663826
OS 12.68830076 0.62474094
OS 12.67997972 0.5956173
OS 12.67027184 0.5678805
OS 12.67027184 0.56649366
OS 12.668885 0.56510682
OS 12.66472448 0.55678578
OS 12.65779028 0.54569106
OS 12.6480824 0.53043582
OS 12.634214 0.51518058
OS 12.61895876 0.4985385
OS 12.599543 0.48189642
OS 12.57735356 0.46802802
OS 12.57457988 0.46664118
OS 12.56625884 0.46248066
OS 12.55377728 0.4569333
OS 12.53574836 0.45138594
OS 12.51355892 0.44445174
OS 12.4885958 0.43890438
OS 12.460859 0.43474386
OS 12.43034852 0.43335702
OS 12.41786696 0.43335702
OS 12.40954592 0.43474386
OS 12.3984512 0.4361307
OS 12.38735648 0.43751754
OS 12.35823284 0.4430649
OS 12.32772236 0.45138594
OS 12.29582504 0.4638675
OS 12.27918296 0.47218854
OS 12.26392772 0.48189642
OS 12.25005932 0.49299114
OS 12.23619092 0.5054727
OS 12.23480408 0.50685954
OS 12.23341724 0.50824638
OS 12.23064356 0.51379374
OS 12.22648304 0.5193411
OS 12.22093568 0.5262753
OS 12.21538832 0.53598318
OS 12.20984096 0.5470779
OS 12.20290676 0.55955946
OS 12.1973594 0.57342786
OS 12.19181204 0.59006994
OS 12.18626468 0.60671202
OS 12.18071732 0.62612778
OS 12.17794364 0.64693038
OS 12.17378312 0.67050666
OS 12.17239628 0.69408294
OS 12.17239628 0.7204329
OS 12.287504 0.73707498
OS 12.287504 0.73568814
OS 12.287504 0.73291446
OS 12.287504 0.7273671
OS 12.28889084 0.71904606
OS 12.29027768 0.71072502
OS 12.29027768 0.70101714
OS 12.2944382 0.67744086
OS 12.29859872 0.65247774
OS 12.30691976 0.62751462
OS 12.3152408 0.60532518
OS 12.32078816 0.5956173
OS 12.32772236 0.58729626
OS 12.3291092 0.58590942
OS 12.33465656 0.5817489
OS 12.3429776 0.5748147
OS 12.35407232 0.5678805
OS 12.36932756 0.55955946
OS 12.38596964 0.5540121
OS 12.40677224 0.54846474
OS 12.42896168 0.5470779
OS 12.43728272 0.5470779
OS 12.44560376 0.54846474
OS 12.45808532 0.54985158
OS 12.47056688 0.55262526
OS 12.48443528 0.55539894
OS 12.49830368 0.5609463
OS 12.51217208 0.5678805
OS 12.51355892 0.56926734
OS 12.51771944 0.57204102
OS 12.5232668 0.57758838
OS 12.53158784 0.58313574
OS 12.53852204 0.59284362
OS 12.54684308 0.6025515
OS 12.55377728 0.61364622
OS 12.55932464 0.62751462
OS 12.55932464 0.62890146
OS 12.56209832 0.63444882
OS 12.56348516 0.6441567
OS 12.56625884 0.65663826
OS 12.56903252 0.67328034
OS 12.57041936 0.69408294
OS 12.57319304 0.71904606
OS 12.57319304 0.7481697
OS 12.57319304 1.40969238
OS 12.70078232 1.40969238
OS 12.70078232 0.7551039
OE
OB 11.61349976 1.14619278 I
OS 11.732768 1.14619278
OS 11.732768 1.05466134
OS 11.61349976 1.05466134
OS 11.61349976 0.64554354
OS 11.61349976 0.64276986
OS 11.61349976 0.6372225
OS 11.61349976 0.62890146
OS 11.6148866 0.61919358
OS 11.61627344 0.59700414
OS 11.61766028 0.58729626
OS 11.61904712 0.58036206
OS 11.62043396 0.57758838
OS 11.62459448 0.57204102
OS 11.63014184 0.56510682
OS 11.63984972 0.55817262
OS 11.6426234 0.55678578
OS 11.6495576 0.5540121
OS 11.66203916 0.55123842
OS 11.68006808 0.54985158
OS 11.69393648 0.54985158
OS 11.70087068 0.55123842
OS 11.71057856 0.55123842
OS 11.72167328 0.55262526
OS 11.732768 0.5540121
OS 11.74802324 0.4499991
OS 11.74524956 0.4499991
OS 11.7397022 0.44861226
OS 11.72999432 0.44722542
OS 11.71751276 0.44583858
OS 11.70364436 0.4430649
OS 11.68838912 0.44167806
OS 11.65787864 0.44029122
OS 11.64678392 0.44029122
OS 11.6356892 0.44167806
OS 11.6218208 0.4430649
OS 11.60517872 0.44445174
OS 11.58853664 0.44861226
OS 11.5732814 0.45277278
OS 11.55802616 0.45970698
OS 11.55663932 0.46109382
OS 11.5524788 0.4638675
OS 11.54693144 0.46802802
OS 11.5386104 0.47496222
OS 11.5316762 0.48189642
OS 11.52335516 0.4916043
OS 11.51503412 0.50131218
OS 11.50948676 0.51379374
OS 11.50948676 0.51518058
OS 11.50671308 0.52072794
OS 11.50532624 0.53043582
OS 11.50255256 0.54430422
OS 11.49977888 0.56233314
OS 11.49839204 0.57342786
OS 11.49839204 0.58590942
OS 11.4970052 0.60116466
OS 11.49561836 0.6164199
OS 11.49561836 0.63306198
OS 11.49561836 0.65247774
OS 11.49561836 1.05466134
OS 11.40824744 1.05466134
OS 11.40824744 1.14619278
OS 11.49561836 1.14619278
OS 11.49561836 1.31816094
OS 11.61349976 1.38888978
OS 11.61349976 1.14619278
OE
OB 10.95475076 1.42494762 I
OS 10.96445864 1.42494762
OS 10.9908086 1.42217394
OS 11.01993224 1.41801342
OS 11.05044272 1.41107922
OS 11.08372688 1.40275818
OS 11.11423736 1.39166346
OS 11.1156242 1.39166346
OS 11.11839788 1.39027662
OS 11.1225584 1.38750294
OS 11.12810576 1.38472926
OS 11.14197416 1.37779506
OS 11.16000308 1.3653135
OS 11.18080568 1.3514451
OS 11.20160828 1.33341618
OS 11.22102404 1.31261358
OS 11.23905296 1.2890373
OS 11.23905296 1.28765046
OS 11.2404398 1.28626362
OS 11.24321348 1.2821031
OS 11.24598716 1.27794258
OS 11.25292136 1.26407418
OS 11.2612424 1.24604526
OS 11.27095028 1.22385582
OS 11.27788448 1.19750586
OS 11.28481868 1.16976906
OS 11.28759236 1.13925858
OS 11.16555044 1.1295507
OS 11.16555044 1.13093754
OS 11.16555044 1.13371122
OS 11.1641636 1.13787174
OS 11.16277676 1.14480594
OS 11.15861624 1.16006118
OS 11.15306888 1.18086378
OS 11.14474784 1.20305322
OS 11.13226628 1.22524266
OS 11.11701104 1.24604526
OS 11.09759528 1.26546102
OS 11.0948216 1.26684786
OS 11.0878874 1.27239522
OS 11.074019 1.28071626
OS 11.05599008 1.2890373
OS 11.0324138 1.29735834
OS 11.004677 1.30567938
OS 10.970006 1.31122674
OS 10.93117448 1.31261358
OS 10.91175872 1.31261358
OS 10.90343768 1.31122674
OS 10.89234296 1.3098399
OS 10.86737984 1.30706622
OS 10.83964304 1.30151886
OS 10.81190624 1.29458466
OS 10.78555628 1.28348994
OS 10.77446156 1.27655574
OS 10.76336684 1.26962154
OS 10.76059316 1.2682347
OS 10.7550458 1.26268734
OS 10.74672476 1.25297946
OS 10.73840372 1.24188474
OS 10.72869584 1.2266295
OS 10.7203748 1.20998742
OS 10.71482744 1.19057166
OS 10.71205376 1.16838222
OS 10.71205376 1.16560854
OS 10.71205376 1.16006118
OS 10.7134406 1.1503533
OS 10.71621428 1.13925858
OS 10.7203748 1.12539018
OS 10.727309 1.11152178
OS 10.73563004 1.09765338
OS 10.7481116 1.08378498
OS 10.74949844 1.08239814
OS 10.75643264 1.07823762
OS 10.76198 1.0740771
OS 10.76752736 1.07130342
OS 10.7758484 1.0671429
OS 10.78555628 1.06159554
OS 10.79803784 1.05743502
OS 10.81190624 1.05188766
OS 10.82716148 1.0463403
OS 10.8451904 1.0394061
OS 10.86460616 1.03385874
OS 10.8867956 1.02692454
OS 10.91175872 1.02137718
OS 10.93949552 1.01444298
OS 10.94088236 1.01444298
OS 10.94642972 1.01305614
OS 10.95475076 1.0116693
OS 10.96445864 1.00889562
OS 10.9769402 1.00612194
OS 10.99219544 1.00196142
OS 11.00745068 0.9978009
OS 11.02409276 0.99364038
OS 11.0601506 0.9839325
OS 11.0948216 0.97422462
OS 11.11146368 0.96867726
OS 11.12671892 0.9631299
OS 11.14058732 0.95896938
OS 11.15168204 0.95342202
OS 11.15306888 0.95342202
OS 11.15584256 0.95203518
OS 11.16000308 0.9492615
OS 11.16555044 0.94648782
OS 11.18080568 0.93816678
OS 11.1988346 0.92707206
OS 11.2196372 0.91181682
OS 11.2404398 0.89517474
OS 11.25985556 0.87575898
OS 11.27649764 0.85495638
OS 11.27788448 0.8521827
OS 11.28343184 0.8452485
OS 11.2889792 0.83276694
OS 11.29730024 0.81612486
OS 11.30423444 0.7967091
OS 11.31116864 0.77313282
OS 11.31532916 0.74678286
OS 11.316716 0.71904606
OS 11.316716 0.71765922
OS 11.316716 0.71627238
OS 11.316716 0.71211186
OS 11.316716 0.7065645
OS 11.31394232 0.69130926
OS 11.31116864 0.6718935
OS 11.30562128 0.64970406
OS 11.29868708 0.62612778
OS 11.28759236 0.60116466
OS 11.27233712 0.5748147
OS 11.27233712 0.57342786
OS 11.27095028 0.57204102
OS 11.26401608 0.56371998
OS 11.2543082 0.55123842
OS 11.2404398 0.53737002
OS 11.22241088 0.52072794
OS 11.20022144 0.50269902
OS 11.17525832 0.48605694
OS 11.14613468 0.4708017
OS 11.14474784 0.4708017
OS 11.14197416 0.46941486
OS 11.13781364 0.46802802
OS 11.13226628 0.46525434
OS 11.12394524 0.46248066
OS 11.11423736 0.45832014
OS 11.09204792 0.45277278
OS 11.06569796 0.44583858
OS 11.03380064 0.43890438
OS 10.99912964 0.43474386
OS 10.96168496 0.43335702
OS 10.93949552 0.43335702
OS 10.9284008 0.43474386
OS 10.91591924 0.43474386
OS 10.90205084 0.4361307
OS 10.88540876 0.43751754
OS 10.85073776 0.4430649
OS 10.81467992 0.44861226
OS 10.77862208 0.45832014
OS 10.74395108 0.4708017
OS 10.74256424 0.4708017
OS 10.73979056 0.47218854
OS 10.73563004 0.47496222
OS 10.73008268 0.4777359
OS 10.7134406 0.48605694
OS 10.69402484 0.4985385
OS 10.6718354 0.51518058
OS 10.64825912 0.53459634
OS 10.62606968 0.55817262
OS 10.60526708 0.58452258
OS 10.60526708 0.58590942
OS 10.6024934 0.5886831
OS 10.60110656 0.59284362
OS 10.59694604 0.59839098
OS 10.59417236 0.60532518
OS 10.59001184 0.61364622
OS 10.58030396 0.63444882
OS 10.57059608 0.66079878
OS 10.56227504 0.68992242
OS 10.55672768 0.72320658
OS 10.553954 0.75787758
OS 10.67322224 0.7689723
OS 10.67322224 0.76758546
OS 10.67322224 0.76619862
OS 10.67460908 0.7620381
OS 10.67460908 0.75649074
OS 10.67738276 0.74400918
OS 10.68154328 0.72598026
OS 10.68709064 0.70795134
OS 10.692638 0.68714874
OS 10.70234588 0.66773298
OS 10.71205376 0.64970406
OS 10.7134406 0.64831722
OS 10.71760112 0.64276986
OS 10.72453532 0.63306198
OS 10.73563004 0.6233541
OS 10.74949844 0.61087254
OS 10.76475368 0.59839098
OS 10.78555628 0.58590942
OS 10.80774572 0.5748147
OS 10.80913256 0.5748147
OS 10.8105194 0.57342786
OS 10.81467992 0.57204102
OS 10.81884044 0.57065418
OS 10.83270884 0.56649366
OS 10.85073776 0.5609463
OS 10.8729272 0.55539894
OS 10.89789032 0.55123842
OS 10.92562712 0.54846474
OS 10.9561376 0.5470779
OS 10.96861916 0.5470779
OS 10.98248756 0.54846474
OS 10.99912964 0.54985158
OS 11.0185454 0.55262526
OS 11.04073484 0.55539894
OS 11.06292428 0.5609463
OS 11.08372688 0.5678805
OS 11.08650056 0.56926734
OS 11.09343476 0.57204102
OS 11.10314264 0.57758838
OS 11.1156242 0.58313574
OS 11.12810576 0.59284362
OS 11.14197416 0.6025515
OS 11.15584256 0.61364622
OS 11.16693728 0.62751462
OS 11.16832412 0.62890146
OS 11.1710978 0.63444882
OS 11.17525832 0.64138302
OS 11.18080568 0.65247774
OS 11.18635304 0.66357246
OS 11.19051356 0.67744086
OS 11.19328724 0.6926961
OS 11.19467408 0.70933818
OS 11.19467408 0.71072502
OS 11.19467408 0.71765922
OS 11.19328724 0.72598026
OS 11.1919004 0.73707498
OS 11.18773988 0.7481697
OS 11.18357936 0.7620381
OS 11.17664516 0.7759065
OS 11.16693728 0.78838806
OS 11.16555044 0.7897749
OS 11.16138992 0.79393542
OS 11.15584256 0.79948278
OS 11.14613468 0.80780382
OS 11.13503996 0.81612486
OS 11.11978472 0.82583274
OS 11.1017558 0.83554062
OS 11.0809532 0.84386166
OS 11.07956636 0.8452485
OS 11.07263216 0.84663534
OS 11.06153744 0.85079586
OS 11.05460324 0.8521827
OS 11.04489536 0.85495638
OS 11.03518748 0.8591169
OS 11.02270592 0.86189058
OS 11.00883752 0.8660511
OS 10.99219544 0.87021162
OS 10.97555336 0.87437214
OS 10.9561376 0.8799195
OS 10.93394816 0.88546686
OS 10.91037188 0.89101422
OS 10.90898504 0.89101422
OS 10.90482452 0.89240106
OS 10.89789032 0.8937879
OS 10.88956928 0.89656158
OS 10.87847456 0.89933526
OS 10.865993 0.90210894
OS 10.8382562 0.91042998
OS 10.80774572 0.92013786
OS 10.7758484 0.92984574
OS 10.7481116 0.93955362
OS 10.73563004 0.94510098
OS 10.72453532 0.95064834
OS 10.72314848 0.95064834
OS 10.72176164 0.95203518
OS 10.7134406 0.95758254
OS 10.70095904 0.96451674
OS 10.68709064 0.97561146
OS 10.67044856 0.98809302
OS 10.65380648 1.00334826
OS 10.6371644 1.02137718
OS 10.623296 1.04079294
OS 10.62190916 1.04356662
OS 10.61774864 1.05050082
OS 10.61220128 1.06159554
OS 10.60665392 1.07546394
OS 10.60110656 1.09349286
OS 10.5955592 1.11429546
OS 10.59139868 1.1364849
OS 10.59001184 1.16006118
OS 10.59001184 1.16144802
OS 10.59001184 1.16283486
OS 10.59001184 1.16699538
OS 10.59001184 1.17254274
OS 10.59278552 1.18641114
OS 10.5955592 1.20444006
OS 10.59971972 1.22524266
OS 10.60665392 1.24881894
OS 10.6163618 1.27239522
OS 10.6302302 1.2959715
OS 10.6302302 1.29735834
OS 10.63161704 1.29874518
OS 10.63855124 1.30706622
OS 10.64825912 1.31816094
OS 10.66074068 1.33202934
OS 10.67738276 1.34728458
OS 10.69818536 1.36392666
OS 10.72314848 1.3791819
OS 10.75088528 1.3930503
OS 10.75227212 1.3930503
OS 10.7550458 1.39443714
OS 10.75920632 1.39582398
OS 10.76475368 1.39859766
OS 10.77168788 1.40137134
OS 10.78139576 1.40414502
OS 10.80219836 1.40969238
OS 10.82854832 1.41523974
OS 10.8590588 1.4207871
OS 10.89095612 1.42494762
OS 10.92701396 1.42633446
OS 10.94504288 1.42633446
OS 10.95475076 1.42494762
OE
OB 13.21807364 1.16006118 I
OS 13.23887624 1.15867434
OS 13.26245252 1.15590066
OS 13.2860288 1.15174014
OS 13.30960508 1.14619278
OS 13.33179452 1.13925858
OS 13.3345682 1.13787174
OS 13.3415024 1.13509806
OS 13.35121028 1.13093754
OS 13.36369184 1.12539018
OS 13.37756024 1.11706914
OS 13.39142864 1.1087481
OS 13.4039102 1.09765338
OS 13.41500492 1.08655866
OS 13.41639176 1.08517182
OS 13.41916544 1.0810113
OS 13.42332596 1.0740771
OS 13.42887332 1.06575606
OS 13.43580752 1.0532745
OS 13.44135488 1.04079294
OS 13.44690224 1.0255377
OS 13.45106276 1.00750878
OS 13.45106276 1.00612194
OS 13.4524496 1.00196142
OS 13.45383644 0.99364038
OS 13.45522328 0.98254566
OS 13.45522328 0.96729042
OS 13.45661012 0.9492615
OS 13.45799696 0.92568522
OS 13.45799696 0.89933526
OS 13.45799696 0.7412355
OS 13.45799696 0.73984866
OS 13.45799696 0.7343013
OS 13.45799696 0.72598026
OS 13.45799696 0.71488554
OS 13.45799696 0.70240398
OS 13.45799696 0.68714874
OS 13.4593838 0.65386458
OS 13.4593838 0.61919358
OS 13.46077064 0.58452258
OS 13.46215748 0.56926734
OS 13.46215748 0.55539894
OS 13.46354432 0.54291738
OS 13.46493116 0.5332095
OS 13.46493116 0.53182266
OS 13.466318 0.5262753
OS 13.46770484 0.51795426
OS 13.47186536 0.50685954
OS 13.47463904 0.49437798
OS 13.4801864 0.48050958
OS 13.4871206 0.46525434
OS 13.4940548 0.4499991
OS 13.37062604 0.4499991
OS 13.3692392 0.45138594
OS 13.36785236 0.4569333
OS 13.36507868 0.4638675
OS 13.36091816 0.47496222
OS 13.35675764 0.48744378
OS 13.35398396 0.50269902
OS 13.35121028 0.5193411
OS 13.3484366 0.53737002
OS 13.34704976 0.53737002
OS 13.34566292 0.53459634
OS 13.33734188 0.52766214
OS 13.32486032 0.51795426
OS 13.30821824 0.5054727
OS 13.28741564 0.49299114
OS 13.26661304 0.47912274
OS 13.2444236 0.46664118
OS 13.22084732 0.4569333
OS 13.21807364 0.45554646
OS 13.2097526 0.45415962
OS 13.19727104 0.4499991
OS 13.1820158 0.44583858
OS 13.16260004 0.44167806
OS 13.1404106 0.43890438
OS 13.11544748 0.4361307
OS 13.09048436 0.43474386
OS 13.07938964 0.43474386
OS 13.0710686 0.4361307
OS 13.06136072 0.4361307
OS 13.050266 0.43751754
OS 13.02530288 0.44167806
OS 12.99756608 0.44861226
OS 12.9670556 0.45832014
OS 12.9393188 0.47218854
OS 12.91435568 0.49021746
OS 12.911582 0.49299114
OS 12.9046478 0.49992534
OS 12.89493992 0.5124069
OS 12.8838452 0.52904898
OS 12.87275048 0.54985158
OS 12.8630426 0.57342786
OS 12.8561084 0.6025515
OS 12.85472156 0.6164199
OS 12.85333472 0.63306198
OS 12.85333472 0.63583566
OS 12.85333472 0.64138302
OS 12.85472156 0.6510909
OS 12.8561084 0.66357246
OS 12.85888208 0.6788277
OS 12.8630426 0.69408294
OS 12.86858996 0.71072502
OS 12.87552416 0.72598026
OS 12.876911 0.7273671
OS 12.87968468 0.73291446
OS 12.88523204 0.7412355
OS 12.89216624 0.75094338
OS 12.90048728 0.7620381
OS 12.911582 0.77313282
OS 12.92267672 0.78422754
OS 12.93654512 0.79393542
OS 12.93793196 0.79532226
OS 12.94347932 0.79809594
OS 12.95041352 0.8036433
OS 12.96150824 0.80919066
OS 12.9739898 0.81473802
OS 12.98924504 0.82167222
OS 13.00450028 0.82721958
OS 13.0225292 0.83276694
OS 13.02391604 0.83276694
OS 13.0294634 0.83415378
OS 13.03778444 0.83692746
OS 13.04887916 0.8383143
OS 13.06274756 0.84108798
OS 13.08077648 0.84386166
OS 13.10157908 0.84802218
OS 13.1265422 0.85079586
OS 13.12792904 0.85079586
OS 13.1334764 0.8521827
OS 13.1404106 0.8521827
OS 13.15011848 0.85356954
OS 13.1612132 0.85495638
OS 13.1750816 0.85773006
OS 13.19033684 0.8591169
OS 13.20697892 0.86189058
OS 13.24026308 0.86882478
OS 13.27632092 0.87575898
OS 13.30821824 0.88408002
OS 13.32347348 0.88824054
OS 13.33734188 0.89240106
OS 13.33734188 0.8937879
OS 13.33734188 0.89656158
OS 13.33872872 0.90488262
OS 13.33872872 0.9145905
OS 13.33872872 0.92013786
OS 13.33872872 0.92291154
OS 13.33872872 0.92429838
OS 13.33872872 0.92568522
OS 13.33872872 0.93400626
OS 13.33734188 0.94787466
OS 13.3345682 0.9631299
OS 13.33040768 0.97977198
OS 13.32347348 0.99641406
OS 13.31515244 1.0116693
OS 13.30405772 1.02415086
OS 13.30267088 1.0255377
OS 13.29573668 1.03108506
OS 13.28464196 1.03663242
OS 13.27077356 1.04495346
OS 13.2513578 1.05188766
OS 13.22916836 1.05882186
OS 13.20143156 1.06298238
OS 13.16953424 1.06436922
OS 13.15566584 1.06436922
OS 13.14179744 1.06298238
OS 13.12238168 1.0602087
OS 13.10296592 1.05743502
OS 13.08216332 1.05188766
OS 13.06274756 1.04495346
OS 13.04610548 1.03524558
OS 13.04471864 1.03385874
OS 13.03917128 1.02969822
OS 13.03223708 1.02276402
OS 13.02391604 1.0116693
OS 13.015595 0.9978009
OS 13.00588712 0.97977198
OS 12.99756608 0.95758254
OS 12.98924504 0.93261942
OS 12.87413732 0.94787466
OS 12.87413732 0.9492615
OS 12.87552416 0.95064834
OS 12.87552416 0.95480886
OS 12.876911 0.96035622
OS 12.88107152 0.97283778
OS 12.88661888 0.9908667
OS 12.89355308 1.00889562
OS 12.90187412 1.02831138
OS 12.91296884 1.04772714
OS 12.9254504 1.06575606
OS 12.92683724 1.0671429
OS 12.9323846 1.07269026
OS 12.94070564 1.0810113
OS 12.95180036 1.09210602
OS 12.9670556 1.10320074
OS 12.98508452 1.11429546
OS 13.00588712 1.12677702
OS 13.0294634 1.1364849
OS 13.03085024 1.1364849
OS 13.03223708 1.13787174
OS 13.0363976 1.13925858
OS 13.04194496 1.14064542
OS 13.05581336 1.14480594
OS 13.07522912 1.14896646
OS 13.09741856 1.15312698
OS 13.12515536 1.1572875
OS 13.154279 1.16006118
OS 13.18756316 1.16144802
OS 13.2028184 1.16144802
OS 13.21807364 1.16006118
OE
OB 15.76015136 1.16006372 I
OS 15.78095396 1.15867688
OS 15.8031434 1.1559032
OS 15.82671968 1.15035584
OS 15.8516828 1.14480848
OS 15.87525908 1.13648744
OS 15.87664592 1.13648744
OS 15.87803276 1.1351006
OS 15.88496696 1.13232692
OS 15.89606168 1.12677956
OS 15.90993008 1.11984536
OS 15.92518532 1.11013748
OS 15.94044056 1.09904276
OS 15.95430896 1.0865612
OS 15.96679052 1.0726928
OS 15.96817736 1.07130596
OS 15.97095104 1.0657586
OS 15.9764984 1.05605072
OS 15.9834326 1.044956
OS 15.9903668 1.02831392
OS 15.997301 1.010285
OS 16.00284836 0.9894824
OS 16.00839572 0.96590612
OS 15.893288 0.95065088
OS 15.893288 0.95342456
OS 15.89190116 0.95897192
OS 15.88912748 0.9686798
OS 15.88496696 0.98116136
OS 15.87803276 0.99364292
OS 15.86971172 1.00751132
OS 15.86000384 1.02137972
OS 15.84613544 1.03386128
OS 15.8447486 1.03524812
OS 15.83920124 1.0380218
OS 15.8308802 1.04356916
OS 15.81839864 1.04911652
OS 15.80453024 1.05466388
OS 15.78650132 1.06021124
OS 15.76431188 1.06298492
OS 15.7407356 1.06437176
OS 15.7268672 1.06437176
OS 15.7129988 1.06298492
OS 15.69496988 1.06159808
OS 15.67694096 1.05743756
OS 15.6575252 1.05327704
OS 15.63949628 1.04634284
OS 15.62424104 1.03663496
OS 15.6228542 1.03524812
OS 15.61869368 1.03247444
OS 15.61314632 1.02692708
OS 15.60759896 1.01860604
OS 15.60066476 1.010285
OS 15.5951174 0.99919028
OS 15.59095688 0.98670872
OS 15.58957004 0.97422716
OS 15.58957004 0.97284032
OS 15.58957004 0.97006664
OS 15.59095688 0.96590612
OS 15.59095688 0.96035876
OS 15.5951174 0.94649036
OS 15.60343844 0.93262196
OS 15.60482528 0.93123512
OS 15.60621212 0.92984828
OS 15.6089858 0.92568776
OS 15.61453316 0.92152724
OS 15.62008052 0.91736672
OS 15.62840156 0.91181936
OS 15.63810944 0.90765884
OS 15.64920416 0.90211148
OS 15.650591 0.90211148
OS 15.65336468 0.90072464
OS 15.65891204 0.8993378
OS 15.66861992 0.89517728
OS 15.68248832 0.89101676
OS 15.70051724 0.88685624
OS 15.71161196 0.88269572
OS 15.72409352 0.87992204
OS 15.73796192 0.87576152
OS 15.75321716 0.871601
OS 15.754604 0.871601
OS 15.75876452 0.87021416
OS 15.76569872 0.86882732
OS 15.77401976 0.86605364
OS 15.78372764 0.86327996
OS 15.7962092 0.86050628
OS 15.82255916 0.85218524
OS 15.8516828 0.8438642
OS 15.88080644 0.83415632
OS 15.9071564 0.82444844
OS 15.91825112 0.82028792
OS 15.927959 0.8161274
OS 15.93073268 0.81474056
OS 15.93628004 0.81196688
OS 15.94460108 0.80780636
OS 15.95708264 0.80087216
OS 15.9695642 0.79255112
OS 15.98204576 0.7814564
OS 15.99452732 0.76897484
OS 16.00562204 0.75510644
OS 16.00700888 0.7537196
OS 16.00978256 0.74817224
OS 16.01532992 0.7398512
OS 16.02087728 0.72736964
OS 16.0250378 0.7121144
OS 16.03058516 0.69547232
OS 16.03335884 0.67605656
OS 16.03474568 0.65386712
OS 16.03474568 0.65109344
OS 16.03474568 0.64415924
OS 16.03335884 0.63306452
OS 16.03058516 0.61780928
OS 16.02642464 0.6011672
OS 16.01949044 0.58313828
OS 16.0111694 0.56233568
OS 16.00007468 0.54291992
OS 15.99868784 0.54014624
OS 15.99314048 0.53459888
OS 15.98620628 0.524891
OS 15.97511156 0.51379628
OS 15.95985632 0.50131472
OS 15.94321424 0.48744632
OS 15.92379848 0.47496476
OS 15.9002222 0.4624832
OS 15.89883536 0.4624832
OS 15.89744852 0.46109636
OS 15.88912748 0.45832268
OS 15.87525908 0.45416216
OS 15.85723016 0.4486148
OS 15.83504072 0.44306744
OS 15.8100776 0.43890692
OS 15.78372764 0.43613324
OS 15.75321716 0.4347464
OS 15.7407356 0.4347464
OS 15.73102772 0.43613324
OS 15.719933 0.43613324
OS 15.7060646 0.43752008
OS 15.6921962 0.43890692
OS 15.67694096 0.4416806
OS 15.6436568 0.4486148
OS 15.6089858 0.45832268
OS 15.57570164 0.47219108
OS 15.5604464 0.48051212
OS 15.546578 0.49022
OS 15.54519116 0.49160684
OS 15.54380432 0.49299368
OS 15.53548328 0.50131472
OS 15.52300172 0.51379628
OS 15.50913332 0.53321204
OS 15.49387808 0.55678832
OS 15.47862284 0.58452512
OS 15.46614128 0.61919612
OS 15.4564334 0.65802764
OS 15.57292796 0.67605656
OS 15.57292796 0.67466972
OS 15.57292796 0.67328288
OS 15.57570164 0.66496184
OS 15.57847532 0.65109344
OS 15.58402268 0.6358382
OS 15.59095688 0.61919612
OS 15.59927792 0.6011672
OS 15.61175948 0.58313828
OS 15.62701472 0.56788304
OS 15.6297884 0.5664962
OS 15.63533576 0.56233568
OS 15.64643048 0.55678832
OS 15.66029888 0.54985412
OS 15.6783278 0.54291992
OS 15.6991304 0.53737256
OS 15.72409352 0.53321204
OS 15.75321716 0.5318252
OS 15.76708556 0.5318252
OS 15.78095396 0.53321204
OS 15.79898288 0.53598572
OS 15.81839864 0.54014624
OS 15.83920124 0.5456936
OS 15.85723016 0.5526278
OS 15.87387224 0.56372252
OS 15.87525908 0.56510936
OS 15.88080644 0.56926988
OS 15.8863538 0.57620408
OS 15.89467484 0.58591196
OS 15.90160904 0.59700668
OS 15.90854324 0.61087508
OS 15.91270376 0.62474348
OS 15.9140906 0.64138556
OS 15.9140906 0.6427724
OS 15.9140906 0.64831976
OS 15.91270376 0.65525396
OS 15.90993008 0.66496184
OS 15.90576956 0.67466972
OS 15.89883536 0.6843776
OS 15.89051432 0.69547232
OS 15.87803276 0.70379336
OS 15.87664592 0.7051802
OS 15.8724854 0.70656704
OS 15.8655512 0.71072756
OS 15.85445648 0.71488808
OS 15.8378144 0.72043544
OS 15.82810652 0.72459596
OS 15.8170118 0.72736964
OS 15.80453024 0.73153016
OS 15.79066184 0.73569068
OS 15.7754066 0.7398512
OS 15.75737768 0.74401172
OS 15.75599084 0.74401172
OS 15.75183032 0.74539856
OS 15.74489612 0.7467854
OS 15.73657508 0.74955908
OS 15.72548036 0.75233276
OS 15.7129988 0.75649328
OS 15.68664884 0.76342748
OS 15.65613836 0.77313536
OS 15.62701472 0.7814564
OS 15.59927792 0.79116428
OS 15.58679636 0.79671164
OS 15.57708848 0.80087216
OS 15.5743148 0.802259
OS 15.56876744 0.80503268
OS 15.5604464 0.81058004
OS 15.54935168 0.81751424
OS 15.53687012 0.82722212
OS 15.52438856 0.83831684
OS 15.511907 0.8507984
OS 15.50081228 0.86605364
OS 15.49942544 0.86744048
OS 15.49665176 0.87298784
OS 15.49249124 0.88269572
OS 15.48833072 0.89379044
OS 15.4841702 0.90765884
OS 15.48000968 0.92430092
OS 15.477236 0.940943
OS 15.47584916 0.96035876
OS 15.47584916 0.96313244
OS 15.47584916 0.9686798
OS 15.477236 0.97700084
OS 15.47862284 0.9894824
OS 15.48139652 1.00196396
OS 15.4841702 1.0172192
OS 15.48971756 1.0310876
OS 15.49665176 1.04634284
OS 15.4980386 1.04772968
OS 15.50081228 1.05327704
OS 15.5049728 1.06021124
OS 15.511907 1.06991912
OS 15.52022804 1.079627
OS 15.52993592 1.09210856
OS 15.54103064 1.10320328
OS 15.55489904 1.11291116
OS 15.55628588 1.114298
OS 15.5604464 1.11568484
OS 15.56599376 1.11984536
OS 15.5743148 1.12400588
OS 15.58540952 1.12955324
OS 15.59789108 1.1351006
OS 15.61314632 1.14064796
OS 15.6297884 1.14619532
OS 15.63256208 1.14758216
OS 15.63810944 1.148969
OS 15.64781732 1.15174268
OS 15.66029888 1.15451636
OS 15.67555412 1.15729004
OS 15.6921962 1.15867688
OS 15.71161196 1.16145056
OS 15.74489612 1.16145056
OS 15.76015136 1.16006372
OE
OB 15.06534452 1.16006372 I
OS 15.07643924 1.15867688
OS 15.09030764 1.1559032
OS 15.10556288 1.15312952
OS 15.1235918 1.148969
OS 15.14023388 1.14480848
OS 15.15964964 1.13787428
OS 15.17767856 1.13094008
OS 15.19709432 1.1212322
OS 15.21651008 1.11013748
OS 15.23592584 1.09765592
OS 15.25395476 1.08240068
OS 15.27059684 1.0657586
OS 15.27198368 1.06437176
OS 15.27475736 1.06159808
OS 15.27891788 1.05605072
OS 15.28446524 1.04772968
OS 15.29139944 1.0380218
OS 15.29833364 1.02692708
OS 15.30665468 1.01305868
OS 15.31497572 0.9964166
OS 15.32329676 0.97838768
OS 15.3316178 0.95897192
OS 15.338552 0.93678248
OS 15.3454862 0.9132062
OS 15.35103356 0.88685624
OS 15.35519408 0.85911944
OS 15.35796776 0.8299958
OS 15.3593546 0.79809848
OS 15.3593546 0.79671164
OS 15.3593546 0.79116428
OS 15.3593546 0.7814564
OS 15.35796776 0.767588
OS 14.83790276 0.767588
OS 14.83790276 0.76620116
OS 14.83790276 0.76204064
OS 14.8392896 0.75649328
OS 14.8392896 0.74817224
OS 14.84067644 0.73846436
OS 14.84345012 0.72736964
OS 14.84761064 0.70240652
OS 14.85593168 0.67466972
OS 14.8670264 0.64415924
OS 14.88228164 0.61642244
OS 14.9016974 0.59145932
OS 14.90308424 0.59145932
OS 14.90447108 0.58868564
OS 14.91279212 0.58175144
OS 14.92527368 0.57204356
OS 14.94191576 0.56233568
OS 14.9641052 0.55124096
OS 14.98906832 0.54153308
OS 15.01680512 0.53459888
OS 15.03206036 0.53321204
OS 15.04870244 0.5318252
OS 15.05979716 0.5318252
OS 15.07227872 0.53321204
OS 15.08753396 0.53598572
OS 15.10417604 0.54014624
OS 15.1235918 0.5456936
OS 15.14162072 0.55401464
OS 15.15964964 0.56510936
OS 15.16103648 0.5664962
OS 15.16797068 0.57204356
OS 15.17629172 0.5803646
OS 15.1859996 0.59145932
OS 15.19709432 0.60671456
OS 15.20957588 0.62613032
OS 15.22205744 0.64831976
OS 15.23315216 0.67466972
OS 15.35519408 0.65941448
OS 15.35519408 0.65802764
OS 15.35380724 0.65525396
OS 15.3524204 0.6497066
OS 15.34964672 0.64138556
OS 15.3454862 0.63306452
OS 15.34132568 0.6219698
OS 15.33023096 0.59839352
OS 15.31636256 0.57204356
OS 15.2969468 0.54430676
OS 15.27475736 0.5179568
OS 15.24702056 0.49299368
OS 15.24563372 0.49299368
OS 15.24286004 0.49022
OS 15.23869952 0.48744632
OS 15.23315216 0.4832858
OS 15.22483112 0.47912528
OS 15.21651008 0.47496476
OS 15.20541536 0.4694174
OS 15.1929338 0.46387004
OS 15.1790654 0.45832268
OS 15.165197 0.45277532
OS 15.130526 0.44445428
OS 15.09169448 0.43752008
OS 15.04870244 0.4347464
OS 15.0334472 0.4347464
OS 15.02373932 0.43613324
OS 15.01125776 0.43752008
OS 14.99600252 0.44029376
OS 14.97936044 0.44306744
OS 14.96133152 0.44584112
OS 14.9225 0.45693584
OS 14.9016974 0.46525688
OS 14.88228164 0.47357792
OS 14.86147904 0.48467264
OS 14.84206328 0.4971542
OS 14.82403436 0.5110226
OS 14.80600544 0.52766468
OS 14.8046186 0.52905152
OS 14.80184492 0.5318252
OS 14.7976844 0.53737256
OS 14.79213704 0.5456936
OS 14.78520284 0.55540148
OS 14.77826864 0.5664962
OS 14.7699476 0.5803646
OS 14.76162656 0.59561984
OS 14.75330552 0.61364876
OS 14.74498448 0.63306452
OS 14.73805028 0.65525396
OS 14.73111608 0.67883024
OS 14.72556872 0.70379336
OS 14.7214082 0.73153016
OS 14.71863452 0.7606538
OS 14.71724768 0.79116428
OS 14.71724768 0.79255112
OS 14.71724768 0.79948532
OS 14.71724768 0.80780636
OS 14.71863452 0.82028792
OS 14.72002136 0.83554316
OS 14.7214082 0.85218524
OS 14.72418188 0.871601
OS 14.7283424 0.89101676
OS 14.73943712 0.93539564
OS 14.74637132 0.95758508
OS 14.75469236 0.98116136
OS 14.76578708 1.0033508
OS 14.77826864 1.0241534
OS 14.79213704 1.044956
OS 14.80739228 1.06437176
OS 14.80877912 1.0657586
OS 14.8115528 1.06853228
OS 14.81710016 1.0726928
OS 14.82403436 1.079627
OS 14.8323554 1.0865612
OS 14.84345012 1.09488224
OS 14.85593168 1.10459012
OS 14.87118692 1.11291116
OS 14.88644216 1.12261904
OS 14.90447108 1.13094008
OS 14.92388684 1.13926112
OS 14.94468944 1.14619532
OS 14.96687888 1.15312952
OS 14.99045516 1.15729004
OS 15.01541828 1.16006372
OS 15.04176824 1.16145056
OS 15.05563664 1.16145056
OS 15.06534452 1.16006372
OE
OB 14.38440608 1.16006372 I
OS 14.39411396 1.16006372
OS 14.40382184 1.15867688
OS 14.42739812 1.15451636
OS 14.45236124 1.14758216
OS 14.4787112 1.13648744
OS 14.50506116 1.12261904
OS 14.5272506 1.10320328
OS 14.53002428 1.1004296
OS 14.53557164 1.09210856
OS 14.54527952 1.079627
OS 14.54944004 1.06991912
OS 14.5549874 1.06021124
OS 14.56053476 1.04772968
OS 14.56469528 1.03524812
OS 14.57024264 1.02137972
OS 14.57440316 1.00473764
OS 14.57717684 0.98809556
OS 14.57995052 0.9686798
OS 14.5827242 0.94926404
OS 14.5827242 0.9270746
OS 14.5827242 0.45000164
OS 14.4648428 0.45000164
OS 14.4648428 0.88685624
OS 14.4648428 0.88824308
OS 14.4648428 0.88962992
OS 14.4648428 0.89795096
OS 14.4648428 0.91043252
OS 14.46345596 0.92568776
OS 14.46206912 0.94232984
OS 14.46068228 0.95897192
OS 14.4579086 0.975614
OS 14.45374808 0.98809556
OS 14.45374808 0.9894824
OS 14.4509744 0.99364292
OS 14.44820072 0.99919028
OS 14.4440402 1.00612448
OS 14.43849284 1.01444552
OS 14.43155864 1.02276656
OS 14.4232376 1.0310876
OS 14.41214288 1.03940864
OS 14.41075604 1.04079548
OS 14.40659552 1.04218232
OS 14.40104816 1.044956
OS 14.39134028 1.04911652
OS 14.3816324 1.05327704
OS 14.36915084 1.05605072
OS 14.35666928 1.05743756
OS 14.34141404 1.0588244
OS 14.33447984 1.0588244
OS 14.32893248 1.05743756
OS 14.31506408 1.05605072
OS 14.298422 1.05327704
OS 14.27900624 1.04634284
OS 14.25820364 1.0380218
OS 14.23740104 1.02554024
OS 14.21798528 1.00889816
OS 14.21659844 1.00612448
OS 14.21105108 0.99919028
OS 14.20273004 0.98809556
OS 14.194409 0.97145348
OS 14.18470112 0.94926404
OS 14.17776692 0.92291408
OS 14.17221956 0.89101676
OS 14.16944588 0.85357208
OS 14.16944588 0.45000164
OS 14.05156448 0.45000164
OS 14.05156448 0.90072464
OS 14.05156448 0.90211148
OS 14.05156448 0.90488516
OS 14.05156448 0.90765884
OS 14.05156448 0.9132062
OS 14.05017764 0.92846144
OS 14.04740396 0.94510352
OS 14.04463028 0.96451928
OS 14.03908292 0.98393504
OS 14.03214872 1.00196396
OS 14.02244084 1.01860604
OS 14.021054 1.01999288
OS 14.01689348 1.02554024
OS 14.00995928 1.0310876
OS 14.0002514 1.03940864
OS 13.98776984 1.04634284
OS 13.97112776 1.05327704
OS 13.951712 1.05743756
OS 13.92813572 1.0588244
OS 13.91981468 1.0588244
OS 13.9101068 1.05743502
OS 13.89901208 1.05604818
OS 13.88514368 1.05188766
OS 13.8685016 1.04772714
OS 13.85324636 1.04079294
OS 13.83660428 1.0324719
OS 13.83521744 1.03108506
OS 13.82967008 1.02692454
OS 13.82273588 1.02137718
OS 13.813028 1.01305614
OS 13.80332012 1.00196142
OS 13.79361224 0.98809302
OS 13.78390436 0.97283778
OS 13.77558332 0.95480886
OS 13.77419648 0.95203518
OS 13.77280964 0.94510098
OS 13.77003596 0.93400626
OS 13.76587544 0.91875102
OS 13.76171492 0.89794842
OS 13.75894124 0.8729853
OS 13.7575544 0.84386166
OS 13.75616756 0.8105775
OS 13.75616756 0.4499991
OS 13.63828616 0.4499991
OS 13.63828616 1.14619278
OS 13.743686 1.14619278
OS 13.743686 1.0463403
OS 13.74507284 1.04911398
OS 13.74923336 1.05466134
OS 13.7575544 1.06436922
OS 13.76726228 1.07546394
OS 13.77974384 1.08933234
OS 13.79499908 1.10320074
OS 13.81164116 1.11706914
OS 13.83105692 1.1295507
OS 13.8338306 1.13093754
OS 13.8407648 1.13509806
OS 13.85185952 1.13925858
OS 13.86711476 1.14619278
OS 13.88514368 1.15174014
OS 13.90594628 1.15590066
OS 13.92952256 1.16006372
OS 13.95448568 1.16145056
OS 13.96696724 1.16145056
OS 13.98222248 1.16006372
OS 13.99886456 1.15729004
OS 14.01966716 1.15312952
OS 14.04046976 1.14758216
OS 14.06127236 1.13926112
OS 14.08068812 1.1281664
OS 14.0834618 1.12677956
OS 14.08900916 1.12261904
OS 14.0973302 1.11568484
OS 14.10842492 1.10459012
OS 14.11951964 1.09210856
OS 14.1320012 1.07685332
OS 14.14309592 1.0588244
OS 14.15141696 1.0380218
OS 14.1528038 1.03940864
OS 14.15557748 1.04356916
OS 14.159738 1.04911652
OS 14.1666722 1.05743756
OS 14.17499324 1.06714544
OS 14.18470112 1.07685332
OS 14.19579584 1.08794804
OS 14.20966424 1.1004296
OS 14.22491948 1.11152432
OS 14.24017472 1.12261904
OS 14.25820364 1.13232692
OS 14.2776194 1.1420348
OS 14.298422 1.15035584
OS 14.32061144 1.1559032
OS 14.34280088 1.16006372
OS 14.367764 1.16145056
OS 14.37747188 1.16145056
OS 14.38440608 1.16006372
OE
OB 9.81060776 1.16006118 I
OS 9.825863 1.15867434
OS 9.84389192 1.15590066
OS 9.86330768 1.15174014
OS 9.88411028 1.14619278
OS 9.90352604 1.13787174
OS 9.90629972 1.1364849
OS 9.91184708 1.13371122
OS 9.92155496 1.1295507
OS 9.93264968 1.1226165
OS 9.94651808 1.11429546
OS 9.95899964 1.10320074
OS 9.9714812 1.09210602
OS 9.98257592 1.07823762
OS 9.98396276 1.07685078
OS 9.98673644 1.07130342
OS 9.99089696 1.06436922
OS 9.99783116 1.05466134
OS 10.00337852 1.04079294
OS 10.00892588 1.02692454
OS 10.01586008 1.01028246
OS 10.0200206 0.99225354
OS 10.0200206 0.9908667
OS 10.02140744 0.98531934
OS 10.02279428 0.9769983
OS 10.02418112 0.96590358
OS 10.02418112 0.9492615
OS 10.02556796 0.92984574
OS 10.0269548 0.90626946
OS 10.0269548 0.87714582
OS 10.0269548 0.4499991
OS 9.9090734 0.4499991
OS 9.9090734 0.87159846
OS 9.9090734 0.8729853
OS 9.9090734 0.87437214
OS 9.9090734 0.88408002
OS 9.9090734 0.89656158
OS 9.90768656 0.91181682
OS 9.90629972 0.92984574
OS 9.90352604 0.94787466
OS 9.89936552 0.96451674
OS 9.895205 0.97977198
OS 9.895205 0.98115882
OS 9.89243132 0.98531934
OS 9.8882708 0.99225354
OS 9.88411028 1.00057458
OS 9.87717608 1.00889562
OS 9.86885504 1.0186035
OS 9.85776032 1.02831138
OS 9.84527876 1.03663242
OS 9.84389192 1.03801926
OS 9.8397314 1.04079294
OS 9.83141036 1.04356662
OS 9.82170248 1.04772714
OS 9.81060776 1.05188766
OS 9.79673936 1.05604818
OS 9.78009728 1.05743502
OS 9.7634552 1.05882186
OS 9.756521 1.05882186
OS 9.75097364 1.05743502
OS 9.73710524 1.05604818
OS 9.71907632 1.0532745
OS 9.69966056 1.0463403
OS 9.67747112 1.03801926
OS 9.65528168 1.02692454
OS 9.63447908 1.01028246
OS 9.6317054 1.00750878
OS 9.62615804 1.00057458
OS 9.62199752 0.99502722
OS 9.617837 0.98809302
OS 9.61228964 0.97977198
OS 9.60812912 0.9700641
OS 9.60258176 0.95896938
OS 9.5970344 0.94510098
OS 9.59287388 0.92984574
OS 9.58871336 0.91320366
OS 9.58593968 0.89517474
OS 9.583166 0.87575898
OS 9.58039232 0.8521827
OS 9.58039232 0.82860642
OS 9.58039232 0.4499991
OS 9.46251092 0.4499991
OS 9.46251092 1.14619278
OS 9.56791076 1.14619278
OS 9.56791076 1.0463403
OS 9.5692976 1.04772714
OS 9.57207128 1.05188766
OS 9.5762318 1.05743502
OS 9.58177916 1.06436922
OS 9.5901002 1.07269026
OS 9.59980808 1.08239814
OS 9.6109028 1.09349286
OS 9.6247712 1.10458758
OS 9.6386396 1.11429546
OS 9.65528168 1.12539018
OS 9.6733106 1.13509806
OS 9.69272636 1.1434191
OS 9.7149158 1.1503533
OS 9.73710524 1.15590066
OS 9.76206836 1.16006118
OS 9.78841832 1.16144802
OS 9.79951304 1.16144802
OS 9.81060776 1.16006118
OE
OB 8.23515752 0.4499991 I
OS 8.11727612 0.4499991
OS 8.11727612 1.40969238
OS 8.23515752 1.40969238
OS 8.23515752 0.4499991
OE
OB 8.5361018 1.2751689 I
OS 8.4182204 1.2751689
OS 8.4182204 1.40969238
OS 8.5361018 1.40969238
OS 8.5361018 1.2751689
OE
OB 7.18115912 0.7551039 I
OS 7.18115912 0.75371706
OS 7.18115912 0.74955654
OS 7.18115912 0.74400918
OS 7.18115912 0.73568814
OS 7.17977228 0.72459342
OS 7.17977228 0.7134987
OS 7.1769986 0.68714874
OS 7.17422492 0.65663826
OS 7.16867756 0.62474094
OS 7.16035652 0.5956173
OS 7.15064864 0.5678805
OS 7.15064864 0.56649366
OS 7.1492618 0.56510682
OS 7.14510128 0.55678578
OS 7.13816708 0.54569106
OS 7.1284592 0.53043582
OS 7.1145908 0.51518058
OS 7.09933556 0.4985385
OS 7.0799198 0.48189642
OS 7.05773036 0.46802802
OS 7.05495668 0.46664118
OS 7.04663564 0.46248066
OS 7.03415408 0.4569333
OS 7.01612516 0.45138594
OS 6.99393572 0.44445174
OS 6.9689726 0.43890438
OS 6.9412358 0.43474386
OS 6.91072532 0.43335702
OS 6.89824376 0.43335702
OS 6.88992272 0.43474386
OS 6.878828 0.4361307
OS 6.86773328 0.43751754
OS 6.83860964 0.4430649
OS 6.80809916 0.45138594
OS 6.77620184 0.4638675
OS 6.75955976 0.47218854
OS 6.74430452 0.48189642
OS 6.73043612 0.49299114
OS 6.71656772 0.5054727
OS 6.71518088 0.50685954
OS 6.71379404 0.50824638
OS 6.71102036 0.51379374
OS 6.70685984 0.5193411
OS 6.70131248 0.5262753
OS 6.69576512 0.53598318
OS 6.69021776 0.5470779
OS 6.68328356 0.55955946
OS 6.6777362 0.57342786
OS 6.67218884 0.59006994
OS 6.66664148 0.60671202
OS 6.66109412 0.62612778
OS 6.65832044 0.64693038
OS 6.65415992 0.67050666
OS 6.65277308 0.69408294
OS 6.65277308 0.7204329
OS 6.7678808 0.73707498
OS 6.7678808 0.73568814
OS 6.7678808 0.73291446
OS 6.7678808 0.7273671
OS 6.76926764 0.71904606
OS 6.77065448 0.71072502
OS 6.77065448 0.70101714
OS 6.774815 0.67744086
OS 6.77897552 0.65247774
OS 6.78729656 0.62751462
OS 6.7956176 0.60532518
OS 6.80116496 0.5956173
OS 6.80809916 0.58729626
OS 6.809486 0.58590942
OS 6.81503336 0.5817489
OS 6.8233544 0.5748147
OS 6.83444912 0.5678805
OS 6.84970436 0.55955946
OS 6.86634644 0.5540121
OS 6.88714904 0.54846474
OS 6.90933848 0.5470779
OS 6.91765952 0.5470779
OS 6.92598056 0.54846474
OS 6.93846212 0.54985158
OS 6.95094368 0.55262526
OS 6.96481208 0.55539894
OS 6.97868048 0.5609463
OS 6.99254888 0.5678805
OS 6.99393572 0.56926734
OS 6.99809624 0.57204102
OS 7.0036436 0.57758838
OS 7.01196464 0.58313574
OS 7.01889884 0.59284362
OS 7.02721988 0.6025515
OS 7.03415408 0.61364622
OS 7.03970144 0.62751462
OS 7.03970144 0.62890146
OS 7.04247512 0.63444882
OS 7.04386196 0.6441567
OS 7.04663564 0.65663826
OS 7.04940932 0.67328034
OS 7.05079616 0.69408294
OS 7.05356984 0.71904606
OS 7.05356984 0.7481697
OS 7.05356984 1.40969238
OS 7.18115912 1.40969238
OS 7.18115912 0.7551039
OE
OB 7.93560008 0.4499991 I
OS 7.83020024 0.4499991
OS 7.83020024 0.55123842
OS 7.8288134 0.54985158
OS 7.82603972 0.54569106
OS 7.8218792 0.5401437
OS 7.814945 0.5332095
OS 7.80662396 0.52488846
OS 7.79691608 0.51379374
OS 7.78582136 0.50408586
OS 7.77195296 0.49299114
OS 7.75669772 0.48189642
OS 7.74005564 0.47218854
OS 7.72202672 0.46248066
OS 7.70261096 0.45277278
OS 7.68042152 0.44583858
OS 7.65823208 0.44029122
OS 7.63326896 0.4361307
OS 7.60830584 0.43474386
OS 7.59859796 0.43474386
OS 7.5861164 0.4361307
OS 7.57086116 0.43751754
OS 7.55283224 0.44029122
OS 7.53341648 0.44445174
OS 7.51400072 0.4499991
OS 7.49319812 0.45832014
OS 7.49042444 0.45970698
OS 7.48487708 0.46248066
OS 7.4751692 0.46802802
OS 7.46407448 0.47496222
OS 7.45020608 0.48328326
OS 7.43772452 0.49299114
OS 7.42524296 0.50408586
OS 7.41414824 0.51656742
OS 7.4127614 0.51795426
OS 7.40998772 0.52350162
OS 7.4058272 0.53043582
OS 7.40027984 0.54153054
OS 7.39334564 0.5540121
OS 7.38779828 0.56926734
OS 7.38225092 0.58590942
OS 7.3780904 0.60393834
OS 7.3780904 0.60532518
OS 7.37670356 0.61087254
OS 7.37531672 0.61919358
OS 7.37531672 0.6302883
OS 7.37392988 0.64693038
OS 7.37254304 0.6649593
OS 7.3711562 0.68853558
OS 7.3711562 0.71488554
OS 7.3711562 1.14619278
OS 7.4890376 1.14619278
OS 7.4890376 0.75926442
OS 7.4890376 0.75787758
OS 7.4890376 0.7551039
OS 7.4890376 0.75094338
OS 7.4890376 0.74400918
OS 7.4890376 0.72875394
OS 7.49042444 0.70933818
OS 7.49042444 0.68853558
OS 7.49181128 0.66773298
OS 7.49319812 0.64970406
OS 7.4959718 0.63444882
OS 7.4959718 0.63306198
OS 7.49874548 0.62751462
OS 7.50151916 0.61919358
OS 7.50567968 0.60809886
OS 7.51261388 0.59700414
OS 7.52093492 0.58452258
OS 7.5306428 0.57342786
OS 7.54312436 0.56233314
OS 7.5445112 0.5609463
OS 7.55005856 0.55817262
OS 7.55699276 0.5540121
OS 7.56808748 0.54985158
OS 7.58056904 0.54430422
OS 7.59582428 0.5401437
OS 7.61246636 0.53737002
OS 7.63188212 0.53598318
OS 7.64159 0.53598318
OS 7.65129788 0.53737002
OS 7.66377944 0.53875686
OS 7.67903468 0.54291738
OS 7.69567676 0.5470779
OS 7.71370568 0.5540121
OS 7.7317346 0.56233314
OS 7.73450828 0.56371998
OS 7.74005564 0.5678805
OS 7.74837668 0.57342786
OS 7.75808456 0.5817489
OS 7.76917928 0.59284362
OS 7.780274 0.60532518
OS 7.78998188 0.61919358
OS 7.79830292 0.63583566
OS 7.79968976 0.63860934
OS 7.8010766 0.6441567
OS 7.80385028 0.65525142
OS 7.8080108 0.67050666
OS 7.81217132 0.68992242
OS 7.814945 0.7134987
OS 7.81633184 0.7412355
OS 7.81771868 0.77313282
OS 7.81771868 1.14619278
OS 7.93560008 1.14619278
OS 7.93560008 0.4499991
OE
OB 8.5361018 0.4499991 I
OS 8.4182204 0.4499991
OS 8.4182204 1.14619278
OS 8.5361018 1.14619278
OS 8.5361018 0.4499991
OE
OB 9.04091156 1.16006118 I
OS 9.06171416 1.15867434
OS 9.08529044 1.15590066
OS 9.10886672 1.15174014
OS 9.132443 1.14619278
OS 9.15463244 1.13925858
OS 9.15740612 1.13787174
OS 9.16434032 1.13509806
OS 9.1740482 1.13093754
OS 9.18652976 1.12539018
OS 9.20039816 1.11706914
OS 9.21426656 1.1087481
OS 9.22674812 1.09765338
OS 9.23784284 1.08655866
OS 9.23922968 1.08517182
OS 9.24200336 1.0810113
OS 9.24616388 1.0740771
OS 9.25171124 1.06575606
OS 9.25864544 1.0532745
OS 9.2641928 1.04079294
OS 9.26974016 1.0255377
OS 9.27390068 1.00750878
OS 9.27390068 1.00612194
OS 9.27528752 1.00196142
OS 9.27667436 0.99364038
OS 9.2780612 0.98254566
OS 9.2780612 0.96729042
OS 9.27944804 0.9492615
OS 9.28083488 0.92568522
OS 9.28083488 0.89933526
OS 9.28083488 0.7412355
OS 9.28083488 0.73984866
OS 9.28083488 0.7343013
OS 9.28083488 0.72598026
OS 9.28083488 0.71488554
OS 9.28083488 0.70240398
OS 9.28083488 0.68714874
OS 9.28222172 0.65386458
OS 9.28222172 0.61919358
OS 9.28360856 0.58452258
OS 9.2849954 0.56926734
OS 9.2849954 0.55539894
OS 9.28638224 0.54291738
OS 9.28776908 0.5332095
OS 9.28776908 0.53182266
OS 9.28915592 0.5262753
OS 9.29054276 0.51795426
OS 9.29470328 0.50685954
OS 9.29747696 0.49437798
OS 9.30302432 0.48050958
OS 9.30995852 0.46525434
OS 9.31689272 0.4499991
OS 9.19346396 0.4499991
OS 9.19207712 0.45138594
OS 9.19069028 0.4569333
OS 9.1879166 0.4638675
OS 9.18375608 0.47496222
OS 9.17959556 0.48744378
OS 9.17682188 0.50269902
OS 9.1740482 0.5193411
OS 9.17127452 0.53737002
OS 9.16988768 0.53737002
OS 9.16850084 0.53459634
OS 9.1601798 0.52766214
OS 9.14769824 0.51795426
OS 9.13105616 0.5054727
OS 9.11025356 0.49299114
OS 9.08945096 0.47912274
OS 9.06726152 0.46664118
OS 9.04368524 0.4569333
OS 9.04091156 0.45554646
OS 9.03259052 0.45415962
OS 9.02010896 0.4499991
OS 9.00485372 0.44583858
OS 8.98543796 0.44167806
OS 8.96324852 0.43890438
OS 8.9382854 0.4361307
OS 8.91332228 0.43474386
OS 8.90222756 0.43474386
OS 8.89390652 0.4361307
OS 8.88419864 0.4361307
OS 8.87310392 0.43751754
OS 8.8481408 0.44167806
OS 8.820404 0.44861226
OS 8.78989352 0.45832014
OS 8.76215672 0.47218854
OS 8.7371936 0.49021746
OS 8.73441992 0.49299114
OS 8.72748572 0.49992534
OS 8.71777784 0.5124069
OS 8.70668312 0.52904898
OS 8.6955884 0.54985158
OS 8.68588052 0.57342786
OS 8.67894632 0.6025515
OS 8.67755948 0.6164199
OS 8.67617264 0.63306198
OS 8.67617264 0.63583566
OS 8.67617264 0.64138302
OS 8.67755948 0.6510909
OS 8.67894632 0.66357246
OS 8.68172 0.6788277
OS 8.68588052 0.69408294
OS 8.69142788 0.71072502
OS 8.69836208 0.72598026
OS 8.69974892 0.7273671
OS 8.7025226 0.73291446
OS 8.70806996 0.7412355
OS 8.71500416 0.75094338
OS 8.7233252 0.7620381
OS 8.73441992 0.77313282
OS 8.74551464 0.78422754
OS 8.75938304 0.79393542
OS 8.76076988 0.79532226
OS 8.76631724 0.79809594
OS 8.77325144 0.8036433
OS 8.78434616 0.80919066
OS 8.79682772 0.81473802
OS 8.81208296 0.82167222
OS 8.8273382 0.82721958
OS 8.84536712 0.83276694
OS 8.84675396 0.83276694
OS 8.85230132 0.83415378
OS 8.86062236 0.83692746
OS 8.87171708 0.8383143
OS 8.88558548 0.84108798
OS 8.9036144 0.84386166
OS 8.924417 0.84802218
OS 8.94938012 0.85079586
OS 8.95076696 0.85079586
OS 8.95631432 0.8521827
OS 8.96324852 0.8521827
OS 8.9729564 0.85356954
OS 8.98405112 0.85495638
OS 8.99791952 0.85773006
OS 9.01317476 0.8591169
OS 9.02981684 0.86189058
OS 9.063101 0.86882478
OS 9.09915884 0.87575898
OS 9.13105616 0.88408002
OS 9.1463114 0.88824054
OS 9.1601798 0.89240106
OS 9.1601798 0.8937879
OS 9.1601798 0.89656158
OS 9.16156664 0.90488262
OS 9.16156664 0.9145905
OS 9.16156664 0.92013786
OS 9.16156664 0.92291154
OS 9.16156664 0.92429838
OS 9.16156664 0.92568522
OS 9.16156664 0.93400626
OS 9.1601798 0.94787466
OS 9.15740612 0.9631299
OS 9.1532456 0.97977198
OS 9.1463114 0.99641406
OS 9.13799036 1.0116693
OS 9.12689564 1.02415086
OS 9.1255088 1.0255377
OS 9.1185746 1.03108506
OS 9.10747988 1.03663242
OS 9.09361148 1.04495346
OS 9.07419572 1.05188766
OS 9.05200628 1.05882186
OS 9.02426948 1.06298238
OS 8.99237216 1.06436922
OS 8.97850376 1.06436922
OS 8.96463536 1.06298238
OS 8.9452196 1.0602087
OS 8.92580384 1.05743502
OS 8.90500124 1.05188766
OS 8.88558548 1.04495346
OS 8.8689434 1.03524558
OS 8.86755656 1.03385874
OS 8.8620092 1.02969822
OS 8.855075 1.02276402
OS 8.84675396 1.0116693
OS 8.83843292 0.9978009
OS 8.82872504 0.97977198
OS 8.820404 0.95758254
OS 8.81208296 0.93261942
OS 8.69697524 0.94787466
OS 8.69697524 0.9492615
OS 8.69836208 0.95064834
OS 8.69836208 0.95480886
OS 8.69974892 0.96035622
OS 8.70390944 0.97283778
OS 8.7094568 0.9908667
OS 8.716391 1.00889562
OS 8.72471204 1.02831138
OS 8.73580676 1.04772714
OS 8.74828832 1.06575606
OS 8.74967516 1.0671429
OS 8.75522252 1.07269026
OS 8.76354356 1.0810113
OS 8.77463828 1.09210602
OS 8.78989352 1.10320074
OS 8.80792244 1.11429546
OS 8.82872504 1.12677702
OS 8.85230132 1.1364849
OS 8.85368816 1.1364849
OS 8.855075 1.13787174
OS 8.85923552 1.13925858
OS 8.86478288 1.14064542
OS 8.87865128 1.14480594
OS 8.89806704 1.14896646
OS 8.92025648 1.15312698
OS 8.94799328 1.1572875
OS 8.97711692 1.16006118
OS 9.01040108 1.16144802
OS 9.02565632 1.16144802
OS 9.04091156 1.16006118
OE
OB 9.16156664 0.79948278 H
OS 9.1601798 0.79948278
OS 9.15879296 0.79809594
OS 9.15463244 0.7967091
OS 9.14908508 0.79532226
OS 9.14215088 0.79254858
OS 9.13382984 0.7897749
OS 9.12412196 0.78700122
OS 9.11302724 0.78422754
OS 9.10054568 0.78006702
OS 9.08529044 0.77729334
OS 9.0700352 0.77313282
OS 9.05200628 0.7689723
OS 9.03259052 0.76481178
OS 9.01317476 0.76065126
OS 8.99098532 0.75787758
OS 8.96740904 0.75371706
OS 8.96463536 0.75371706
OS 8.95631432 0.75233022
OS 8.94244592 0.74955654
OS 8.92719068 0.74678286
OS 8.9105486 0.74400918
OS 8.89390652 0.73984866
OS 8.87865128 0.73568814
OS 8.86478288 0.73014078
OS 8.86339604 0.73014078
OS 8.85923552 0.7273671
OS 8.85368816 0.72459342
OS 8.8481408 0.7204329
OS 8.83149872 0.70933818
OS 8.81763032 0.6926961
OS 8.81763032 0.69130926
OS 8.81485664 0.68853558
OS 8.8134698 0.68298822
OS 8.81069612 0.67605402
OS 8.80792244 0.66773298
OS 8.80514876 0.65941194
OS 8.80376192 0.64831722
OS 8.80237508 0.6372225
OS 8.80237508 0.63583566
OS 8.80237508 0.62890146
OS 8.80376192 0.62058042
OS 8.8065356 0.6094857
OS 8.81069612 0.59700414
OS 8.81763032 0.58452258
OS 8.82595136 0.57065418
OS 8.83704608 0.55817262
OS 8.83843292 0.55678578
OS 8.84398028 0.5540121
OS 8.85230132 0.54846474
OS 8.86339604 0.54291738
OS 8.87865128 0.53737002
OS 8.8966802 0.53182266
OS 8.9174828 0.52904898
OS 8.94244592 0.52766214
OS 8.95354064 0.52766214
OS 8.96740904 0.52904898
OS 8.98266428 0.53182266
OS 9.00208004 0.53459634
OS 9.0214958 0.5401437
OS 9.0422984 0.5470779
OS 9.063101 0.55678578
OS 9.06587468 0.55817262
OS 9.07142204 0.56233314
OS 9.08112992 0.56926734
OS 9.09222464 0.57897522
OS 9.1047062 0.59006994
OS 9.1185746 0.60393834
OS 9.12966932 0.62058042
OS 9.14076404 0.63860934
OS 9.14215088 0.63999618
OS 9.14353772 0.64554354
OS 9.1463114 0.65525142
OS 9.15047192 0.66773298
OS 9.15463244 0.68437506
OS 9.15740612 0.70379082
OS 9.15879296 0.7273671
OS 9.1601798 0.7551039
OS 9.16156664 0.79948278
OE
OB 13.33872872 0.79948278 H
OS 13.33734188 0.79948278
OS 13.33595504 0.79809594
OS 13.33179452 0.7967091
OS 13.32624716 0.79532226
OS 13.31931296 0.79254858
OS 13.31099192 0.7897749
OS 13.30128404 0.78700122
OS 13.29018932 0.78422754
OS 13.27770776 0.78006702
OS 13.26245252 0.77729334
OS 13.24719728 0.77313282
OS 13.22916836 0.7689723
OS 13.2097526 0.76481178
OS 13.19033684 0.76065126
OS 13.1681474 0.75787758
OS 13.14457112 0.75371706
OS 13.14179744 0.75371706
OS 13.1334764 0.75233022
OS 13.119608 0.74955654
OS 13.10435276 0.74678286
OS 13.08771068 0.74400918
OS 13.0710686 0.73984866
OS 13.05581336 0.73568814
OS 13.04194496 0.73014078
OS 13.04055812 0.73014078
OS 13.0363976 0.7273671
OS 13.03085024 0.72459342
OS 13.02530288 0.7204329
OS 13.0086608 0.70933818
OS 12.9947924 0.6926961
OS 12.9947924 0.69130926
OS 12.99201872 0.68853558
OS 12.99063188 0.68298822
OS 12.9878582 0.67605402
OS 12.98508452 0.66773298
OS 12.98231084 0.65941194
OS 12.980924 0.64831722
OS 12.97953716 0.6372225
OS 12.97953716 0.63583566
OS 12.97953716 0.62890146
OS 12.980924 0.62058042
OS 12.98369768 0.6094857
OS 12.9878582 0.59700414
OS 12.9947924 0.58452258
OS 13.00311344 0.57065418
OS 13.01420816 0.55817262
OS 13.015595 0.55678578
OS 13.02114236 0.5540121
OS 13.0294634 0.54846474
OS 13.04055812 0.54291738
OS 13.05581336 0.53737002
OS 13.07384228 0.53182266
OS 13.09464488 0.52904898
OS 13.119608 0.52766214
OS 13.13070272 0.52766214
OS 13.14457112 0.52904898
OS 13.15982636 0.53182266
OS 13.17924212 0.53459634
OS 13.19865788 0.5401437
OS 13.21946048 0.5470779
OS 13.24026308 0.55678578
OS 13.24303676 0.55817262
OS 13.24858412 0.56233314
OS 13.258292 0.56926734
OS 13.26938672 0.57897522
OS 13.28186828 0.59006994
OS 13.29573668 0.60393834
OS 13.3068314 0.62058042
OS 13.31792612 0.63860934
OS 13.31931296 0.63999618
OS 13.3206998 0.64554354
OS 13.32347348 0.65525142
OS 13.327634 0.66773298
OS 13.33179452 0.68437506
OS 13.3345682 0.70379082
OS 13.33595504 0.7273671
OS 13.33734188 0.7551039
OS 13.33872872 0.79948278
OE
OB 15.04315508 1.06437176 H
OS 15.03483404 1.06437176
OS 15.02928668 1.06298492
OS 15.01403144 1.06159808
OS 14.99600252 1.05743756
OS 14.97381308 1.05050336
OS 14.9502368 1.04079548
OS 14.92804736 1.02692708
OS 14.90585792 1.00889816
OS 14.90308424 1.00612448
OS 14.89753688 0.99919028
OS 14.887829 0.98670872
OS 14.87812112 0.97006664
OS 14.8670264 0.95065088
OS 14.85731852 0.92568776
OS 14.84899748 0.89656412
OS 14.84483696 0.8646668
OS 15.234539 0.8646668
OS 15.234539 0.86605364
OS 15.234539 0.86882732
OS 15.23315216 0.87298784
OS 15.23315216 0.8785352
OS 15.23037848 0.89517728
OS 15.22621796 0.9132062
OS 15.21928376 0.93539564
OS 15.21234956 0.95619824
OS 15.20125484 0.97700084
OS 15.18877328 0.99502976
OS 15.18877328 0.9964166
OS 15.1859996 0.99780344
OS 15.1790654 1.00612448
OS 15.16658384 1.0172192
OS 15.14994176 1.02970076
OS 15.12913916 1.04218232
OS 15.10417604 1.05327704
OS 15.0750524 1.06159808
OS 15.05979716 1.06298492
OS 15.04315508 1.06437176
OE
SE
S P 0
OB 13.71958902 -0.91785694 I
OS 13.72097586 -0.9164701
OS 13.7223627 -0.91369642
OS 13.72652322 -0.9095359
OS 13.73345742 -0.9026017
OS 13.74039162 -0.8956675
OS 13.74871266 -0.88734646
OS 13.75980738 -0.87902542
OS 13.7709021 -0.87070438
OS 13.7986389 -0.85267546
OS 13.83053622 -0.83880706
OS 13.84856514 -0.83187286
OS 13.8679809 -0.82771234
OS 13.8887835 -0.82493866
OS 13.9095861 -0.82355182
OS 13.92068082 -0.82355182
OS 13.93316238 -0.82493866
OS 13.94841762 -0.8263255
OS 13.96644654 -0.83048602
OS 13.98724914 -0.83464654
OS 14.00943858 -0.84158074
OS 14.03024118 -0.84990178
OS 14.03301486 -0.85128862
OS 14.03994906 -0.8540623
OS 14.05104378 -0.8609965
OS 14.06352534 -0.86931754
OS 14.07878058 -0.87902542
OS 14.09403582 -0.89150698
OS 14.1106779 -0.90676222
OS 14.1245463 -0.9234043
OS 14.12593314 -0.92479114
OS 14.13009366 -0.93172534
OS 14.13702786 -0.94143322
OS 14.1453489 -0.95391478
OS 14.15505678 -0.97055686
OS 14.16476466 -0.98997262
OS 14.17447254 -1.01216206
OS 14.18279358 -1.03573834
OS 14.18279358 -1.03712518
OS 14.18418042 -1.03851202
OS 14.18556726 -1.04267254
OS 14.1869541 -1.04683306
OS 14.18972778 -1.06070146
OS 14.1938883 -1.07873038
OS 14.19804882 -1.09953298
OS 14.20220934 -1.12310926
OS 14.20359618 -1.14945922
OS 14.20498302 -1.17719602
OS 14.20498302 -1.17858286
OS 14.20498302 -1.18551706
OS 14.20498302 -1.1938381
OS 14.20359618 -1.20631966
OS 14.20220934 -1.2215749
OS 14.2008225 -1.23821698
OS 14.19804882 -1.25763274
OS 14.1938883 -1.27843534
OS 14.18279358 -1.32281422
OS 14.17585938 -1.3463905
OS 14.16753834 -1.36857994
OS 14.15783046 -1.39215622
OS 14.1453489 -1.41295882
OS 14.1314805 -1.43376142
OS 14.11622526 -1.45317718
OS 14.11483842 -1.45456402
OS 14.11206474 -1.4573377
OS 14.10790422 -1.46149822
OS 14.10097002 -1.46843242
OS 14.09126214 -1.47536662
OS 14.08155426 -1.48368766
OS 14.07045954 -1.4920087
OS 14.05659114 -1.50171658
OS 14.0413359 -1.51003762
OS 14.02608066 -1.5197455
OS 13.98863598 -1.53500074
OS 13.96922022 -1.54193494
OS 13.94841762 -1.54609546
OS 13.92622818 -1.54886914
OS 13.90403874 -1.55025598
OS 13.89849138 -1.55025598
OS 13.89155718 -1.54886914
OS 13.88323614 -1.54886914
OS 13.87352826 -1.5474823
OS 13.8610467 -1.54470862
OS 13.8333099 -1.53777442
OS 13.81805466 -1.53222706
OS 13.80279942 -1.52529286
OS 13.78615734 -1.51697182
OS 13.7709021 -1.50726394
OS 13.75426002 -1.49478238
OS 13.73900478 -1.48091398
OS 13.72513638 -1.46565874
OS 13.71126798 -1.44762982
OS 13.71126798 -1.53500074
OS 13.60170762 -1.53500074
OS 13.60170762 -0.57530746
OS 13.71958902 -0.57530746
OS 13.71958902 -0.91785694
OE
OB 13.16346618 -0.82493866 I
OS 13.17594774 -0.8263255
OS 13.18981614 -0.82909918
OS 13.20507138 -0.83187286
OS 13.2231003 -0.83464654
OS 13.26054498 -0.8471281
OS 13.27996074 -0.8540623
OS 13.2993765 -0.86377018
OS 13.31879226 -0.87347806
OS 13.33820802 -0.88734646
OS 13.35623694 -0.90121486
OS 13.37426586 -0.91785694
OS 13.3756527 -0.91924378
OS 13.37842638 -0.92201746
OS 13.3825869 -0.92756482
OS 13.38813426 -0.93449902
OS 13.39506846 -0.9442069
OS 13.4033895 -0.95668846
OS 13.41171054 -0.97055686
OS 13.42003158 -0.9858121
OS 13.42835262 -1.00245418
OS 13.43667366 -1.02325678
OS 13.4449947 -1.04405938
OS 13.4519289 -1.06763566
OS 13.45747626 -1.09259878
OS 13.46163678 -1.11894874
OS 13.46441046 -1.14668554
OS 13.4657973 -1.17719602
OS 13.4657973 -1.17858286
OS 13.4657973 -1.18274338
OS 13.4657973 -1.18967758
OS 13.4657973 -1.19938546
OS 13.46441046 -1.21048018
OS 13.46302362 -1.22434858
OS 13.46302362 -1.23821698
OS 13.46024994 -1.25347222
OS 13.45608942 -1.28814322
OS 13.44776838 -1.32281422
OS 13.4380605 -1.35748522
OS 13.4241921 -1.38938254
OS 13.4241921 -1.39076938
OS 13.42280526 -1.39215622
OS 13.42003158 -1.39631674
OS 13.4172579 -1.4018641
OS 13.40755002 -1.4157325
OS 13.39506846 -1.43237458
OS 13.37842638 -1.45179034
OS 13.35762378 -1.4712061
OS 13.3340475 -1.49062186
OS 13.3063107 -1.50865078
OS 13.30492386 -1.50865078
OS 13.30353702 -1.51003762
OS 13.2993765 -1.5128113
OS 13.2924423 -1.51558498
OS 13.2855081 -1.51835866
OS 13.27718706 -1.52113234
OS 13.25638446 -1.52945338
OS 13.23280818 -1.53638758
OS 13.20368454 -1.54332178
OS 13.17317406 -1.54886914
OS 13.1398899 -1.55025598
OS 13.1260215 -1.55025598
OS 13.11492678 -1.54886914
OS 13.10244522 -1.5474823
OS 13.08857682 -1.54470862
OS 13.07193474 -1.54193494
OS 13.05529266 -1.53916126
OS 13.01784798 -1.52806654
OS 12.99704538 -1.5197455
OS 12.97762962 -1.51142446
OS 12.95821386 -1.50032974
OS 12.9387981 -1.48784818
OS 12.92076918 -1.47397978
OS 12.90274026 -1.4573377
OS 12.90135342 -1.45595086
OS 12.89857974 -1.45317718
OS 12.89441922 -1.44762982
OS 12.88887186 -1.43930878
OS 12.88193766 -1.4296009
OS 12.87500346 -1.41850618
OS 12.86668242 -1.40463778
OS 12.85836138 -1.3879957
OS 12.85004034 -1.36996678
OS 12.8417193 -1.34916418
OS 12.8347851 -1.32697474
OS 12.8278509 -1.30339846
OS 12.82230354 -1.2770485
OS 12.81814302 -1.2493117
OS 12.81536934 -1.21880122
OS 12.8139825 -1.1869039
OS 12.8139825 -1.18413022
OS 12.8139825 -1.17858286
OS 12.81536934 -1.16887498
OS 12.81536934 -1.15500658
OS 12.81675618 -1.13975134
OS 12.81952986 -1.12033558
OS 12.82230354 -1.10091982
OS 12.8278509 -1.07873038
OS 12.83339826 -1.05654094
OS 12.84033246 -1.03296466
OS 12.8486535 -1.00800154
OS 12.85974822 -0.98442526
OS 12.87084294 -0.96223582
OS 12.88609818 -0.94004638
OS 12.90135342 -0.91924378
OS 12.92076918 -0.90121486
OS 12.92215602 -0.89982802
OS 12.9249297 -0.89844118
OS 12.93047706 -0.89428066
OS 12.93741126 -0.8887333
OS 12.9457323 -0.88318594
OS 12.95682702 -0.87625174
OS 12.96792174 -0.86931754
OS 12.98179014 -0.86238334
OS 12.99704538 -0.85544914
OS 13.01368746 -0.84851494
OS 13.05113214 -0.83603338
OS 13.09412418 -0.8263255
OS 13.11631362 -0.82493866
OS 13.1398899 -0.82355182
OS 13.1537583 -0.82355182
OS 13.16346618 -0.82493866
OE
OB 12.3632595 -0.5766943 I
OS 12.37574106 -0.5766943
OS 12.4048647 -0.57808114
OS 12.43537518 -0.58224166
OS 12.46865934 -0.58640218
OS 12.49916982 -0.59333638
OS 12.51442506 -0.5974969
OS 12.52690662 -0.60165742
OS 12.52829346 -0.60165742
OS 12.5296803 -0.60304426
OS 12.53800134 -0.60720478
OS 12.5504829 -0.61275214
OS 12.56573814 -0.62246002
OS 12.58238022 -0.63494158
OS 12.60040914 -0.65158366
OS 12.61705122 -0.67099942
OS 12.6336933 -0.69318886
OS 12.6336933 -0.6945757
OS 12.63508014 -0.69596254
OS 12.6406275 -0.70428358
OS 12.64617486 -0.71815198
OS 12.6544959 -0.7361809
OS 12.6614301 -0.7569835
OS 12.6683643 -0.78194662
OS 12.67252482 -0.80829658
OS 12.67391166 -0.83742022
OS 12.67391166 -0.83880706
OS 12.67391166 -0.84158074
OS 12.67391166 -0.8471281
OS 12.67252482 -0.8540623
OS 12.67252482 -0.86377018
OS 12.67113798 -0.87347806
OS 12.66559062 -0.89705434
OS 12.65726958 -0.92479114
OS 12.64617486 -0.95391478
OS 12.62953278 -0.98303842
OS 12.61843806 -0.99690682
OS 12.60734334 -1.01077522
OS 12.6059565 -1.01216206
OS 12.60456966 -1.0135489
OS 12.60040914 -1.01770942
OS 12.59486178 -1.02186994
OS 12.58792758 -1.0274173
OS 12.57960654 -1.03296466
OS 12.56851182 -1.03989886
OS 12.5574171 -1.0482199
OS 12.5435487 -1.0551541
OS 12.52829346 -1.0620883
OS 12.51165138 -1.07040934
OS 12.49362246 -1.07734354
OS 12.47281986 -1.0828909
OS 12.45201726 -1.0898251
OS 12.42844098 -1.09398562
OS 12.40347786 -1.09814614
OS 12.40625154 -1.09953298
OS 12.4117989 -1.10230666
OS 12.42011994 -1.10785402
OS 12.43121466 -1.11340138
OS 12.45617778 -1.12865662
OS 12.46865934 -1.1383645
OS 12.47975406 -1.14668554
OS 12.48252774 -1.14945922
OS 12.48946194 -1.15639342
OS 12.50055666 -1.16748814
OS 12.51442506 -1.18135654
OS 12.5296803 -1.2007723
OS 12.54770922 -1.2215749
OS 12.56573814 -1.24653802
OS 12.5851539 -1.27427482
OS 12.75018786 -1.53500074
OS 12.5920881 -1.53500074
OS 12.46588566 -1.33529578
OS 12.46588566 -1.33390894
OS 12.46311198 -1.33113526
OS 12.4603383 -1.32697474
OS 12.45617778 -1.32142738
OS 12.4464699 -1.30617214
OS 12.43398834 -1.28675638
OS 12.4187331 -1.26595378
OS 12.40347786 -1.24376434
OS 12.38822262 -1.22296174
OS 12.37435422 -1.20354598
OS 12.37296738 -1.20215914
OS 12.36880686 -1.19661178
OS 12.36187266 -1.18829074
OS 12.35216478 -1.17858286
OS 12.33136218 -1.15778026
OS 12.32026746 -1.14807238
OS 12.30917274 -1.13975134
OS 12.3077859 -1.1383645
OS 12.30501222 -1.13697766
OS 12.29946486 -1.13420398
OS 12.29114382 -1.13004346
OS 12.28282278 -1.12588294
OS 12.2731149 -1.12172242
OS 12.25092546 -1.11478822
OS 12.24953862 -1.11478822
OS 12.24676494 -1.11340138
OS 12.24121758 -1.11340138
OS 12.23428338 -1.11201454
OS 12.2245755 -1.1106277
OS 12.21348078 -1.1106277
OS 12.19822554 -1.10924086
OS 12.03457842 -1.10924086
OS 12.03457842 -1.53500074
OS 11.90698914 -1.53500074
OS 11.90698914 -0.57530746
OS 12.35216478 -0.57530746
OS 12.3632595 -0.5766943
OE
OB 15.65145714 -0.82493612 I
OS 15.67225974 -0.82632296
OS 15.69444918 -0.82909664
OS 15.71802546 -0.834644
OS 15.74298858 -0.84019136
OS 15.76656486 -0.8485124
OS 15.7679517 -0.8485124
OS 15.76933854 -0.84989924
OS 15.77627274 -0.85267292
OS 15.78736746 -0.85822028
OS 15.80123586 -0.86515448
OS 15.8164911 -0.87486236
OS 15.83174634 -0.88595708
OS 15.84561474 -0.89843864
OS 15.8580963 -0.91230704
OS 15.85948314 -0.91369388
OS 15.86225682 -0.91924124
OS 15.86780418 -0.92894912
OS 15.87473838 -0.94004384
OS 15.88167258 -0.95668592
OS 15.88860678 -0.97471484
OS 15.89415414 -0.99551744
OS 15.8997015 -1.01909372
OS 15.78459378 -1.03434896
OS 15.78459378 -1.03157528
OS 15.78320694 -1.02602792
OS 15.78043326 -1.01632004
OS 15.77627274 -1.00383848
OS 15.76933854 -0.99135692
OS 15.7610175 -0.97748852
OS 15.75130962 -0.96362012
OS 15.73744122 -0.95113856
OS 15.73605438 -0.94975172
OS 15.73050702 -0.94697804
OS 15.72218598 -0.94143068
OS 15.70970442 -0.93588332
OS 15.69583602 -0.93033596
OS 15.6778071 -0.9247886
OS 15.65561766 -0.92201492
OS 15.63204138 -0.92062808
OS 15.61817298 -0.92063062
OS 15.60430458 -0.92201746
OS 15.58627566 -0.9234043
OS 15.56824674 -0.92756482
OS 15.54883098 -0.93172534
OS 15.53080206 -0.93865954
OS 15.51554682 -0.94836742
OS 15.51415998 -0.94975426
OS 15.50999946 -0.95252794
OS 15.5044521 -0.9580753
OS 15.49890474 -0.96639634
OS 15.49197054 -0.97471738
OS 15.48642318 -0.9858121
OS 15.48226266 -0.99829366
OS 15.48087582 -1.01077522
OS 15.48087582 -1.01216206
OS 15.48087582 -1.01493574
OS 15.48226266 -1.01909626
OS 15.48226266 -1.02464362
OS 15.48642318 -1.03851202
OS 15.49474422 -1.05238042
OS 15.49613106 -1.05376726
OS 15.4975179 -1.0551541
OS 15.50029158 -1.05931462
OS 15.50583894 -1.06347514
OS 15.5113863 -1.06763566
OS 15.51970734 -1.07318302
OS 15.52941522 -1.07734354
OS 15.54050994 -1.0828909
OS 15.54189678 -1.0828909
OS 15.54467046 -1.08427774
OS 15.55021782 -1.08566458
OS 15.5599257 -1.0898251
OS 15.5737941 -1.09398562
OS 15.59182302 -1.09814614
OS 15.60291774 -1.10230666
OS 15.6153993 -1.10508034
OS 15.6292677 -1.10923832
OS 15.64452294 -1.11339884
OS 15.64590978 -1.11339884
OS 15.6500703 -1.11478568
OS 15.6570045 -1.11617252
OS 15.66532554 -1.1189462
OS 15.67503342 -1.12171988
OS 15.68751498 -1.12449356
OS 15.71386494 -1.1328146
OS 15.74298858 -1.14113564
OS 15.77211222 -1.15084352
OS 15.79846218 -1.1605514
OS 15.8095569 -1.16471192
OS 15.81926478 -1.16887244
OS 15.82203846 -1.17025928
OS 15.82758582 -1.17303296
OS 15.83590686 -1.17719348
OS 15.84838842 -1.18412768
OS 15.86086998 -1.19244872
OS 15.87335154 -1.20354344
OS 15.8858331 -1.216025
OS 15.89692782 -1.2298934
OS 15.89831466 -1.23128024
OS 15.90108834 -1.2368276
OS 15.9066357 -1.24514864
OS 15.91218306 -1.2576302
OS 15.91634358 -1.27288544
OS 15.92189094 -1.28952752
OS 15.92466462 -1.30894328
OS 15.92605146 -1.33113272
OS 15.92605146 -1.3339064
OS 15.92605146 -1.3408406
OS 15.92466462 -1.35193532
OS 15.92189094 -1.36719056
OS 15.91773042 -1.38383264
OS 15.91079622 -1.40186156
OS 15.90247518 -1.42266416
OS 15.89138046 -1.44207992
OS 15.88999362 -1.4448536
OS 15.88444626 -1.45040096
OS 15.87751206 -1.46010884
OS 15.86641734 -1.47120356
OS 15.8511621 -1.48368512
OS 15.83452002 -1.49755352
OS 15.81510426 -1.51003508
OS 15.79152798 -1.52251664
OS 15.79014114 -1.52251664
OS 15.7887543 -1.52390348
OS 15.78043326 -1.52667716
OS 15.76656486 -1.53083768
OS 15.74853594 -1.53638504
OS 15.7263465 -1.5419324
OS 15.70138338 -1.54609292
OS 15.67503342 -1.5488666
OS 15.64452294 -1.55025344
OS 15.63204138 -1.55025344
OS 15.6223335 -1.54886914
OS 15.61123878 -1.54886914
OS 15.59737038 -1.5474823
OS 15.58350198 -1.54609546
OS 15.56824674 -1.54332178
OS 15.53496258 -1.53638758
OS 15.50029158 -1.5266797
OS 15.46700742 -1.5128113
OS 15.45175218 -1.50449026
OS 15.43788378 -1.49478238
OS 15.43649694 -1.49339554
OS 15.4351101 -1.4920087
OS 15.42678906 -1.48368766
OS 15.4143075 -1.4712061
OS 15.4004391 -1.45179034
OS 15.38518386 -1.42821406
OS 15.36992862 -1.40047726
OS 15.35744706 -1.36580626
OS 15.34773918 -1.32697474
OS 15.46423374 -1.30894582
OS 15.46423374 -1.31033266
OS 15.46423374 -1.3117195
OS 15.46700742 -1.32004054
OS 15.4697811 -1.33390894
OS 15.47532846 -1.34916418
OS 15.48226266 -1.36580626
OS 15.4905837 -1.38383518
OS 15.50306526 -1.4018641
OS 15.5183205 -1.41711934
OS 15.52109418 -1.41850618
OS 15.52664154 -1.4226667
OS 15.53773626 -1.42821406
OS 15.55160466 -1.43514826
OS 15.56963358 -1.44208246
OS 15.59043618 -1.44762982
OS 15.6153993 -1.45179034
OS 15.64452294 -1.45317464
OS 15.65839134 -1.45317464
OS 15.67225974 -1.4517878
OS 15.69028866 -1.44901412
OS 15.70970442 -1.4448536
OS 15.73050702 -1.43930624
OS 15.74853594 -1.43237204
OS 15.76517802 -1.42127732
OS 15.76656486 -1.41989048
OS 15.77211222 -1.41572996
OS 15.77765958 -1.40879576
OS 15.78598062 -1.39908788
OS 15.79291482 -1.38799316
OS 15.79984902 -1.37412476
OS 15.80400954 -1.36025636
OS 15.80539638 -1.34361428
OS 15.80539638 -1.34222744
OS 15.80539638 -1.33668008
OS 15.80400954 -1.32974588
OS 15.80123586 -1.320038
OS 15.79707534 -1.31033012
OS 15.79014114 -1.30062224
OS 15.7818201 -1.28952752
OS 15.76933854 -1.28120648
OS 15.7679517 -1.27981964
OS 15.76379118 -1.2784328
OS 15.75685698 -1.27427228
OS 15.74576226 -1.27011176
OS 15.72912018 -1.2645644
OS 15.7194123 -1.26040388
OS 15.70831758 -1.2576302
OS 15.69583602 -1.25346968
OS 15.68196762 -1.24930916
OS 15.66671238 -1.24514864
OS 15.64868346 -1.24098812
OS 15.64729662 -1.24098812
OS 15.6431361 -1.23960128
OS 15.6362019 -1.23821444
OS 15.62788086 -1.2354433
OS 15.61678614 -1.23266962
OS 15.60430458 -1.2285091
OS 15.57795462 -1.2215749
OS 15.54744414 -1.21186702
OS 15.5183205 -1.20354598
OS 15.4905837 -1.1938381
OS 15.47810214 -1.18829074
OS 15.46839426 -1.18413022
OS 15.46562058 -1.18274338
OS 15.46007322 -1.1799697
OS 15.45175218 -1.17442234
OS 15.44065746 -1.16748814
OS 15.4281759 -1.15778026
OS 15.41569434 -1.14668554
OS 15.40321278 -1.13420398
OS 15.39211806 -1.11894874
OS 15.39073122 -1.1175619
OS 15.38795754 -1.11201454
OS 15.38379702 -1.10230666
OS 15.3796365 -1.09121194
OS 15.37547598 -1.07734354
OS 15.37131546 -1.06070146
OS 15.36854178 -1.04405938
OS 15.36715494 -1.02464362
OS 15.36715494 -1.02186994
OS 15.36715494 -1.01632258
OS 15.36854178 -1.00800154
OS 15.36992862 -0.99551998
OS 15.3727023 -0.98303842
OS 15.37547598 -0.96778318
OS 15.38102334 -0.95391478
OS 15.38795754 -0.93865954
OS 15.38934438 -0.9372727
OS 15.39211806 -0.93172534
OS 15.39627858 -0.92479114
OS 15.40321278 -0.91508326
OS 15.41153382 -0.90537538
OS 15.4212417 -0.89289382
OS 15.43233642 -0.8817991
OS 15.44620482 -0.87209122
OS 15.44759166 -0.87070438
OS 15.45175218 -0.86931754
OS 15.45729954 -0.86515702
OS 15.46562058 -0.8609965
OS 15.4767153 -0.85544914
OS 15.48919686 -0.84990178
OS 15.5044521 -0.84435442
OS 15.52109418 -0.83880706
OS 15.52386786 -0.83742022
OS 15.52941522 -0.83603338
OS 15.5391231 -0.8332597
OS 15.55160466 -0.83048602
OS 15.5668599 -0.82771234
OS 15.58350198 -0.8263255
OS 15.60291774 -0.82355182
OS 15.6362019 -0.82354928
OS 15.65145714 -0.82493612
OE
OB 14.46570894 -1.53500074 I
OS 14.34782754 -1.53500074
OS 14.34782754 -0.57530746
OS 14.46570894 -0.57530746
OS 14.46570894 -1.53500074
OE
OB 14.9566503 -0.82493866 I
OS 14.96774502 -0.8263255
OS 14.98161342 -0.82909918
OS 14.99686866 -0.83187286
OS 15.01489758 -0.83603338
OS 15.03153966 -0.8401939
OS 15.05095542 -0.8471281
OS 15.06898434 -0.8540623
OS 15.0884001 -0.86377018
OS 15.10781586 -0.8748649
OS 15.12723162 -0.88734646
OS 15.14526054 -0.9026017
OS 15.16190262 -0.91924378
OS 15.16328946 -0.92063062
OS 15.16606314 -0.9234043
OS 15.17022366 -0.92895166
OS 15.17577102 -0.9372727
OS 15.18270522 -0.94698058
OS 15.18963942 -0.9580753
OS 15.19796046 -0.9719437
OS 15.2062815 -0.98858578
OS 15.21460254 -1.0066147
OS 15.22292358 -1.02603046
OS 15.22985778 -1.0482199
OS 15.23679198 -1.07179618
OS 15.24233934 -1.09814614
OS 15.24649986 -1.12588294
OS 15.24927354 -1.15500658
OS 15.25066038 -1.1869039
OS 15.25066038 -1.18829074
OS 15.25066038 -1.1938381
OS 15.25066038 -1.20354598
OS 15.24927354 -1.21741438
OS 14.72920854 -1.21741438
OS 14.72920854 -1.21880122
OS 14.72920854 -1.22296174
OS 14.73059538 -1.2285091
OS 14.73059538 -1.23683014
OS 14.73198222 -1.24653802
OS 14.7347559 -1.25763274
OS 14.73891642 -1.28259586
OS 14.74723746 -1.31033266
OS 14.75833218 -1.34084314
OS 14.77358742 -1.36857994
OS 14.79300318 -1.39354306
OS 14.79439002 -1.39354306
OS 14.79577686 -1.39631674
OS 14.8040979 -1.40325094
OS 14.81657946 -1.41295882
OS 14.83322154 -1.4226667
OS 14.85541098 -1.43376142
OS 14.8803741 -1.4434693
OS 14.9081109 -1.4504035
OS 14.92336614 -1.45179034
OS 14.94000822 -1.45317718
OS 14.95110294 -1.45317718
OS 14.9635845 -1.45179034
OS 14.97883974 -1.44901666
OS 14.99548182 -1.44485614
OS 15.01489758 -1.43930878
OS 15.0329265 -1.43098774
OS 15.05095542 -1.41989302
OS 15.05234226 -1.41850618
OS 15.05927646 -1.41295882
OS 15.0675975 -1.40463778
OS 15.07730538 -1.39354306
OS 15.0884001 -1.37828782
OS 15.10088166 -1.35887206
OS 15.11336322 -1.33668262
OS 15.12445794 -1.31033266
OS 15.24649986 -1.3255879
OS 15.24649986 -1.32697474
OS 15.24511302 -1.32974842
OS 15.24372618 -1.33529578
OS 15.2409525 -1.34361682
OS 15.23679198 -1.35193786
OS 15.23263146 -1.36303258
OS 15.22153674 -1.38660886
OS 15.20766834 -1.41295882
OS 15.18825258 -1.44069562
OS 15.16606314 -1.46704558
OS 15.13832634 -1.4920087
OS 15.1369395 -1.4920087
OS 15.13416582 -1.49478238
OS 15.1300053 -1.49755606
OS 15.12445794 -1.50171658
OS 15.1161369 -1.5058771
OS 15.10781586 -1.51003762
OS 15.09672114 -1.51558498
OS 15.08423958 -1.52113234
OS 15.07037118 -1.5266797
OS 15.05650278 -1.53222706
OS 15.02183178 -1.5405481
OS 14.98300026 -1.5474823
OS 14.94000822 -1.55025598
OS 14.92475298 -1.55025598
OS 14.9150451 -1.54886914
OS 14.90256354 -1.5474823
OS 14.8873083 -1.54470862
OS 14.87066622 -1.54193494
OS 14.8526373 -1.53916126
OS 14.81380578 -1.52806654
OS 14.79300318 -1.5197455
OS 14.77358742 -1.51142446
OS 14.75278482 -1.50032974
OS 14.73336906 -1.48784818
OS 14.71534014 -1.47397978
OS 14.69731122 -1.4573377
OS 14.69592438 -1.45595086
OS 14.6931507 -1.45317718
OS 14.68899018 -1.44762982
OS 14.68344282 -1.43930878
OS 14.67650862 -1.4296009
OS 14.66957442 -1.41850618
OS 14.66125338 -1.40463778
OS 14.65293234 -1.38938254
OS 14.6446113 -1.37135362
OS 14.63629026 -1.35193786
OS 14.62935606 -1.32974842
OS 14.62242186 -1.30617214
OS 14.6168745 -1.28120902
OS 14.61271398 -1.25347222
OS 14.6099403 -1.22434858
OS 14.60855346 -1.1938381
OS 14.60855346 -1.19245126
OS 14.60855346 -1.18551706
OS 14.60855346 -1.17719602
OS 14.6099403 -1.16471446
OS 14.61132714 -1.14945922
OS 14.61271398 -1.13281714
OS 14.61548766 -1.11340138
OS 14.61964818 -1.09398562
OS 14.6307429 -1.04960674
OS 14.6376771 -1.0274173
OS 14.64599814 -1.00384102
OS 14.65709286 -0.98165158
OS 14.66957442 -0.96084898
OS 14.68344282 -0.94004638
OS 14.69869806 -0.92063062
OS 14.7000849 -0.91924378
OS 14.70285858 -0.9164701
OS 14.70840594 -0.91230958
OS 14.71534014 -0.90537538
OS 14.72366118 -0.89844118
OS 14.7347559 -0.89012014
OS 14.74723746 -0.88041226
OS 14.7624927 -0.87209122
OS 14.77774794 -0.86238334
OS 14.79577686 -0.8540623
OS 14.81519262 -0.84574126
OS 14.83599522 -0.83880706
OS 14.85818466 -0.83187286
OS 14.88176094 -0.82771234
OS 14.90672406 -0.82493866
OS 14.93307402 -0.82355182
OS 14.94694242 -0.82355182
OS 14.9566503 -0.82493866
OE
OB 10.66576734 -1.53500074 I
OS 10.54788594 -1.53500074
OS 10.54788594 -0.83880706
OS 10.66576734 -0.83880706
OS 10.66576734 -1.53500074
OE
OB 10.37869146 -0.82493866 I
OS 10.3939467 -0.82771234
OS 10.41197562 -0.8332597
OS 10.43139138 -0.8401939
OS 10.45358082 -0.84990178
OS 10.4771571 -0.86238334
OS 10.43416506 -0.97055686
OS 10.43277822 -0.96917002
OS 10.42723086 -0.96639634
OS 10.41890982 -0.96223582
OS 10.4078151 -0.9580753
OS 10.39533354 -0.95391478
OS 10.3800783 -0.94975426
OS 10.36482306 -0.94698058
OS 10.34956782 -0.94559374
OS 10.34263362 -0.94559374
OS 10.33569942 -0.94698058
OS 10.32599154 -0.94836742
OS 10.31628366 -0.9511411
OS 10.3038021 -0.95530162
OS 10.29132054 -0.96084898
OS 10.28022582 -0.96917002
OS 10.27883898 -0.97055686
OS 10.27467846 -0.97333054
OS 10.27051794 -0.9788779
OS 10.26358374 -0.9858121
OS 10.25664954 -0.99551998
OS 10.24971534 -1.0066147
OS 10.24278114 -1.01909626
OS 10.23723378 -1.0343515
OS 10.23584694 -1.03712518
OS 10.2344601 -1.04544622
OS 10.23168642 -1.05792778
OS 10.2275259 -1.07456986
OS 10.22336538 -1.09537246
OS 10.2205917 -1.11894874
OS 10.21920486 -1.14391186
OS 10.21781802 -1.17164866
OS 10.21781802 -1.53500074
OS 10.09993662 -1.53500074
OS 10.09993662 -0.83880706
OS 10.2067233 -0.83880706
OS 10.2067233 -0.9442069
OS 10.20811014 -0.94282006
OS 10.2136575 -0.93311218
OS 10.2205917 -0.92063062
OS 10.23168642 -0.90537538
OS 10.24278114 -0.89012014
OS 10.2552627 -0.87347806
OS 10.26774426 -0.85960966
OS 10.28022582 -0.84851494
OS 10.28161266 -0.8471281
OS 10.28577318 -0.84435442
OS 10.29409422 -0.8401939
OS 10.30241526 -0.83603338
OS 10.31350998 -0.83187286
OS 10.32737838 -0.82771234
OS 10.34124678 -0.82493866
OS 10.35650202 -0.82355182
OS 10.3662099 -0.82355182
OS 10.37869146 -0.82493866
OE
OB 10.66576734 -0.70983094 I
OS 10.54788594 -0.70983094
OS 10.54788594 -0.57530746
OS 10.66576734 -0.57530746
OS 10.66576734 -0.70983094
OE
OB 8.8406859 -0.56005222 I
OS 8.85316746 -0.56143906
OS 8.8684227 -0.5628259
OS 8.88367794 -0.56421274
OS 8.90170686 -0.56837326
OS 8.93915154 -0.5766943
OS 8.98075674 -0.58917586
OS 9.00155934 -0.5974969
OS 9.0209751 -0.60720478
OS 9.04039086 -0.61968634
OS 9.05980662 -0.6321679
OS 9.06119346 -0.63355474
OS 9.06396714 -0.63494158
OS 9.0695145 -0.6391021
OS 9.0764487 -0.6460363
OS 9.0833829 -0.6529705
OS 9.09309078 -0.66267838
OS 9.10279866 -0.6737731
OS 9.11389338 -0.68486782
OS 9.1249881 -0.69873622
OS 9.13608282 -0.7153783
OS 9.14856438 -0.73202038
OS 9.1596591 -0.7500493
OS 9.16936698 -0.7708519
OS 9.1804617 -0.7916545
OS 9.18878274 -0.81384394
OS 9.19710378 -0.83880706
OS 9.07228818 -0.8679307
OS 9.07228818 -0.86654386
OS 9.07090134 -0.86377018
OS 9.06812766 -0.85822282
OS 9.06535398 -0.85128862
OS 9.0625803 -0.84296758
OS 9.05841978 -0.83187286
OS 9.04732506 -0.80968342
OS 9.03345666 -0.7847203
OS 9.01681458 -0.75975718
OS 8.99601198 -0.7361809
OS 8.97382254 -0.7153783
OS 8.97104886 -0.71260462
OS 8.96272782 -0.70705726
OS 8.94885942 -0.70012306
OS 8.9308305 -0.69041518
OS 8.90725422 -0.68209414
OS 8.88090426 -0.6737731
OS 8.84900694 -0.66822574
OS 8.81433594 -0.6668389
OS 8.80324122 -0.6668389
OS 8.79630702 -0.66822574
OS 8.78659914 -0.66822574
OS 8.77550442 -0.66961258
OS 8.74915446 -0.6737731
OS 8.72003082 -0.67932046
OS 8.68952034 -0.68902834
OS 8.65762302 -0.70289674
OS 8.62849938 -0.72092566
OS 8.62711254 -0.72092566
OS 8.6257257 -0.72369934
OS 8.61601782 -0.73063354
OS 8.60353626 -0.74172826
OS 8.58828102 -0.75837034
OS 8.5702521 -0.77917294
OS 8.55361002 -0.80274922
OS 8.53835478 -0.83187286
OS 8.52448638 -0.86377018
OS 8.52448638 -0.86515702
OS 8.52309954 -0.8679307
OS 8.5217127 -0.87209122
OS 8.52032586 -0.87902542
OS 8.51755218 -0.88734646
OS 8.5147785 -0.89705434
OS 8.51061798 -0.92063062
OS 8.50507062 -0.94836742
OS 8.49952326 -0.9788779
OS 8.49674958 -1.01216206
OS 8.49536274 -1.0482199
OS 8.49536274 -1.04960674
OS 8.49536274 -1.05376726
OS 8.49536274 -1.06070146
OS 8.49536274 -1.0690225
OS 8.49674958 -1.07873038
OS 8.49674958 -1.09121194
OS 8.49813642 -1.10508034
OS 8.49952326 -1.12033558
OS 8.50368378 -1.15361974
OS 8.51061798 -1.18967758
OS 8.51893902 -1.22573542
OS 8.53003374 -1.26179326
OS 8.53003374 -1.2631801
OS 8.53142058 -1.26595378
OS 8.53419426 -1.2701143
OS 8.53696794 -1.2770485
OS 8.54528898 -1.29369058
OS 8.55777054 -1.31310634
OS 8.57302578 -1.33529578
OS 8.59244154 -1.35887206
OS 8.61463098 -1.37967466
OS 8.64098094 -1.39909042
OS 8.64236778 -1.39909042
OS 8.64514146 -1.40047726
OS 8.64930198 -1.40325094
OS 8.65484934 -1.40602462
OS 8.66178354 -1.4087983
OS 8.67010458 -1.41295882
OS 8.68952034 -1.42127986
OS 8.71448346 -1.4296009
OS 8.74222026 -1.4365351
OS 8.77273074 -1.44208246
OS 8.80462806 -1.4434693
OS 8.81433594 -1.4434693
OS 8.82265698 -1.44208246
OS 8.83236486 -1.44208246
OS 8.84207274 -1.44069562
OS 8.86703586 -1.43514826
OS 8.8961595 -1.42821406
OS 8.92528314 -1.41711934
OS 8.95579362 -1.4018641
OS 8.97104886 -1.39354306
OS 8.98491726 -1.38244834
OS 8.9863041 -1.3810615
OS 8.98769094 -1.37967466
OS 8.99185146 -1.37551414
OS 8.99739882 -1.37135362
OS 9.00294618 -1.36441942
OS 9.00988038 -1.35609838
OS 9.01820142 -1.34777734
OS 9.02513562 -1.33668262
OS 9.03345666 -1.32420106
OS 9.04316454 -1.31033266
OS 9.05148558 -1.29646426
OS 9.05980662 -1.27982218
OS 9.06674082 -1.26179326
OS 9.07367502 -1.2423775
OS 9.08060922 -1.2215749
OS 9.08615658 -1.19938546
OS 9.21374586 -1.23128278
OS 9.21374586 -1.23266962
OS 9.21235902 -1.23821698
OS 9.20958534 -1.24653802
OS 9.20542482 -1.25763274
OS 9.2012643 -1.2701143
OS 9.19571694 -1.28536954
OS 9.18878274 -1.30201162
OS 9.1804617 -1.32004054
OS 9.16104594 -1.35887206
OS 9.13608282 -1.39770358
OS 9.12082758 -1.41711934
OS 9.10557234 -1.4365351
OS 9.08893026 -1.45317718
OS 9.0695145 -1.46981926
OS 9.06812766 -1.4712061
OS 9.06535398 -1.47397978
OS 9.05841978 -1.47675346
OS 9.05148558 -1.48230082
OS 9.04039086 -1.48923502
OS 9.02929614 -1.49616922
OS 9.0140409 -1.50310342
OS 8.99878566 -1.51003762
OS 8.98075674 -1.51835866
OS 8.96134098 -1.52529286
OS 8.94053838 -1.53222706
OS 8.91834894 -1.53916126
OS 8.89477266 -1.54470862
OS 8.86980954 -1.5474823
OS 8.84345958 -1.55025598
OS 8.81572278 -1.55164282
OS 8.80046754 -1.55164282
OS 8.78937282 -1.55025598
OS 8.77689126 -1.55025598
OS 8.76163602 -1.54886914
OS 8.74499394 -1.54609546
OS 8.72557818 -1.54332178
OS 8.68535982 -1.53638758
OS 8.64375462 -1.52529286
OS 8.60214942 -1.51003762
OS 8.58273366 -1.50032974
OS 8.5633179 -1.48923502
OS 8.56193106 -1.48784818
OS 8.55915738 -1.48646134
OS 8.55361002 -1.48230082
OS 8.54806266 -1.47675346
OS 8.53974162 -1.4712061
OS 8.53003374 -1.46288506
OS 8.51893902 -1.45317718
OS 8.5078443 -1.44208246
OS 8.49674958 -1.4296009
OS 8.48426802 -1.41711934
OS 8.4593049 -1.38522202
OS 8.43572862 -1.34777734
OS 8.41492602 -1.30617214
OS 8.41492602 -1.3047853
OS 8.41215234 -1.30062478
OS 8.4107655 -1.29369058
OS 8.40660498 -1.28536954
OS 8.4038313 -1.27427482
OS 8.39967078 -1.26040642
OS 8.39412342 -1.24515118
OS 8.3899629 -1.2285091
OS 8.38580238 -1.21048018
OS 8.38025502 -1.18967758
OS 8.37332082 -1.14668554
OS 8.36777346 -1.09814614
OS 8.36499978 -1.0482199
OS 8.36499978 -1.04683306
OS 8.36499978 -1.0412857
OS 8.36499978 -1.03296466
OS 8.36638662 -1.02325678
OS 8.36638662 -1.00938838
OS 8.36777346 -0.99551998
OS 8.3691603 -0.97749106
OS 8.37193398 -0.95946214
OS 8.37886818 -0.91924378
OS 8.38857606 -0.8748649
OS 8.40244446 -0.83048602
OS 8.42186022 -0.78749398
OS 8.42324706 -0.78610714
OS 8.4246339 -0.78194662
OS 8.42740758 -0.77639926
OS 8.43295494 -0.76946506
OS 8.4385023 -0.75975718
OS 8.4454365 -0.74866246
OS 8.46346542 -0.72369934
OS 8.4870417 -0.69596254
OS 8.5147785 -0.66822574
OS 8.54667582 -0.64048894
OS 8.5841205 -0.61691266
OS 8.58550734 -0.61552582
OS 8.58966786 -0.61413898
OS 8.59521522 -0.6113653
OS 8.60214942 -0.60720478
OS 8.61324414 -0.60304426
OS 8.62433886 -0.59888374
OS 8.63820726 -0.59333638
OS 8.6534625 -0.58778902
OS 8.67010458 -0.58224166
OS 8.6881335 -0.5766943
OS 8.72696502 -0.56837326
OS 8.7713439 -0.56143906
OS 8.81710962 -0.55866538
OS 8.83097802 -0.55866538
OS 8.8406859 -0.56005222
OE
OB 11.10262194 -0.82493866 I
OS 11.12342454 -0.8263255
OS 11.14561398 -0.82909918
OS 11.16919026 -0.83464654
OS 11.19415338 -0.8401939
OS 11.21772966 -0.84851494
OS 11.2191165 -0.84851494
OS 11.22050334 -0.84990178
OS 11.22743754 -0.85267546
OS 11.23853226 -0.85822282
OS 11.25240066 -0.86515702
OS 11.2676559 -0.8748649
OS 11.28291114 -0.88595962
OS 11.29677954 -0.89844118
OS 11.3092611 -0.91230958
OS 11.31064794 -0.91369642
OS 11.31342162 -0.91924378
OS 11.31896898 -0.92895166
OS 11.32590318 -0.94004638
OS 11.33283738 -0.95668846
OS 11.33977158 -0.97471738
OS 11.34531894 -0.99551998
OS 11.3508663 -1.01909626
OS 11.23575858 -1.0343515
OS 11.23575858 -1.03157782
OS 11.23437174 -1.02603046
OS 11.23159806 -1.01632258
OS 11.22743754 -1.00384102
OS 11.22050334 -0.99135946
OS 11.2121823 -0.97749106
OS 11.20247442 -0.96362266
OS 11.18860602 -0.9511411
OS 11.18721918 -0.94975426
OS 11.18167182 -0.94698058
OS 11.17335078 -0.94143322
OS 11.16086922 -0.93588586
OS 11.14700082 -0.9303385
OS 11.1289719 -0.92479114
OS 11.10678246 -0.92201746
OS 11.08320618 -0.92063062
OS 11.06933778 -0.92063062
OS 11.05546938 -0.92201746
OS 11.03744046 -0.9234043
OS 11.01941154 -0.92756482
OS 10.99999578 -0.93172534
OS 10.98196686 -0.93865954
OS 10.96671162 -0.94836742
OS 10.96532478 -0.94975426
OS 10.96116426 -0.95252794
OS 10.9556169 -0.9580753
OS 10.95006954 -0.96639634
OS 10.94313534 -0.97471738
OS 10.93758798 -0.9858121
OS 10.93342746 -0.99829366
OS 10.93204062 -1.01077522
OS 10.93204062 -1.01216206
OS 10.93204062 -1.01493574
OS 10.93342746 -1.01909626
OS 10.93342746 -1.02464362
OS 10.93758798 -1.03851202
OS 10.94590902 -1.05238042
OS 10.94729586 -1.05376726
OS 10.9486827 -1.0551541
OS 10.95145638 -1.05931462
OS 10.95700374 -1.06347514
OS 10.9625511 -1.06763566
OS 10.97087214 -1.07318302
OS 10.98058002 -1.07734354
OS 10.99167474 -1.0828909
OS 10.99306158 -1.0828909
OS 10.99583526 -1.08427774
OS 11.00138262 -1.08566458
OS 11.0110905 -1.0898251
OS 11.0249589 -1.09398562
OS 11.04298782 -1.09814614
OS 11.05408254 -1.10230666
OS 11.0665641 -1.10508034
OS 11.0804325 -1.10924086
OS 11.09568774 -1.11340138
OS 11.09707458 -1.11340138
OS 11.1012351 -1.11478822
OS 11.1081693 -1.11617506
OS 11.11649034 -1.11894874
OS 11.12619822 -1.12172242
OS 11.13867978 -1.1244961
OS 11.16502974 -1.13281714
OS 11.19415338 -1.14113818
OS 11.22327702 -1.15084606
OS 11.24962698 -1.16055394
OS 11.2607217 -1.16471446
OS 11.27042958 -1.16887498
OS 11.27320326 -1.17026182
OS 11.27875062 -1.1730355
OS 11.28707166 -1.17719602
OS 11.29955322 -1.18413022
OS 11.31203478 -1.19245126
OS 11.32451634 -1.20354598
OS 11.3369979 -1.21602754
OS 11.34809262 -1.22989594
OS 11.34947946 -1.23128278
OS 11.35225314 -1.23683014
OS 11.3578005 -1.24515118
OS 11.36334786 -1.25763274
OS 11.36750838 -1.27288798
OS 11.37305574 -1.28953006
OS 11.37582942 -1.30894582
OS 11.37721626 -1.33113526
OS 11.37721626 -1.33390894
OS 11.37721626 -1.34084314
OS 11.37582942 -1.35193786
OS 11.37305574 -1.3671931
OS 11.36889522 -1.38383518
OS 11.36196102 -1.4018641
OS 11.35363998 -1.4226667
OS 11.34254526 -1.44208246
OS 11.34115842 -1.44485614
OS 11.33561106 -1.4504035
OS 11.32867686 -1.46011138
OS 11.31758214 -1.4712061
OS 11.3023269 -1.48368766
OS 11.28568482 -1.49755606
OS 11.26626906 -1.51003762
OS 11.24269278 -1.52251918
OS 11.24130594 -1.52251918
OS 11.2399191 -1.52390602
OS 11.23159806 -1.5266797
OS 11.21772966 -1.53084022
OS 11.19970074 -1.53638758
OS 11.1775113 -1.54193494
OS 11.15254818 -1.54609546
OS 11.12619822 -1.54886914
OS 11.09568774 -1.55025598
OS 11.08320618 -1.55025598
OS 11.0734983 -1.54886914
OS 11.06240358 -1.54886914
OS 11.04853518 -1.5474823
OS 11.03466678 -1.54609546
OS 11.01941154 -1.54332178
OS 10.98612738 -1.53638758
OS 10.95145638 -1.5266797
OS 10.91817222 -1.5128113
OS 10.90291698 -1.50449026
OS 10.88904858 -1.49478238
OS 10.88766174 -1.49339554
OS 10.8862749 -1.4920087
OS 10.87795386 -1.48368766
OS 10.8654723 -1.4712061
OS 10.8516039 -1.45179034
OS 10.83634866 -1.42821406
OS 10.82109342 -1.40047726
OS 10.80861186 -1.36580626
OS 10.79890398 -1.32697474
OS 10.91539854 -1.30894582
OS 10.91539854 -1.31033266
OS 10.91539854 -1.3117195
OS 10.91817222 -1.32004054
OS 10.9209459 -1.33390894
OS 10.92649326 -1.34916418
OS 10.93342746 -1.36580626
OS 10.9417485 -1.38383518
OS 10.95423006 -1.4018641
OS 10.9694853 -1.41711934
OS 10.97225898 -1.41850618
OS 10.97780634 -1.4226667
OS 10.98890106 -1.42821406
OS 11.00276946 -1.43514826
OS 11.02079838 -1.44208246
OS 11.04160098 -1.44762982
OS 11.0665641 -1.45179034
OS 11.09568774 -1.45317718
OS 11.10955614 -1.45317718
OS 11.12342454 -1.45179034
OS 11.14145346 -1.44901666
OS 11.16086922 -1.44485614
OS 11.18167182 -1.43930878
OS 11.19970074 -1.43237458
OS 11.21634282 -1.42127986
OS 11.21772966 -1.41989302
OS 11.22327702 -1.4157325
OS 11.22882438 -1.4087983
OS 11.23714542 -1.39909042
OS 11.24407962 -1.3879957
OS 11.25101382 -1.3741273
OS 11.25517434 -1.3602589
OS 11.25656118 -1.34361682
OS 11.25656118 -1.34222998
OS 11.25656118 -1.33668262
OS 11.25517434 -1.32974842
OS 11.25240066 -1.32004054
OS 11.24824014 -1.31033266
OS 11.24130594 -1.30062478
OS 11.2329849 -1.28953006
OS 11.22050334 -1.28120902
OS 11.2191165 -1.27982218
OS 11.21495598 -1.27843534
OS 11.20802178 -1.27427482
OS 11.19692706 -1.2701143
OS 11.18028498 -1.26456694
OS 11.1705771 -1.26040642
OS 11.15948238 -1.25763274
OS 11.14700082 -1.25347222
OS 11.13313242 -1.2493117
OS 11.11787718 -1.24515118
OS 11.09984826 -1.24099066
OS 11.09846142 -1.24099066
OS 11.0943009 -1.23960382
OS 11.0873667 -1.23821698
OS 11.07904566 -1.2354433
OS 11.06795094 -1.23266962
OS 11.05546938 -1.2285091
OS 11.02911942 -1.2215749
OS 10.99860894 -1.21186702
OS 10.9694853 -1.20354598
OS 10.9417485 -1.1938381
OS 10.92926694 -1.18829074
OS 10.91955906 -1.18413022
OS 10.91678538 -1.18274338
OS 10.91123802 -1.1799697
OS 10.90291698 -1.17442234
OS 10.89182226 -1.16748814
OS 10.8793407 -1.15778026
OS 10.86685914 -1.14668554
OS 10.85437758 -1.13420398
OS 10.84328286 -1.11894874
OS 10.84189602 -1.1175619
OS 10.83912234 -1.11201454
OS 10.83496182 -1.10230666
OS 10.8308013 -1.09121194
OS 10.82664078 -1.07734354
OS 10.82248026 -1.06070146
OS 10.81970658 -1.04405938
OS 10.81831974 -1.02464362
OS 10.81831974 -1.02186994
OS 10.81831974 -1.01632258
OS 10.81970658 -1.00800154
OS 10.82109342 -0.99551998
OS 10.8238671 -0.98303842
OS 10.82664078 -0.96778318
OS 10.83218814 -0.95391478
OS 10.83912234 -0.93865954
OS 10.84050918 -0.9372727
OS 10.84328286 -0.93172534
OS 10.84744338 -0.92479114
OS 10.85437758 -0.91508326
OS 10.86269862 -0.90537538
OS 10.8724065 -0.89289382
OS 10.88350122 -0.8817991
OS 10.89736962 -0.87209122
OS 10.89875646 -0.87070438
OS 10.90291698 -0.86931754
OS 10.90846434 -0.86515702
OS 10.91678538 -0.8609965
OS 10.9278801 -0.85544914
OS 10.94036166 -0.84990178
OS 10.9556169 -0.84435442
OS 10.97225898 -0.83880706
OS 10.97503266 -0.83742022
OS 10.98058002 -0.83603338
OS 10.9902879 -0.8332597
OS 11.00276946 -0.83048602
OS 11.0180247 -0.82771234
OS 11.03466678 -0.8263255
OS 11.05408254 -0.82355182
OS 11.0873667 -0.82355182
OS 11.10262194 -0.82493866
OE
OB 9.47308494 -0.91924378 I
OS 9.47447178 -0.91785694
OS 9.47724546 -0.91508326
OS 9.48140598 -0.91092274
OS 9.48834018 -0.90398854
OS 9.49527438 -0.89705434
OS 9.50498226 -0.8887333
OS 9.51746382 -0.88041226
OS 9.52994538 -0.87070438
OS 9.54381378 -0.86238334
OS 9.55906902 -0.8540623
OS 9.59512686 -0.83880706
OS 9.61454262 -0.83187286
OS 9.63534522 -0.82771234
OS 9.65753466 -0.82493866
OS 9.6797241 -0.82355182
OS 9.69220566 -0.82355182
OS 9.7074609 -0.82493866
OS 9.72548982 -0.82771234
OS 9.74629242 -0.83048602
OS 9.76848186 -0.83603338
OS 9.7906713 -0.84435442
OS 9.81286074 -0.8540623
OS 9.81563442 -0.85544914
OS 9.82256862 -0.85960966
OS 9.8322765 -0.86654386
OS 9.84475806 -0.87625174
OS 9.85723962 -0.8887333
OS 9.87110802 -0.9026017
OS 9.88358958 -0.91924378
OS 9.8946843 -0.93865954
OS 9.89607114 -0.94143322
OS 9.89884482 -0.94836742
OS 9.90300534 -0.96084898
OS 9.90716586 -0.9788779
OS 9.91132638 -1.00106734
OS 9.9154869 -1.0274173
OS 9.91826058 -1.05931462
OS 9.91964742 -1.09537246
OS 9.91964742 -1.53500074
OS 9.80176602 -1.53500074
OS 9.80176602 -1.09398562
OS 9.80176602 -1.09259878
OS 9.80176602 -1.0898251
OS 9.80176602 -1.08566458
OS 9.80176602 -1.08011722
OS 9.80037918 -1.06486198
OS 9.7976055 -1.04544622
OS 9.79205814 -1.02464362
OS 9.78512394 -1.00384102
OS 9.77541606 -0.98303842
OS 9.7629345 -0.96639634
OS 9.76154766 -0.9650095
OS 9.7560003 -0.95946214
OS 9.74767926 -0.95252794
OS 9.7351977 -0.94559374
OS 9.71994246 -0.9372727
OS 9.70191354 -0.93172534
OS 9.6797241 -0.92617798
OS 9.65476098 -0.92479114
OS 9.64643994 -0.92479114
OS 9.63673206 -0.92617798
OS 9.62286366 -0.92756482
OS 9.60899526 -0.93172534
OS 9.59235318 -0.93588586
OS 9.5757111 -0.94282006
OS 9.55768218 -0.95252794
OS 9.55629534 -0.95391478
OS 9.55074798 -0.9580753
OS 9.54242694 -0.96362266
OS 9.53271906 -0.9719437
OS 9.52162434 -0.98303842
OS 9.51052962 -0.99551998
OS 9.50082174 -1.01077522
OS 9.4925007 -1.0274173
OS 9.49111386 -1.03019098
OS 9.48972702 -1.03573834
OS 9.48695334 -1.04683306
OS 9.48279282 -1.06070146
OS 9.4786323 -1.07873038
OS 9.47585862 -1.10091982
OS 9.47447178 -1.12588294
OS 9.47308494 -1.15500658
OS 9.47308494 -1.53500074
OS 9.35520354 -1.53500074
OS 9.35520354 -0.57530746
OS 9.47308494 -0.57530746
OS 9.47308494 -0.91924378
OE
OB 14.93446086 -0.92063062 H
OS 14.92613982 -0.92063062
OS 14.92059246 -0.92201746
OS 14.90533722 -0.9234043
OS 14.8873083 -0.92756482
OS 14.86511886 -0.93449902
OS 14.84154258 -0.9442069
OS 14.81935314 -0.9580753
OS 14.7971637 -0.97610422
OS 14.79439002 -0.9788779
OS 14.78884266 -0.9858121
OS 14.77913478 -0.99829366
OS 14.7694269 -1.01493574
OS 14.75833218 -1.0343515
OS 14.7486243 -1.05931462
OS 14.74030326 -1.08843826
OS 14.73614274 -1.12033558
OS 15.12584478 -1.12033558
OS 15.12584478 -1.11894874
OS 15.12584478 -1.11617506
OS 15.12445794 -1.11201454
OS 15.12445794 -1.10646718
OS 15.12168426 -1.0898251
OS 15.11752374 -1.07179618
OS 15.11058954 -1.04960674
OS 15.10365534 -1.02880414
OS 15.09256062 -1.00800154
OS 15.08007906 -0.98997262
OS 15.08007906 -0.98858578
OS 15.07730538 -0.98719894
OS 15.07037118 -0.9788779
OS 15.05788962 -0.96778318
OS 15.04124754 -0.95530162
OS 15.02044494 -0.94282006
OS 14.99548182 -0.93172534
OS 14.96635818 -0.9234043
OS 14.95110294 -0.92201746
OS 14.93446086 -0.92063062
OE
OB 12.33690954 -0.68209414 H
OS 12.03457842 -0.68209414
OS 12.03457842 -0.9996805
OS 12.32026746 -0.9996805
OS 12.33690954 -0.99829366
OS 12.3563253 -0.99690682
OS 12.37851474 -0.99551998
OS 12.40070418 -0.9927463
OS 12.42289362 -0.98858578
OS 12.44230938 -0.98303842
OS 12.44508306 -0.98165158
OS 12.45063042 -0.9788779
OS 12.45895146 -0.97471738
OS 12.47004618 -0.96917002
OS 12.48252774 -0.96084898
OS 12.4950093 -0.9511411
OS 12.50749086 -0.93865954
OS 12.51719874 -0.92479114
OS 12.51858558 -0.9234043
OS 12.52135926 -0.91785694
OS 12.52551978 -0.9095359
OS 12.53106714 -0.89844118
OS 12.53522766 -0.88595962
OS 12.53938818 -0.87209122
OS 12.54216186 -0.85544914
OS 12.5435487 -0.83880706
OS 12.5435487 -0.83742022
OS 12.5435487 -0.83603338
OS 12.54216186 -0.82771234
OS 12.54077502 -0.81523078
OS 12.53800134 -0.7985887
OS 12.53106714 -0.78194662
OS 12.5227461 -0.76253086
OS 12.51026454 -0.74450194
OS 12.49362246 -0.72647302
OS 12.49084878 -0.72508618
OS 12.48391458 -0.71953882
OS 12.47281986 -0.71260462
OS 12.45479094 -0.70428358
OS 12.43398834 -0.69596254
OS 12.40625154 -0.68902834
OS 12.37435422 -0.68348098
OS 12.33690954 -0.68209414
OE
OB 13.1398899 -0.92063062 H
OS 13.13156886 -0.92063062
OS 13.12463466 -0.92201746
OS 13.10937942 -0.9234043
OS 13.08857682 -0.92895166
OS 13.06500054 -0.9372727
OS 13.04003742 -0.94836742
OS 13.01646114 -0.9650095
OS 13.00397958 -0.97610422
OS 12.99288486 -0.98719894
OS 12.99288486 -0.98858578
OS 12.99011118 -0.98997262
OS 12.9873375 -0.99413314
OS 12.98317698 -0.9996805
OS 12.97901646 -1.0066147
OS 12.97485594 -1.01493574
OS 12.96930858 -1.02603046
OS 12.96376122 -1.03712518
OS 12.95821386 -1.05099358
OS 12.9526665 -1.06486198
OS 12.94850598 -1.08150406
OS 12.94434546 -1.09953298
OS 12.94018494 -1.11894874
OS 12.93741126 -1.13975134
OS 12.93602442 -1.16332762
OS 12.93463758 -1.1869039
OS 12.93463758 -1.18829074
OS 12.93463758 -1.19245126
OS 12.93463758 -1.19938546
OS 12.93602442 -1.20909334
OS 12.93602442 -1.22018806
OS 12.93741126 -1.23266962
OS 12.94157178 -1.26179326
OS 12.94850598 -1.29507742
OS 12.9596007 -1.32836158
OS 12.9734691 -1.3602589
OS 12.98317698 -1.3741273
OS 12.99288486 -1.3879957
OS 12.9942717 -1.3879957
OS 12.99565854 -1.39076938
OS 13.00397958 -1.39770358
OS 13.01646114 -1.4087983
OS 13.03310322 -1.41989302
OS 13.05390582 -1.43237458
OS 13.07886894 -1.4434693
OS 13.10799258 -1.4504035
OS 13.12324782 -1.45179034
OS 13.1398899 -1.45317718
OS 13.14821094 -1.45317718
OS 13.15514514 -1.45179034
OS 13.17040038 -1.44901666
OS 13.19120298 -1.44485614
OS 13.21339242 -1.4365351
OS 13.23835554 -1.42544038
OS 13.26193182 -1.4087983
OS 13.27441338 -1.39770358
OS 13.2855081 -1.38660886
OS 13.28689494 -1.38522202
OS 13.28828178 -1.38383518
OS 13.29105546 -1.37967466
OS 13.29521598 -1.3741273
OS 13.2993765 -1.3671931
OS 13.30492386 -1.35887206
OS 13.31047122 -1.34777734
OS 13.31601858 -1.33668262
OS 13.32156594 -1.32281422
OS 13.32572646 -1.30755898
OS 13.33127382 -1.2909169
OS 13.33543434 -1.27288798
OS 13.33959486 -1.25208538
OS 13.34236854 -1.23128278
OS 13.34514222 -1.2077065
OS 13.34514222 -1.18274338
OS 13.34514222 -1.18135654
OS 13.34514222 -1.17719602
OS 13.34514222 -1.17026182
OS 13.34375538 -1.16194078
OS 13.34375538 -1.15084606
OS 13.34236854 -1.1383645
OS 13.33820802 -1.10924086
OS 13.33127382 -1.07873038
OS 13.3201791 -1.04544622
OS 13.30492386 -1.01493574
OS 13.29660282 -0.9996805
OS 13.2855081 -0.98719894
OS 13.2855081 -0.9858121
OS 13.28273442 -0.98442526
OS 13.27441338 -0.97610422
OS 13.26193182 -0.96639634
OS 13.24528974 -0.95391478
OS 13.22448714 -0.94143322
OS 13.19952402 -0.9303385
OS 13.17178722 -0.9234043
OS 13.15653198 -0.92201746
OS 13.1398899 -0.92063062
OE
OB 13.91235978 -0.92063062 H
OS 13.89155718 -0.92063062
OS 13.88600982 -0.92201746
OS 13.87075458 -0.92479114
OS 13.85272566 -0.92895166
OS 13.83192306 -0.9372727
OS 13.80973362 -0.94975426
OS 13.7986389 -0.95668846
OS 13.78754418 -0.96639634
OS 13.77644946 -0.97610422
OS 13.76535474 -0.98858578
OS 13.76535474 -0.98997262
OS 13.76258106 -0.99135946
OS 13.75980738 -0.99551998
OS 13.7570337 -1.00106734
OS 13.75287318 -1.00800154
OS 13.74732582 -1.01632258
OS 13.7431653 -1.02603046
OS 13.73761794 -1.03712518
OS 13.73207058 -1.05099358
OS 13.72791006 -1.06486198
OS 13.7223627 -1.08150406
OS 13.71820218 -1.09814614
OS 13.7154285 -1.1175619
OS 13.71265482 -1.1383645
OS 13.70988114 -1.1591671
OS 13.70988114 -1.18274338
OS 13.70988114 -1.18413022
OS 13.70988114 -1.18829074
OS 13.70988114 -1.19522494
OS 13.70988114 -1.20354598
OS 13.71126798 -1.21325386
OS 13.71126798 -1.22573542
OS 13.71404166 -1.25208538
OS 13.71820218 -1.28120902
OS 13.72374954 -1.3117195
OS 13.73207058 -1.3394563
OS 13.73761794 -1.35193786
OS 13.7431653 -1.36303258
OS 13.7431653 -1.36441942
OS 13.74593898 -1.3671931
OS 13.74871266 -1.37135362
OS 13.75287318 -1.37690098
OS 13.76535474 -1.39215622
OS 13.78338366 -1.40741146
OS 13.80418626 -1.42405354
OS 13.83053622 -1.43930878
OS 13.84440462 -1.44485614
OS 13.8610467 -1.44901666
OS 13.87630194 -1.45179034
OS 13.89433086 -1.45317718
OS 13.90126506 -1.45317718
OS 13.90681242 -1.45179034
OS 13.92206766 -1.44901666
OS 13.94009658 -1.44485614
OS 13.96089918 -1.4365351
OS 13.98308862 -1.42544038
OS 14.00527806 -1.4087983
OS 14.01637278 -1.39770358
OS 14.0274675 -1.38660886
OS 14.0274675 -1.38522202
OS 14.03024118 -1.38383518
OS 14.03301486 -1.37967466
OS 14.03578854 -1.3741273
OS 14.0413359 -1.3671931
OS 14.04549642 -1.35887206
OS 14.05104378 -1.34777734
OS 14.05659114 -1.33668262
OS 14.06075166 -1.32281422
OS 14.06629902 -1.30894582
OS 14.07184638 -1.29230374
OS 14.0760069 -1.27427482
OS 14.07878058 -1.25485906
OS 14.08155426 -1.23405646
OS 14.08432794 -1.21048018
OS 14.08432794 -1.1869039
OS 14.08432794 -1.18551706
OS 14.08432794 -1.18135654
OS 14.08432794 -1.17442234
OS 14.0829411 -1.16471446
OS 14.0829411 -1.15361974
OS 14.08155426 -1.13975134
OS 14.07739374 -1.1106277
OS 14.07184638 -1.07873038
OS 14.0621385 -1.04405938
OS 14.0482701 -1.0135489
OS 14.03994906 -0.99829366
OS 14.03024118 -0.9858121
OS 14.03024118 -0.98442526
OS 14.0274675 -0.98303842
OS 14.0205333 -0.97610422
OS 14.00943858 -0.9650095
OS 13.99418334 -0.95252794
OS 13.97476758 -0.94143322
OS 13.95257814 -0.9303385
OS 13.92622818 -0.9234043
OS 13.91235978 -0.92063062
OE
SE
S P 0
OB 35.73690338 -37.45999874 I
OS 35.61486146 -37.45999874
OS 35.61486146 -36.65701838
OS 35.33471978 -37.45999874
OS 35.2209989 -37.45999874
OS 34.9436309 -36.64314998
OS 34.9436309 -37.45999874
OS 34.82158898 -37.45999874
OS 34.82158898 -36.50030546
OS 35.01158606 -36.50030546
OS 35.23902782 -37.1812439
OS 35.23902782 -37.18263074
OS 35.24041466 -37.18540442
OS 35.2418015 -37.18956494
OS 35.24457518 -37.19649914
OS 35.25012254 -37.21314122
OS 35.25705674 -37.23394382
OS 35.26399094 -37.2575201
OS 35.27231198 -37.28109638
OS 35.27924618 -37.30328582
OS 35.28479354 -37.32270158
OS 35.28618038 -37.3199279
OS 35.28756722 -37.3129937
OS 35.29172774 -37.30051214
OS 35.2972751 -37.28387006
OS 35.3042093 -37.26168062
OS 35.31391718 -37.23533066
OS 35.32362506 -37.20482018
OS 35.33610662 -37.16876234
OS 35.56632206 -36.50030546
OS 35.73690338 -36.50030546
OS 35.73690338 -37.45999874
OE
OB 34.61356298 -37.05504146 I
OS 34.61356298 -37.0564283
OS 34.61356298 -37.06197566
OS 34.61356298 -37.06890986
OS 34.61356298 -37.07861774
OS 34.61217614 -37.0910993
OS 34.61217614 -37.1049677
OS 34.6107893 -37.12160978
OS 34.60940246 -37.13825186
OS 34.60524194 -37.17569654
OS 34.59969458 -37.21452806
OS 34.59137354 -37.25197274
OS 34.58582618 -37.27000166
OS 34.58027882 -37.28664374
OS 34.58027882 -37.28803058
OS 34.57889198 -37.29080426
OS 34.5761183 -37.29496478
OS 34.57334462 -37.30051214
OS 34.56502358 -37.31576738
OS 34.55254202 -37.33518314
OS 34.53589994 -37.35737258
OS 34.51648418 -37.37956202
OS 34.49152106 -37.4031383
OS 34.46101058 -37.4239409
OS 34.45962374 -37.4239409
OS 34.45685006 -37.42671458
OS 34.45268954 -37.42810142
OS 34.44575534 -37.43226194
OS 34.4374343 -37.43642246
OS 34.42633958 -37.44058298
OS 34.41524486 -37.4447435
OS 34.40137646 -37.45029086
OS 34.38612122 -37.45583822
OS 34.36947914 -37.45999874
OS 34.35145022 -37.46415926
OS 34.33064762 -37.46831978
OS 34.30984502 -37.47109346
OS 34.28765558 -37.47386714
OS 34.23772934 -37.47664082
OS 34.22524778 -37.47664082
OS 34.2155399 -37.47525398
OS 34.20444518 -37.47525398
OS 34.19057678 -37.47386714
OS 34.17532154 -37.4724803
OS 34.1600663 -37.47109346
OS 34.1253953 -37.4655461
OS 34.08795062 -37.45722506
OS 34.05189278 -37.44613034
OS 34.01722178 -37.4308751
OS 34.01583494 -37.4308751
OS 34.01306126 -37.42810142
OS 34.00890074 -37.42532774
OS 34.00335338 -37.42255406
OS 33.98809814 -37.41145934
OS 33.97006922 -37.3962041
OS 33.94926662 -37.37678834
OS 33.92985086 -37.3545989
OS 33.9104351 -37.3268621
OS 33.89517986 -37.29635162
OS 33.89517986 -37.29496478
OS 33.89379302 -37.2921911
OS 33.89240618 -37.28664374
OS 33.8896325 -37.27970954
OS 33.88685882 -37.2713885
OS 33.88408514 -37.26029378
OS 33.87992462 -37.24781222
OS 33.87715094 -37.23255698
OS 33.87437726 -37.2159149
OS 33.87021674 -37.19788598
OS 33.86744306 -37.17847022
OS 33.86466938 -37.15766762
OS 33.8618957 -37.13409134
OS 33.86050886 -37.10912822
OS 33.85912202 -37.08277826
OS 33.85912202 -37.05504146
OS 33.85912202 -36.50030546
OS 33.9867113 -36.50030546
OS 33.9867113 -37.05504146
OS 33.9867113 -37.0564283
OS 33.9867113 -37.06058882
OS 33.9867113 -37.06752302
OS 33.9867113 -37.07584406
OS 33.98809814 -37.08555194
OS 33.98809814 -37.0980335
OS 33.98948498 -37.12438346
OS 33.99225866 -37.15489394
OS 33.99641918 -37.18540442
OS 34.00196654 -37.21452806
OS 34.00474022 -37.22700962
OS 34.00890074 -37.23949118
OS 34.01028758 -37.24226486
OS 34.01306126 -37.24919906
OS 34.01999546 -37.25890694
OS 34.0283165 -37.27277534
OS 34.03802438 -37.28664374
OS 34.05189278 -37.30189898
OS 34.06853486 -37.31715422
OS 34.08795062 -37.32963578
OS 34.0907243 -37.33102262
OS 34.0976585 -37.33518314
OS 34.11014006 -37.33934366
OS 34.12678214 -37.34489102
OS 34.1461979 -37.35182522
OS 34.17116102 -37.35598574
OS 34.19751098 -37.36014626
OS 34.22663462 -37.3615331
OS 34.24050302 -37.3615331
OS 34.24882406 -37.36014626
OS 34.26130562 -37.36014626
OS 34.27378718 -37.35875942
OS 34.30429766 -37.35321206
OS 34.33758182 -37.34627786
OS 34.36947914 -37.33518314
OS 34.39998962 -37.3199279
OS 34.41385802 -37.31022002
OS 34.42633958 -37.2991253
OS 34.42772642 -37.29773846
OS 34.42911326 -37.29635162
OS 34.43188694 -37.2921911
OS 34.43604746 -37.28664374
OS 34.44020798 -37.2783227
OS 34.44575534 -37.27000166
OS 34.4513027 -37.2575201
OS 34.45685006 -37.24503854
OS 34.46239742 -37.2297833
OS 34.46655794 -37.21175438
OS 34.4721053 -37.19095178
OS 34.47626582 -37.16876234
OS 34.48042634 -37.14379922
OS 34.48320002 -37.11744926
OS 34.4859737 -37.08693878
OS 34.4859737 -37.05504146
OS 34.4859737 -36.50030546
OS 34.61356298 -36.50030546
OS 34.61356298 -37.05504146
OE
OB 33.64416182 -37.45999874 I
OS 33.51241202 -37.45999874
OS 33.01037594 -36.70694462
OS 33.01037594 -37.45999874
OS 32.88833402 -37.45999874
OS 32.88833402 -36.50030546
OS 33.01869698 -36.50030546
OS 33.5221199 -37.25474642
OS 33.5221199 -36.50030546
OS 33.64416182 -36.50030546
OS 33.64416182 -37.45999874
OE
OB 38.19022334 -36.5016923 I
OS 38.2027049 -36.5016923
OS 38.23182854 -36.50307914
OS 38.26233902 -36.50723966
OS 38.29562318 -36.51140018
OS 38.32613366 -36.51833438
OS 38.3413889 -36.5224949
OS 38.35387046 -36.52665542
OS 38.3552573 -36.52665542
OS 38.35664414 -36.52804226
OS 38.36496518 -36.53220278
OS 38.37744674 -36.53775014
OS 38.39270198 -36.54745802
OS 38.40934406 -36.55993958
OS 38.42737298 -36.57658166
OS 38.44401506 -36.59599742
OS 38.46065714 -36.61818686
OS 38.46065714 -36.6195737
OS 38.46204398 -36.62096054
OS 38.46759134 -36.62928158
OS 38.4731387 -36.64314998
OS 38.48145974 -36.6611789
OS 38.48839394 -36.6819815
OS 38.49532814 -36.70694462
OS 38.49948866 -36.73329458
OS 38.5008755 -36.76241822
OS 38.5008755 -36.76380506
OS 38.5008755 -36.76657874
OS 38.5008755 -36.7721261
OS 38.49948866 -36.7790603
OS 38.49948866 -36.78876818
OS 38.49810182 -36.79847606
OS 38.49255446 -36.82205234
OS 38.48423342 -36.84978914
OS 38.4731387 -36.87891278
OS 38.45649662 -36.90803642
OS 38.4454019 -36.92190482
OS 38.43430718 -36.93577322
OS 38.43292034 -36.93716006
OS 38.4315335 -36.9385469
OS 38.42737298 -36.94270742
OS 38.42182562 -36.94686794
OS 38.41489142 -36.9524153
OS 38.40657038 -36.95796266
OS 38.39547566 -36.96489686
OS 38.38438094 -36.9732179
OS 38.37051254 -36.9801521
OS 38.3552573 -36.9870863
OS 38.33861522 -36.99540734
OS 38.3205863 -37.00234154
OS 38.2997837 -37.0078889
OS 38.2789811 -37.0148231
OS 38.25540482 -37.01898362
OS 38.2304417 -37.02314414
OS 38.23321538 -37.02453098
OS 38.23876274 -37.02730466
OS 38.24708378 -37.03285202
OS 38.2581785 -37.03839938
OS 38.28314162 -37.05365462
OS 38.29562318 -37.0633625
OS 38.3067179 -37.07168354
OS 38.30949158 -37.07445722
OS 38.31642578 -37.08139142
OS 38.3275205 -37.09248614
OS 38.3413889 -37.10635454
OS 38.35664414 -37.1257703
OS 38.37467306 -37.1465729
OS 38.39270198 -37.17153602
OS 38.41211774 -37.19927282
OS 38.5771517 -37.45999874
OS 38.41905194 -37.45999874
OS 38.2928495 -37.26029378
OS 38.2928495 -37.25890694
OS 38.29007582 -37.25613326
OS 38.28730214 -37.25197274
OS 38.28314162 -37.24642538
OS 38.27343374 -37.23117014
OS 38.26095218 -37.21175438
OS 38.24569694 -37.19095178
OS 38.2304417 -37.16876234
OS 38.21518646 -37.14795974
OS 38.20131806 -37.12854398
OS 38.19993122 -37.12715714
OS 38.1957707 -37.12160978
OS 38.1888365 -37.11328874
OS 38.17912862 -37.10358086
OS 38.15832602 -37.08277826
OS 38.1472313 -37.07307038
OS 38.13613658 -37.06474934
OS 38.13474974 -37.0633625
OS 38.13197606 -37.06197566
OS 38.1264287 -37.05920198
OS 38.11810766 -37.05504146
OS 38.10978662 -37.05088094
OS 38.10007874 -37.04672042
OS 38.0778893 -37.03978622
OS 38.07650246 -37.03978622
OS 38.07372878 -37.03839938
OS 38.06818142 -37.03839938
OS 38.06124722 -37.03701254
OS 38.05153934 -37.0356257
OS 38.04044462 -37.0356257
OS 38.02518938 -37.03423886
OS 37.86154226 -37.03423886
OS 37.86154226 -37.45999874
OS 37.73395298 -37.45999874
OS 37.73395298 -36.50030546
OS 38.17912862 -36.50030546
OS 38.19022334 -36.5016923
OE
OB 37.53424802 -36.61402634 I
OS 36.96703046 -36.61402634
OS 36.96703046 -36.90664958
OS 37.49819018 -36.90664958
OS 37.49819018 -37.02037046
OS 36.96703046 -37.02037046
OS 36.96703046 -37.34627786
OS 37.55643746 -37.34627786
OS 37.55643746 -37.45999874
OS 36.83944118 -37.45999874
OS 36.83944118 -36.50030546
OS 37.53424802 -36.50030546
OS 37.53424802 -36.61402634
OE
OB 36.32492354 -36.5016923 I
OS 36.33601826 -36.5016923
OS 36.36098138 -36.50446598
OS 36.38871818 -36.50723966
OS 36.41784182 -36.51278702
OS 36.44696546 -36.51972122
OS 36.47331542 -36.5294291
OS 36.47470226 -36.5294291
OS 36.4760891 -36.53081594
OS 36.48441014 -36.53497646
OS 36.4968917 -36.54191066
OS 36.5107601 -36.55161854
OS 36.52740218 -36.5641001
OS 36.5454311 -36.57935534
OS 36.56207318 -36.5987711
OS 36.57732842 -36.6195737
OS 36.57871526 -36.62234738
OS 36.58287578 -36.63066842
OS 36.58980998 -36.64176314
OS 36.59674418 -36.65840522
OS 36.60367838 -36.67782098
OS 36.61061258 -36.69862358
OS 36.6147731 -36.72219986
OS 36.61615994 -36.74577614
OS 36.61615994 -36.74854982
OS 36.61615994 -36.75548402
OS 36.6147731 -36.76796558
OS 36.61199942 -36.78322082
OS 36.6078389 -36.80124974
OS 36.6009047 -36.8206655
OS 36.59258366 -36.84008126
OS 36.58148894 -36.86088386
OS 36.5801021 -36.86365754
OS 36.57594158 -36.8692049
OS 36.56762054 -36.88029962
OS 36.55652582 -36.89139434
OS 36.54265742 -36.90526274
OS 36.52601534 -36.92051798
OS 36.50521274 -36.93438638
OS 36.48163646 -36.94825478
OS 36.4830233 -36.94825478
OS 36.48579698 -36.94964162
OS 36.4899575 -36.95102846
OS 36.49550486 -36.95380214
OS 36.51214694 -36.9593495
OS 36.5315627 -36.96905738
OS 36.5523653 -36.98153894
OS 36.57594158 -36.99679418
OS 36.59674418 -37.0148231
OS 36.61615994 -37.03701254
OS 36.61754678 -37.03978622
OS 36.62309414 -37.04810726
OS 36.63141518 -37.06058882
OS 36.63973622 -37.0772309
OS 36.64805726 -37.09942034
OS 36.6563783 -37.12299662
OS 36.66192566 -37.15073342
OS 36.6633125 -37.1812439
OS 36.6633125 -37.18263074
OS 36.6633125 -37.18401758
OS 36.6633125 -37.19233862
OS 36.66192566 -37.20620702
OS 36.65915198 -37.2228491
OS 36.6563783 -37.24226486
OS 36.65083094 -37.26306746
OS 36.64389674 -37.2852569
OS 36.63418886 -37.30744634
OS 36.63280202 -37.31022002
OS 36.6286415 -37.31715422
OS 36.62309414 -37.3268621
OS 36.6147731 -37.3407305
OS 36.60367838 -37.3545989
OS 36.59258366 -37.36985414
OS 36.57871526 -37.38510938
OS 36.56346002 -37.39759094
OS 36.56207318 -37.39897778
OS 36.55652582 -37.4031383
OS 36.54681794 -37.40868566
OS 36.53433638 -37.41423302
OS 36.51908114 -37.42255406
OS 36.50105222 -37.4308751
OS 36.48163646 -37.4378093
OS 36.45806018 -37.4447435
OS 36.4552865 -37.4447435
OS 36.44696546 -37.44751718
OS 36.43309706 -37.44890402
OS 36.41506814 -37.4516777
OS 36.3928787 -37.45445138
OS 36.36652874 -37.45722506
OS 36.3374051 -37.4586119
OS 36.30412094 -37.45999874
OS 35.93799518 -37.45999874
OS 35.93799518 -36.50030546
OS 36.31521566 -36.50030546
OS 36.32492354 -36.5016923
OE
OB 32.3849111 -36.61402634 I
OS 32.06871158 -36.61402634
OS 32.06871158 -37.45999874
OS 31.9411223 -37.45999874
OS 31.9411223 -36.61402634
OS 31.62492278 -36.61402634
OS 31.62492278 -36.50030546
OS 32.3849111 -36.50030546
OS 32.3849111 -36.61402634
OE
OB 30.62639798 -37.45999874 I
OS 30.48216662 -37.45999874
OS 30.36983258 -37.16876234
OS 29.96764898 -37.16876234
OS 29.86363598 -37.45999874
OS 29.7291125 -37.45999874
OS 30.09523826 -36.50030546
OS 30.23392226 -36.50030546
OS 30.62639798 -37.45999874
OE
OB 29.3546657 -36.5016923 I
OS 29.37824198 -36.50307914
OS 29.4032051 -36.50446598
OS 29.42678138 -36.50723966
OS 29.44758398 -36.51001334
OS 29.45035766 -36.51001334
OS 29.46006554 -36.51278702
OS 29.4725471 -36.5155607
OS 29.48918918 -36.51972122
OS 29.5072181 -36.52665542
OS 29.52663386 -36.53497646
OS 29.54743646 -36.54468434
OS 29.56546538 -36.55577906
OS 29.56823906 -36.5571659
OS 29.57378642 -36.56132642
OS 29.58210746 -36.56964746
OS 29.59320218 -36.57935534
OS 29.60568374 -36.5918369
OS 29.6181653 -36.60847898
OS 29.6320337 -36.6265079
OS 29.64312842 -36.6473105
OS 29.64451526 -36.65008418
OS 29.64728894 -36.65701838
OS 29.6528363 -36.66949994
OS 29.65838366 -36.68614202
OS 29.66254418 -36.70555778
OS 29.66809154 -36.72774722
OS 29.67086522 -36.75271034
OS 29.67225206 -36.7790603
OS 29.67225206 -36.78044714
OS 29.67225206 -36.78460766
OS 29.67225206 -36.79015502
OS 29.67086522 -36.7998629
OS 29.66947838 -36.80957078
OS 29.66809154 -36.82205234
OS 29.66531786 -36.83592074
OS 29.66254418 -36.85117598
OS 29.6528363 -36.8830733
OS 29.64728894 -36.89971538
OS 29.6389679 -36.9177443
OS 29.62926002 -36.93577322
OS 29.61955214 -36.9524153
OS 29.60707058 -36.96905738
OS 29.59320218 -36.98569946
OS 29.59181534 -36.9870863
OS 29.58904166 -36.98985998
OS 29.58488114 -36.9940205
OS 29.57794694 -36.99818102
OS 29.5696259 -37.00511522
OS 29.55853118 -37.01204942
OS 29.54466278 -37.02037046
OS 29.52940754 -37.02730466
OS 29.51137862 -37.0356257
OS 29.49057602 -37.04394674
OS 29.46838658 -37.05088094
OS 29.44203662 -37.0564283
OS 29.41429982 -37.06197566
OS 29.38378934 -37.06613618
OS 29.34911834 -37.06890986
OS 29.3130605 -37.0702967
OS 29.06758982 -37.0702967
OS 29.06758982 -37.45999874
OS 28.94000054 -37.45999874
OS 28.94000054 -36.50030546
OS 29.3338631 -36.50030546
OS 29.3546657 -36.5016923
OE
OB 31.18668134 -36.5016923 I
OS 31.1991629 -36.5016923
OS 31.22828654 -36.50307914
OS 31.25879702 -36.50723966
OS 31.29208118 -36.51140018
OS 31.32259166 -36.51833438
OS 31.3378469 -36.5224949
OS 31.35032846 -36.52665542
OS 31.3517153 -36.52665542
OS 31.35310214 -36.52804226
OS 31.36142318 -36.53220278
OS 31.37390474 -36.53775014
OS 31.38915998 -36.54745802
OS 31.40580206 -36.55993958
OS 31.42383098 -36.57658166
OS 31.44047306 -36.59599742
OS 31.45711514 -36.61818686
OS 31.45711514 -36.6195737
OS 31.45850198 -36.62096054
OS 31.46404934 -36.62928158
OS 31.4695967 -36.64314998
OS 31.47791774 -36.6611789
OS 31.48485194 -36.6819815
OS 31.49178614 -36.70694462
OS 31.49594666 -36.73329458
OS 31.4973335 -36.76241822
OS 31.4973335 -36.76380506
OS 31.4973335 -36.76657874
OS 31.4973335 -36.7721261
OS 31.49594666 -36.7790603
OS 31.49594666 -36.78876818
OS 31.49455982 -36.79847606
OS 31.48901246 -36.82205234
OS 31.48069142 -36.84978914
OS 31.4695967 -36.87891278
OS 31.45295462 -36.90803642
OS 31.4418599 -36.92190482
OS 31.43076518 -36.93577322
OS 31.42937834 -36.93716006
OS 31.4279915 -36.9385469
OS 31.42383098 -36.94270742
OS 31.41828362 -36.94686794
OS 31.41134942 -36.9524153
OS 31.40302838 -36.95796266
OS 31.39193366 -36.96489686
OS 31.38083894 -36.9732179
OS 31.36697054 -36.9801521
OS 31.3517153 -36.9870863
OS 31.33507322 -36.99540734
OS 31.3170443 -37.00234154
OS 31.2962417 -37.0078889
OS 31.2754391 -37.0148231
OS 31.25186282 -37.01898362
OS 31.2268997 -37.02314414
OS 31.22967338 -37.02453098
OS 31.23522074 -37.02730466
OS 31.24354178 -37.03285202
OS 31.2546365 -37.03839938
OS 31.27959962 -37.05365462
OS 31.29208118 -37.0633625
OS 31.3031759 -37.07168354
OS 31.30594958 -37.07445722
OS 31.31288378 -37.08139142
OS 31.3239785 -37.09248614
OS 31.3378469 -37.10635454
OS 31.35310214 -37.1257703
OS 31.37113106 -37.1465729
OS 31.38915998 -37.17153602
OS 31.40857574 -37.19927282
OS 31.5736097 -37.45999874
OS 31.41550994 -37.45999874
OS 31.2893075 -37.26029378
OS 31.2893075 -37.25890694
OS 31.28653382 -37.25613326
OS 31.28376014 -37.25197274
OS 31.27959962 -37.24642538
OS 31.26989174 -37.23117014
OS 31.25741018 -37.21175438
OS 31.24215494 -37.19095178
OS 31.2268997 -37.16876234
OS 31.21164446 -37.14795974
OS 31.19777606 -37.12854398
OS 31.19638922 -37.12715714
OS 31.1922287 -37.12160978
OS 31.1852945 -37.11328874
OS 31.17558662 -37.10358086
OS 31.15478402 -37.08277826
OS 31.1436893 -37.07307038
OS 31.13259458 -37.06474934
OS 31.13120774 -37.0633625
OS 31.12843406 -37.06197566
OS 31.1228867 -37.05920198
OS 31.11456566 -37.05504146
OS 31.10624462 -37.05088094
OS 31.09653674 -37.04672042
OS 31.0743473 -37.03978622
OS 31.07296046 -37.03978622
OS 31.07018678 -37.03839938
OS 31.06463942 -37.03839938
OS 31.05770522 -37.03701254
OS 31.04799734 -37.0356257
OS 31.03690262 -37.0356257
OS 31.02164738 -37.03423886
OS 30.85800026 -37.03423886
OS 30.85800026 -37.45999874
OS 30.73041098 -37.45999874
OS 30.73041098 -36.50030546
OS 31.17558662 -36.50030546
OS 31.18668134 -36.5016923
OE
OB 38.16387338 -36.60709214 H
OS 37.86154226 -36.60709214
OS 37.86154226 -36.9246785
OS 38.1472313 -36.9246785
OS 38.16387338 -36.92329166
OS 38.18328914 -36.92190482
OS 38.20547858 -36.92051798
OS 38.22766802 -36.9177443
OS 38.24985746 -36.91358378
OS 38.26927322 -36.90803642
OS 38.2720469 -36.90664958
OS 38.27759426 -36.9038759
OS 38.2859153 -36.89971538
OS 38.29701002 -36.89416802
OS 38.30949158 -36.88584698
OS 38.32197314 -36.8761391
OS 38.3344547 -36.86365754
OS 38.34416258 -36.84978914
OS 38.34554942 -36.8484023
OS 38.3483231 -36.84285494
OS 38.35248362 -36.8345339
OS 38.35803098 -36.82343918
OS 38.3621915 -36.81095762
OS 38.36635202 -36.79708922
OS 38.3691257 -36.78044714
OS 38.37051254 -36.76380506
OS 38.37051254 -36.76241822
OS 38.37051254 -36.76103138
OS 38.3691257 -36.75271034
OS 38.36773886 -36.74022878
OS 38.36496518 -36.7235867
OS 38.35803098 -36.70694462
OS 38.34970994 -36.68752886
OS 38.33722838 -36.66949994
OS 38.3205863 -36.65147102
OS 38.31781262 -36.65008418
OS 38.31087842 -36.64453682
OS 38.2997837 -36.63760262
OS 38.28175478 -36.62928158
OS 38.26095218 -36.62096054
OS 38.23321538 -36.61402634
OS 38.20131806 -36.60847898
OS 38.16387338 -36.60709214
OE
OB 29.34218414 -36.61402634 H
OS 29.06758982 -36.61402634
OS 29.06758982 -36.95657582
OS 29.32554206 -36.95657582
OS 29.33524994 -36.95518898
OS 29.34495782 -36.95518898
OS 29.35605254 -36.95380214
OS 29.3824025 -36.95102846
OS 29.41152614 -36.9454811
OS 29.44064978 -36.93716006
OS 29.46699974 -36.92606534
OS 29.4794813 -36.91913114
OS 29.48918918 -36.9108101
OS 29.49196286 -36.90803642
OS 29.49751022 -36.90248906
OS 29.50583126 -36.89139434
OS 29.51553914 -36.87752594
OS 29.52524702 -36.85949702
OS 29.53356806 -36.83730758
OS 29.53911542 -36.81234446
OS 29.5418891 -36.78322082
OS 29.5418891 -36.78183398
OS 29.5418891 -36.78044714
OS 29.5418891 -36.77351294
OS 29.54050226 -36.76103138
OS 29.53772858 -36.74716298
OS 29.5349549 -36.73190774
OS 29.52940754 -36.71387882
OS 29.5210865 -36.69723674
OS 29.51137862 -36.68059466
OS 29.50999178 -36.67920782
OS 29.50583126 -36.67366046
OS 29.49889706 -36.66672626
OS 29.49057602 -36.65701838
OS 29.47809446 -36.6473105
OS 29.46422606 -36.63898946
OS 29.44897082 -36.63066842
OS 29.4309419 -36.62373422
OS 29.42955506 -36.62373422
OS 29.4240077 -36.62234738
OS 29.41568666 -36.62096054
OS 29.40459194 -36.61818686
OS 29.38794986 -36.61680002
OS 29.36714726 -36.61541318
OS 29.34218414 -36.61402634
OE
OB 30.16180658 -36.60015794 H
OS 30.16180658 -36.60154478
OS 30.16041974 -36.60431846
OS 30.16041974 -36.60986582
OS 30.15764606 -36.61541318
OS 30.15625922 -36.62512106
OS 30.15348554 -36.63482894
OS 30.14793818 -36.65840522
OS 30.14100398 -36.68614202
OS 30.1312961 -36.7166525
OS 30.12158822 -36.74993666
OS 30.10910666 -36.78460766
OS 30.00509366 -37.06474934
OS 30.32961422 -37.06474934
OS 30.22976174 -36.80124974
OS 30.22976174 -36.7998629
OS 30.2283749 -36.79570238
OS 30.22560122 -36.78876818
OS 30.22282754 -36.78044714
OS 30.21866702 -36.77073926
OS 30.2145065 -36.7582577
OS 30.21034598 -36.7443893
OS 30.20479862 -36.7305209
OS 30.1937039 -36.69862358
OS 30.18260918 -36.66533942
OS 30.17151446 -36.63205526
OS 30.16180658 -36.60015794
OE
OB 31.16033138 -36.60709214 H
OS 30.85800026 -36.60709214
OS 30.85800026 -36.9246785
OS 31.1436893 -36.9246785
OS 31.16033138 -36.92329166
OS 31.17974714 -36.92190482
OS 31.20193658 -36.92051798
OS 31.22412602 -36.9177443
OS 31.24631546 -36.91358378
OS 31.26573122 -36.90803642
OS 31.2685049 -36.90664958
OS 31.27405226 -36.9038759
OS 31.2823733 -36.89971538
OS 31.29346802 -36.89416802
OS 31.30594958 -36.88584698
OS 31.31843114 -36.8761391
OS 31.3309127 -36.86365754
OS 31.34062058 -36.84978914
OS 31.34200742 -36.8484023
OS 31.3447811 -36.84285494
OS 31.34894162 -36.8345339
OS 31.35448898 -36.82343918
OS 31.3586495 -36.81095762
OS 31.36281002 -36.79708922
OS 31.3655837 -36.78044714
OS 31.36697054 -36.76380506
OS 31.36697054 -36.76241822
OS 31.36697054 -36.76103138
OS 31.3655837 -36.75271034
OS 31.36419686 -36.74022878
OS 31.36142318 -36.7235867
OS 31.35448898 -36.70694462
OS 31.34616794 -36.68752886
OS 31.33368638 -36.66949994
OS 31.3170443 -36.65147102
OS 31.31427062 -36.65008418
OS 31.30733642 -36.64453682
OS 31.2962417 -36.63760262
OS 31.27821278 -36.62928158
OS 31.25741018 -36.62096054
OS 31.22967338 -36.61402634
OS 31.19777606 -36.60847898
OS 31.16033138 -36.60709214
OE
OB 36.29302622 -36.61402634 H
OS 36.06558446 -36.61402634
OS 36.06558446 -36.90248906
OS 36.30134726 -36.90248906
OS 36.31937618 -36.90110222
OS 36.33879194 -36.89971538
OS 36.3582077 -36.89832854
OS 36.37762346 -36.89555486
OS 36.3928787 -36.89278118
OS 36.39565238 -36.89139434
OS 36.40119974 -36.8900075
OS 36.40952078 -36.88584698
OS 36.4206155 -36.88029962
OS 36.43171022 -36.87475226
OS 36.44419178 -36.86643122
OS 36.45667334 -36.8553365
OS 36.46638122 -36.84424178
OS 36.46776806 -36.84285494
OS 36.47054174 -36.83869442
OS 36.47470226 -36.83037338
OS 36.47886278 -36.8206655
OS 36.4830233 -36.80957078
OS 36.48718382 -36.79570238
OS 36.4899575 -36.7790603
OS 36.49134434 -36.76103138
OS 36.49134434 -36.7582577
OS 36.49134434 -36.75271034
OS 36.4899575 -36.7443893
OS 36.48857066 -36.73329458
OS 36.48579698 -36.71942618
OS 36.48163646 -36.70555778
OS 36.4760891 -36.69168938
OS 36.46776806 -36.67782098
OS 36.46638122 -36.67643414
OS 36.46360754 -36.67227362
OS 36.45806018 -36.66533942
OS 36.45112598 -36.65840522
OS 36.4414181 -36.65008418
OS 36.43032338 -36.64176314
OS 36.41645498 -36.6334421
OS 36.40119974 -36.62789474
OS 36.3998129 -36.62789474
OS 36.3928787 -36.62512106
OS 36.38317082 -36.62373422
OS 36.36791558 -36.62096054
OS 36.34711298 -36.61818686
OS 36.3235367 -36.61680002
OS 36.29302622 -36.61402634
OE
OB 36.31798934 -37.01620994 H
OS 36.06558446 -37.01620994
OS 36.06558446 -37.34627786
OS 36.33879194 -37.34627786
OS 36.36791558 -37.34489102
OS 36.38039714 -37.34350418
OS 36.39149186 -37.34211734
OS 36.3928787 -37.34211734
OS 36.39842606 -37.3407305
OS 36.4067471 -37.33934366
OS 36.41645498 -37.33656998
OS 36.44003126 -37.32824894
OS 36.46360754 -37.31715422
OS 36.46499438 -37.31576738
OS 36.4691549 -37.3129937
OS 36.47470226 -37.30883318
OS 36.48163646 -37.30328582
OS 36.48857066 -37.29496478
OS 36.49827854 -37.28664374
OS 36.50521274 -37.27554902
OS 36.51353378 -37.26306746
OS 36.51492062 -37.26168062
OS 36.51630746 -37.2575201
OS 36.51908114 -37.24919906
OS 36.52324166 -37.23949118
OS 36.52740218 -37.22839646
OS 36.53017586 -37.21452806
OS 36.5315627 -37.19788598
OS 36.53294954 -37.1812439
OS 36.53294954 -37.17847022
OS 36.53294954 -37.17292286
OS 36.5315627 -37.16182814
OS 36.52878902 -37.14934658
OS 36.52601534 -37.13547818
OS 36.52046798 -37.12022294
OS 36.51353378 -37.1049677
OS 36.5038259 -37.08971246
OS 36.50243906 -37.08832562
OS 36.49827854 -37.08277826
OS 36.49273118 -37.07584406
OS 36.48441014 -37.06752302
OS 36.47331542 -37.05781514
OS 36.45944702 -37.04810726
OS 36.44419178 -37.03978622
OS 36.42616286 -37.03285202
OS 36.42338918 -37.03146518
OS 36.41784182 -37.03007834
OS 36.40536026 -37.02730466
OS 36.39010502 -37.02453098
OS 36.37068926 -37.0217573
OS 36.34711298 -37.01898362
OS 36.31798934 -37.01620994
OE
SE
S P 0
OB 40.9056459 -38.32112732 I
OS 40.92136342 -38.32205188
OS 40.9380055 -38.32297644
OS 40.95372302 -38.32482556
OS 40.96759142 -38.32667468
OS 40.96944054 -38.32667468
OS 40.97591246 -38.3285238
OS 40.9842335 -38.33037292
OS 40.99532822 -38.3331466
OS 41.0073475 -38.3377694
OS 41.02029134 -38.34331676
OS 41.03415974 -38.34978868
OS 41.04617902 -38.35718516
OS 41.04802814 -38.35810972
OS 41.05172638 -38.3608834
OS 41.05727374 -38.36643076
OS 41.06467022 -38.37290268
OS 41.07299126 -38.38122372
OS 41.0813123 -38.39231844
OS 41.0905579 -38.40433772
OS 41.09795438 -38.41820612
OS 41.09887894 -38.42005524
OS 41.10072806 -38.42467804
OS 41.1044263 -38.43299908
OS 41.10812454 -38.4440938
OS 41.11089822 -38.45703764
OS 41.11459646 -38.4718306
OS 41.11644558 -38.48847268
OS 41.11737014 -38.50603932
OS 41.11737014 -38.50696388
OS 41.11737014 -38.50973756
OS 41.11737014 -38.5134358
OS 41.11644558 -38.51990772
OS 41.11552102 -38.52637964
OS 41.11459646 -38.53470068
OS 41.11274734 -38.54394628
OS 41.11089822 -38.55411644
OS 41.1044263 -38.57538132
OS 41.10072806 -38.58647604
OS 41.0951807 -38.59849532
OS 41.08870878 -38.6105146
OS 41.08223686 -38.62160932
OS 41.07391582 -38.63270404
OS 41.06467022 -38.64379876
OS 41.06374566 -38.64472332
OS 41.06189654 -38.64657244
OS 41.05912286 -38.64934612
OS 41.05450006 -38.6521198
OS 41.0489527 -38.6567426
OS 41.04155622 -38.6613654
OS 41.03231062 -38.66691276
OS 41.02214046 -38.67153556
OS 41.01012118 -38.67708292
OS 40.99625278 -38.68263028
OS 40.98145982 -38.68725308
OS 40.96389318 -38.69095132
OS 40.94540198 -38.69464956
OS 40.92506166 -38.69742324
OS 40.90194766 -38.69927236
OS 40.8779091 -38.70019692
OS 40.71426198 -38.70019692
OS 40.71426198 -38.95999828
OS 40.62920246 -38.95999828
OS 40.62920246 -38.32020276
OS 40.8917775 -38.32020276
OS 40.9056459 -38.32112732
OE
OB 40.49791494 -38.98403684 I
OS 40.49791494 -38.9849614
OS 40.49791494 -38.98773508
OS 40.49791494 -38.99235788
OS 40.49791494 -38.99790524
OS 40.49699038 -39.00530172
OS 40.49699038 -39.0126982
OS 40.49514126 -39.0311894
OS 40.49236758 -39.05060516
OS 40.48866934 -39.07094548
OS 40.48312198 -39.08851212
OS 40.47942374 -39.09683316
OS 40.4757255 -39.10330508
OS 40.4757255 -39.10422964
OS 40.47480094 -39.1051542
OS 40.47017814 -39.109777
OS 40.46278166 -39.11717348
OS 40.45353606 -39.12549452
OS 40.44059222 -39.13381556
OS 40.42395014 -39.14028748
OS 40.40453438 -39.14583484
OS 40.39343966 -39.1467594
OS 40.38142038 -39.14768396
OS 40.37587302 -39.14768396
OS 40.37032566 -39.1467594
OS 40.36200462 -39.1467594
OS 40.35275902 -39.14583484
OS 40.34258886 -39.14398572
OS 40.32039942 -39.13843836
OS 40.33519238 -39.07187004
OS 40.33611694 -39.07187004
OS 40.33889062 -39.0727946
OS 40.34351342 -39.07371916
OS 40.34813622 -39.07464372
OS 40.3601555 -39.0774174
OS 40.36570286 -39.07834196
OS 40.37494846 -39.07834196
OS 40.37957126 -39.0774174
OS 40.38511862 -39.07649284
OS 40.39066598 -39.07464372
OS 40.39621334 -39.07094548
OS 40.40268526 -39.06724724
OS 40.40730806 -39.06169988
OS 40.40823262 -39.06077532
OS 40.40915718 -39.05800164
OS 40.4110063 -39.05337884
OS 40.41377998 -39.04598236
OS 40.4156291 -39.0358122
OS 40.41655366 -39.02841572
OS 40.41747822 -39.0219438
OS 40.41840278 -39.01362276
OS 40.41840278 -39.0034526
OS 40.41932734 -38.99328244
OS 40.41932734 -38.98218772
OS 40.41932734 -38.49586916
OS 40.49791494 -38.49586916
OS 40.49791494 -38.98403684
OE
OB 41.51770462 -38.3100326 I
OS 41.52602566 -38.31095716
OS 41.53619582 -38.31188172
OS 41.54636598 -38.31280628
OS 41.55838526 -38.31557996
OS 41.58334838 -38.32112732
OS 41.61108518 -38.32944836
OS 41.62495358 -38.33499572
OS 41.63789742 -38.34146764
OS 41.65084126 -38.34978868
OS 41.6637851 -38.35810972
OS 41.66470966 -38.35903428
OS 41.66655878 -38.35995884
OS 41.67025702 -38.36273252
OS 41.67487982 -38.36735532
OS 41.67950262 -38.37197812
OS 41.68597454 -38.37845004
OS 41.69244646 -38.38584652
OS 41.69984294 -38.393243
OS 41.70723942 -38.4024886
OS 41.7146359 -38.41358332
OS 41.72295694 -38.42467804
OS 41.73035342 -38.43669732
OS 41.73682534 -38.45056572
OS 41.74422182 -38.46443412
OS 41.74976918 -38.47922708
OS 41.75531654 -38.49586916
OS 41.67210614 -38.51528492
OS 41.67210614 -38.51436036
OS 41.67118158 -38.51251124
OS 41.66933246 -38.508813
OS 41.66748334 -38.5041902
OS 41.66563422 -38.49864284
OS 41.66286054 -38.49124636
OS 41.65546406 -38.4764534
OS 41.64621846 -38.45981132
OS 41.63512374 -38.44316924
OS 41.62125534 -38.42745172
OS 41.60646238 -38.41358332
OS 41.60461326 -38.4117342
OS 41.5990659 -38.40803596
OS 41.5898203 -38.40341316
OS 41.57780102 -38.39694124
OS 41.5620835 -38.39139388
OS 41.54451686 -38.38584652
OS 41.52325198 -38.38214828
OS 41.50013798 -38.38122372
OS 41.4927415 -38.38122372
OS 41.4881187 -38.38214828
OS 41.48164678 -38.38214828
OS 41.4742503 -38.38307284
OS 41.45668366 -38.38584652
OS 41.4372679 -38.38954476
OS 41.41692758 -38.39601668
OS 41.3956627 -38.40526228
OS 41.37624694 -38.41728156
OS 41.37532238 -38.41728156
OS 41.37439782 -38.41913068
OS 41.3679259 -38.42375348
OS 41.35960486 -38.43114996
OS 41.3494347 -38.44224468
OS 41.33741542 -38.45611308
OS 41.3263207 -38.4718306
OS 41.31615054 -38.49124636
OS 41.30690494 -38.51251124
OS 41.30690494 -38.5134358
OS 41.30598038 -38.51528492
OS 41.30505582 -38.5180586
OS 41.30413126 -38.5226814
OS 41.30228214 -38.52822876
OS 41.30043302 -38.53470068
OS 41.29765934 -38.5504182
OS 41.2939611 -38.5689094
OS 41.29026286 -38.58924972
OS 41.28841374 -38.61143916
OS 41.28748918 -38.63547772
OS 41.28748918 -38.63640228
OS 41.28748918 -38.63917596
OS 41.28748918 -38.64379876
OS 41.28748918 -38.64934612
OS 41.28841374 -38.65581804
OS 41.28841374 -38.66413908
OS 41.2893383 -38.67338468
OS 41.29026286 -38.68355484
OS 41.29303654 -38.70574428
OS 41.29765934 -38.72978284
OS 41.3032067 -38.7538214
OS 41.31060318 -38.77785996
OS 41.31060318 -38.77878452
OS 41.31152774 -38.78063364
OS 41.31337686 -38.78340732
OS 41.31522598 -38.78803012
OS 41.32077334 -38.79912484
OS 41.32909438 -38.81206868
OS 41.33926454 -38.82686164
OS 41.35220838 -38.84257916
OS 41.36700134 -38.85644756
OS 41.38456798 -38.8693914
OS 41.38549254 -38.8693914
OS 41.38734166 -38.87031596
OS 41.39011534 -38.87216508
OS 41.39381358 -38.8740142
OS 41.39843638 -38.87586332
OS 41.40398374 -38.878637
OS 41.41692758 -38.88418436
OS 41.43356966 -38.88973172
OS 41.45206086 -38.89435452
OS 41.47240118 -38.89805276
OS 41.49366606 -38.89897732
OS 41.50013798 -38.89897732
OS 41.50568534 -38.89805276
OS 41.51215726 -38.89805276
OS 41.51862918 -38.8971282
OS 41.53527126 -38.89342996
OS 41.55468702 -38.88880716
OS 41.57410278 -38.88141068
OS 41.5944431 -38.87124052
OS 41.60461326 -38.86569316
OS 41.61385886 -38.85829668
OS 41.61478342 -38.85737212
OS 41.61570798 -38.85644756
OS 41.61848166 -38.85367388
OS 41.6221799 -38.8509002
OS 41.62587814 -38.8462774
OS 41.63050094 -38.84073004
OS 41.6360483 -38.83518268
OS 41.6406711 -38.8277862
OS 41.64621846 -38.81946516
OS 41.65269038 -38.81021956
OS 41.65823774 -38.80097396
OS 41.6637851 -38.78987924
OS 41.6684079 -38.77785996
OS 41.6730307 -38.76491612
OS 41.6776535 -38.75104772
OS 41.68135174 -38.73625476
OS 41.76641126 -38.75751964
OS 41.76641126 -38.7584442
OS 41.7654867 -38.76214244
OS 41.76363758 -38.7676898
OS 41.7608639 -38.77508628
OS 41.75809022 -38.78340732
OS 41.75439198 -38.79357748
OS 41.74976918 -38.8046722
OS 41.74422182 -38.81669148
OS 41.73127798 -38.84257916
OS 41.7146359 -38.86846684
OS 41.70446574 -38.88141068
OS 41.69429558 -38.89435452
OS 41.68320086 -38.90544924
OS 41.67025702 -38.91654396
OS 41.66933246 -38.91746852
OS 41.66748334 -38.91931764
OS 41.66286054 -38.92116676
OS 41.65823774 -38.924865
OS 41.65084126 -38.9294878
OS 41.64344478 -38.9341106
OS 41.63327462 -38.9387334
OS 41.62310446 -38.9433562
OS 41.61108518 -38.94890356
OS 41.59814134 -38.95352636
OS 41.58427294 -38.95814916
OS 41.56947998 -38.96277196
OS 41.55376246 -38.9664702
OS 41.53712038 -38.96831932
OS 41.51955374 -38.97016844
OS 41.50106254 -38.971093
OS 41.49089238 -38.971093
OS 41.4834959 -38.97016844
OS 41.47517486 -38.97016844
OS 41.4650047 -38.96924388
OS 41.45390998 -38.96739476
OS 41.44096614 -38.96554564
OS 41.4141539 -38.96092284
OS 41.3864171 -38.95352636
OS 41.3586803 -38.9433562
OS 41.34573646 -38.93688428
OS 41.33279262 -38.9294878
OS 41.33186806 -38.92856324
OS 41.33001894 -38.92763868
OS 41.3263207 -38.924865
OS 41.32262246 -38.92116676
OS 41.3170751 -38.91746852
OS 41.31060318 -38.91192116
OS 41.3032067 -38.90544924
OS 41.29581022 -38.89805276
OS 41.28841374 -38.88973172
OS 41.2800927 -38.88141068
OS 41.26345062 -38.8601458
OS 41.2477331 -38.83518268
OS 41.2338647 -38.80744588
OS 41.2338647 -38.80652132
OS 41.23201558 -38.80374764
OS 41.23109102 -38.79912484
OS 41.22831734 -38.79357748
OS 41.22646822 -38.786181
OS 41.22369454 -38.7769354
OS 41.2199963 -38.76676524
OS 41.21722262 -38.75567052
OS 41.21444894 -38.74365124
OS 41.2107507 -38.72978284
OS 41.2061279 -38.70112148
OS 41.20242966 -38.66876188
OS 41.20058054 -38.63547772
OS 41.20058054 -38.63455316
OS 41.20058054 -38.63085492
OS 41.20058054 -38.62530756
OS 41.2015051 -38.61883564
OS 41.2015051 -38.60959004
OS 41.20242966 -38.60034444
OS 41.20335422 -38.58832516
OS 41.20520334 -38.57630588
OS 41.20982614 -38.54949364
OS 41.21629806 -38.51990772
OS 41.22554366 -38.4903218
OS 41.2384875 -38.46166044
OS 41.23941206 -38.46073588
OS 41.24033662 -38.4579622
OS 41.24218574 -38.45426396
OS 41.24588398 -38.44964116
OS 41.24958222 -38.44316924
OS 41.25420502 -38.43577276
OS 41.2662243 -38.41913068
OS 41.28194182 -38.40063948
OS 41.30043302 -38.38214828
OS 41.3216979 -38.36365708
OS 41.34666102 -38.34793956
OS 41.34758558 -38.347015
OS 41.35035926 -38.34609044
OS 41.3540575 -38.34424132
OS 41.3586803 -38.34146764
OS 41.36607678 -38.33869396
OS 41.37347326 -38.33592028
OS 41.38271886 -38.33222204
OS 41.39288902 -38.3285238
OS 41.40398374 -38.32482556
OS 41.41600302 -38.32112732
OS 41.4418907 -38.31557996
OS 41.47147662 -38.31095716
OS 41.5019871 -38.30910804
OS 41.5112327 -38.30910804
OS 41.51770462 -38.3100326
OE
OB 42.90454462 -39.1375138 I
OS 42.38401734 -39.1375138
OS 42.38401734 -39.08111564
OS 42.90454462 -39.08111564
OS 42.90454462 -39.1375138
OE
OB 42.12514054 -38.32112732 I
OS 42.13253702 -38.32112732
OS 42.1491791 -38.32297644
OS 42.1676703 -38.32482556
OS 42.18708606 -38.3285238
OS 42.20650182 -38.3331466
OS 42.22406846 -38.33961852
OS 42.22499302 -38.33961852
OS 42.22591758 -38.34054308
OS 42.23146494 -38.34331676
OS 42.23978598 -38.34793956
OS 42.24903158 -38.35441148
OS 42.2601263 -38.36273252
OS 42.27214558 -38.37290268
OS 42.2832403 -38.38584652
OS 42.29341046 -38.39971492
OS 42.29433502 -38.40156404
OS 42.2971087 -38.4071114
OS 42.3017315 -38.41450788
OS 42.3063543 -38.4256026
OS 42.3109771 -38.43854644
OS 42.3155999 -38.45241484
OS 42.31837358 -38.46813236
OS 42.31929814 -38.48384988
OS 42.31929814 -38.485699
OS 42.31929814 -38.4903218
OS 42.31837358 -38.49864284
OS 42.31652446 -38.508813
OS 42.31375078 -38.52083228
OS 42.30912798 -38.53377612
OS 42.30358062 -38.54671996
OS 42.29618414 -38.56058836
OS 42.29525958 -38.56243748
OS 42.2924859 -38.56613572
OS 42.28693854 -38.5735322
OS 42.27954206 -38.58092868
OS 42.27029646 -38.59017428
OS 42.25920174 -38.60034444
OS 42.24533334 -38.60959004
OS 42.22961582 -38.61883564
OS 42.23054038 -38.61883564
OS 42.2323895 -38.6197602
OS 42.23516318 -38.62068476
OS 42.23886142 -38.62253388
OS 42.24995614 -38.62623212
OS 42.26289998 -38.63270404
OS 42.27676838 -38.64102508
OS 42.2924859 -38.65119524
OS 42.3063543 -38.66321452
OS 42.31929814 -38.67800748
OS 42.3202227 -38.6798566
OS 42.32392094 -38.68540396
OS 42.3294683 -38.693725
OS 42.33501566 -38.70481972
OS 42.34056302 -38.71961268
OS 42.34611038 -38.7353302
OS 42.34980862 -38.7538214
OS 42.35073318 -38.77416172
OS 42.35073318 -38.77508628
OS 42.35073318 -38.77601084
OS 42.35073318 -38.7815582
OS 42.34980862 -38.7908038
OS 42.3479595 -38.80189852
OS 42.34611038 -38.81484236
OS 42.34241214 -38.82871076
OS 42.33778934 -38.84350372
OS 42.33131742 -38.85829668
OS 42.33039286 -38.8601458
OS 42.32761918 -38.8647686
OS 42.32392094 -38.87124052
OS 42.31837358 -38.88048612
OS 42.3109771 -38.88973172
OS 42.30358062 -38.89990188
OS 42.29433502 -38.91007204
OS 42.28416486 -38.91839308
OS 42.2832403 -38.91931764
OS 42.27954206 -38.92209132
OS 42.27307014 -38.92578956
OS 42.2647491 -38.9294878
OS 42.25457894 -38.93503516
OS 42.24255966 -38.94058252
OS 42.22961582 -38.94520532
OS 42.2138983 -38.94982812
OS 42.21204918 -38.94982812
OS 42.20650182 -38.95167724
OS 42.19725622 -38.9526018
OS 42.18523694 -38.95445092
OS 42.17044398 -38.95630004
OS 42.15287734 -38.95814916
OS 42.13346158 -38.95907372
OS 42.11127214 -38.95999828
OS 41.8671883 -38.95999828
OS 41.8671883 -38.32020276
OS 42.11866862 -38.32020276
OS 42.12514054 -38.32112732
OE
OB 40.30745558 -38.48662356 I
OS 40.31762574 -38.48847268
OS 40.32964502 -38.49217092
OS 40.34258886 -38.49679372
OS 40.35738182 -38.50326564
OS 40.37309934 -38.51158668
OS 40.34443798 -38.58370236
OS 40.34351342 -38.5827778
OS 40.33981518 -38.58092868
OS 40.33426782 -38.578155
OS 40.32687134 -38.57538132
OS 40.3185503 -38.57260764
OS 40.30838014 -38.56983396
OS 40.29820998 -38.56798484
OS 40.28803982 -38.56706028
OS 40.28341702 -38.56706028
OS 40.27879422 -38.56798484
OS 40.2723223 -38.5689094
OS 40.26585038 -38.57075852
OS 40.25752934 -38.5735322
OS 40.2492083 -38.57723044
OS 40.24181182 -38.5827778
OS 40.24088726 -38.58370236
OS 40.23811358 -38.58555148
OS 40.2353399 -38.58924972
OS 40.2307171 -38.59387252
OS 40.2260943 -38.60034444
OS 40.2214715 -38.60774092
OS 40.2168487 -38.61606196
OS 40.21315046 -38.62623212
OS 40.2122259 -38.62808124
OS 40.21130134 -38.6336286
OS 40.20945222 -38.64194964
OS 40.20667854 -38.65304436
OS 40.20390486 -38.66691276
OS 40.20205574 -38.68263028
OS 40.20113118 -38.69927236
OS 40.20020662 -38.71776356
OS 40.20020662 -38.95999828
OS 40.12161902 -38.95999828
OS 40.12161902 -38.49586916
OS 40.19281014 -38.49586916
OS 40.19281014 -38.56613572
OS 40.1937347 -38.56521116
OS 40.19743294 -38.55873924
OS 40.20205574 -38.5504182
OS 40.20945222 -38.54024804
OS 40.2168487 -38.53007788
OS 40.22516974 -38.51898316
OS 40.23349078 -38.50973756
OS 40.24181182 -38.50234108
OS 40.24273638 -38.50141652
OS 40.24551006 -38.4995674
OS 40.25105742 -38.49679372
OS 40.25660478 -38.49402004
OS 40.26400126 -38.49124636
OS 40.27324686 -38.48847268
OS 40.28249246 -38.48662356
OS 40.29266262 -38.485699
OS 40.29913454 -38.485699
OS 40.30745558 -38.48662356
OE
OB 39.48829542 -38.95999828 I
OS 39.3986131 -38.95999828
OS 39.3986131 -38.87031596
OS 39.48829542 -38.87031596
OS 39.48829542 -38.95999828
OE
OB 38.6404739 -38.95999828 I
OS 38.55171614 -38.95999828
OS 38.30393406 -38.32020276
OS 38.39639006 -38.32020276
OS 38.56281086 -38.78525644
OS 38.56281086 -38.786181
OS 38.56373542 -38.78803012
OS 38.56465998 -38.7908038
OS 38.5665091 -38.79450204
OS 38.56743366 -38.8000494
OS 38.56928278 -38.80559676
OS 38.57390558 -38.81946516
OS 38.57945294 -38.83518268
OS 38.5850003 -38.85274932
OS 38.59609502 -38.88973172
OS 38.59609502 -38.88880716
OS 38.59701958 -38.88695804
OS 38.59794414 -38.88418436
OS 38.5988687 -38.88048612
OS 38.60164238 -38.87031596
OS 38.60626518 -38.85644756
OS 38.61088798 -38.84073004
OS 38.61643534 -38.8231634
OS 38.62290726 -38.8046722
OS 38.63030374 -38.78525644
OS 38.80412102 -38.32020276
OS 38.8901051 -38.32020276
OS 38.6404739 -38.95999828
OE
OB 39.27564662 -38.42745172 I
OS 39.25438174 -38.54671996
OS 39.20538006 -38.54671996
OS 39.1859643 -38.42745172
OS 39.1859643 -38.32020276
OS 39.27564662 -38.32020276
OS 39.27564662 -38.42745172
OE
OB 40.49791494 -38.4117342 I
OS 40.41932734 -38.4117342
OS 40.41932734 -38.32020276
OS 40.49791494 -38.32020276
OS 40.49791494 -38.4117342
OE
OB 39.84517558 -38.48662356 I
OS 39.8516475 -38.48754812
OS 39.8655159 -38.48939724
OS 39.88215798 -38.49309548
OS 39.89972462 -38.49864284
OS 39.91729126 -38.50696388
OS 39.9348579 -38.51713404
OS 39.93578246 -38.51713404
OS 39.93670702 -38.51898316
OS 39.94225438 -38.5226814
OS 39.95057542 -38.53007788
OS 39.96074558 -38.53932348
OS 39.9718403 -38.55134276
OS 39.98293502 -38.56613572
OS 39.99402974 -38.58370236
OS 40.00327534 -38.60311812
OS 40.00327534 -38.60404268
OS 40.0041999 -38.6058918
OS 40.00512446 -38.60866548
OS 40.00697358 -38.61236372
OS 40.0088227 -38.61791108
OS 40.01067182 -38.624383
OS 40.01529462 -38.63917596
OS 40.01991742 -38.65766716
OS 40.02361566 -38.67800748
OS 40.02638934 -38.70112148
OS 40.0273139 -38.72516004
OS 40.0273139 -38.7260846
OS 40.0273139 -38.72793372
OS 40.0273139 -38.73163196
OS 40.0273139 -38.73717932
OS 40.02638934 -38.74365124
OS 40.02638934 -38.75104772
OS 40.02454022 -38.7676898
OS 40.02084198 -38.78803012
OS 40.01621918 -38.809295
OS 40.00974726 -38.83148444
OS 40.00142622 -38.85367388
OS 40.00142622 -38.85459844
OS 40.00050166 -38.85644756
OS 39.99865254 -38.85922124
OS 39.99680342 -38.86291948
OS 39.9903315 -38.87308964
OS 39.98201046 -38.88603348
OS 39.9718403 -38.89990188
OS 39.95889646 -38.91377028
OS 39.9441035 -38.92763868
OS 39.92653686 -38.94058252
OS 39.9256123 -38.94058252
OS 39.92468774 -38.94150708
OS 39.92191406 -38.9433562
OS 39.91821582 -38.94520532
OS 39.90897022 -38.94982812
OS 39.89602638 -38.95537548
OS 39.88030886 -38.96092284
OS 39.86366678 -38.96554564
OS 39.84425102 -38.96924388
OS 39.82483526 -38.97016844
OS 39.81836334 -38.97016844
OS 39.81096686 -38.96924388
OS 39.80172126 -38.96831932
OS 39.79062654 -38.9664702
OS 39.77860726 -38.96369652
OS 39.76658798 -38.95999828
OS 39.7545687 -38.95445092
OS 39.75364414 -38.95352636
OS 39.74902134 -38.95167724
OS 39.74347398 -38.947979
OS 39.7360775 -38.94243164
OS 39.72868102 -38.93688428
OS 39.71943542 -38.9294878
OS 39.71111438 -38.92116676
OS 39.7037179 -38.91192116
OS 39.7037179 -39.1375138
OS 39.6251303 -39.1375138
OS 39.6251303 -38.49586916
OS 39.69632142 -38.49586916
OS 39.69632142 -38.55689012
OS 39.69724598 -38.555041
OS 39.70094422 -38.55134276
OS 39.70556702 -38.54487084
OS 39.7129635 -38.53747436
OS 39.72128454 -38.52822876
OS 39.73053014 -38.51990772
OS 39.74162486 -38.51158668
OS 39.75271958 -38.5041902
OS 39.7545687 -38.50326564
OS 39.75826694 -38.50141652
OS 39.76566342 -38.49864284
OS 39.77490902 -38.4949446
OS 39.78600374 -38.49124636
OS 39.79894758 -38.48847268
OS 39.81374054 -38.48662356
OS 39.83038262 -38.485699
OS 39.84055278 -38.485699
OS 39.84517558 -38.48662356
OE
OB 44.92193454 -38.40988508 I
OS 44.84334694 -38.40988508
OS 44.84334694 -38.32020276
OS 44.92193454 -38.32020276
OS 44.92193454 -38.40988508
OE
OB 45.24553054 -38.48662356 I
OS 45.25385158 -38.48754812
OS 45.26309718 -38.48939724
OS 45.27326734 -38.49124636
OS 45.28528662 -38.49309548
OS 45.31024974 -38.50141652
OS 45.32319358 -38.50603932
OS 45.33613742 -38.51251124
OS 45.34908126 -38.51898316
OS 45.3620251 -38.52822876
OS 45.37404438 -38.53747436
OS 45.38606366 -38.54856908
OS 45.38698822 -38.54949364
OS 45.38883734 -38.55134276
OS 45.39161102 -38.555041
OS 45.39530926 -38.5596638
OS 45.39993206 -38.56613572
OS 45.40547942 -38.57445676
OS 45.41102678 -38.58370236
OS 45.41657414 -38.59387252
OS 45.4221215 -38.60496724
OS 45.42766886 -38.61883564
OS 45.43321622 -38.63270404
OS 45.43783902 -38.64842156
OS 45.44153726 -38.66506364
OS 45.44431094 -38.68263028
OS 45.44616006 -38.70112148
OS 45.44708462 -38.7214618
OS 45.44708462 -38.72238636
OS 45.44708462 -38.72516004
OS 45.44708462 -38.72978284
OS 45.44708462 -38.73625476
OS 45.44616006 -38.74365124
OS 45.4452355 -38.75289684
OS 45.4452355 -38.76214244
OS 45.44338638 -38.7723126
OS 45.4406127 -38.7954266
OS 45.43506534 -38.8185406
OS 45.42859342 -38.8416546
OS 45.41934782 -38.86291948
OS 45.41934782 -38.86384404
OS 45.41842326 -38.8647686
OS 45.41657414 -38.86754228
OS 45.41472502 -38.87124052
OS 45.4082531 -38.88048612
OS 45.39993206 -38.89158084
OS 45.38883734 -38.90452468
OS 45.37496894 -38.91746852
OS 45.35925142 -38.93041236
OS 45.34076022 -38.94243164
OS 45.33983566 -38.94243164
OS 45.3389111 -38.9433562
OS 45.33613742 -38.94520532
OS 45.33151462 -38.94705444
OS 45.32689182 -38.94890356
OS 45.32134446 -38.95075268
OS 45.30747606 -38.95630004
OS 45.29175854 -38.96092284
OS 45.27234278 -38.96554564
OS 45.25200246 -38.96924388
OS 45.22981302 -38.97016844
OS 45.22056742 -38.97016844
OS 45.21317094 -38.96924388
OS 45.2048499 -38.96831932
OS 45.1956043 -38.9664702
OS 45.18450958 -38.96462108
OS 45.17341486 -38.96277196
OS 45.14845174 -38.95537548
OS 45.13458334 -38.94982812
OS 45.1216395 -38.94428076
OS 45.10869566 -38.93688428
OS 45.09575182 -38.92856324
OS 45.08373254 -38.91931764
OS 45.07171326 -38.90822292
OS 45.0707887 -38.90729836
OS 45.06893958 -38.90544924
OS 45.0661659 -38.901751
OS 45.06246766 -38.89620364
OS 45.05784486 -38.88973172
OS 45.05322206 -38.88233524
OS 45.0476747 -38.87308964
OS 45.04212734 -38.86199492
OS 45.03657998 -38.84997564
OS 45.03103262 -38.83610724
OS 45.02640982 -38.82131428
OS 45.02178702 -38.80559676
OS 45.01808878 -38.78803012
OS 45.0153151 -38.76953892
OS 45.01346598 -38.7491986
OS 45.01254142 -38.72793372
OS 45.01254142 -38.7260846
OS 45.01254142 -38.72238636
OS 45.01346598 -38.71591444
OS 45.01346598 -38.70666884
OS 45.01439054 -38.69649868
OS 45.01623966 -38.68355484
OS 45.01808878 -38.670611
OS 45.02178702 -38.65581804
OS 45.02548526 -38.64102508
OS 45.03010806 -38.62530756
OS 45.03565542 -38.60866548
OS 45.0430519 -38.59294796
OS 45.05044838 -38.578155
OS 45.06061854 -38.56336204
OS 45.0707887 -38.54949364
OS 45.08373254 -38.53747436
OS 45.0846571 -38.5365498
OS 45.08650622 -38.53562524
OS 45.09020446 -38.53285156
OS 45.09482726 -38.52915332
OS 45.10037462 -38.52545508
OS 45.1077711 -38.52083228
OS 45.11516758 -38.51620948
OS 45.12441318 -38.51158668
OS 45.13458334 -38.50696388
OS 45.14567806 -38.50234108
OS 45.17064118 -38.49402004
OS 45.19930254 -38.48754812
OS 45.2140955 -38.48662356
OS 45.22981302 -38.485699
OS 45.23905862 -38.485699
OS 45.24553054 -38.48662356
OE
OB 44.92193454 -38.95999828 I
OS 44.84334694 -38.95999828
OS 44.84334694 -38.49586916
OS 44.92193454 -38.49586916
OS 44.92193454 -38.95999828
OE
OB 46.10722046 -38.42745172 I
OS 46.08595558 -38.54671996
OS 46.0369539 -38.54671996
OS 46.01753814 -38.42745172
OS 46.01753814 -38.32020276
OS 46.10722046 -38.32020276
OS 46.10722046 -38.42745172
OE
OB 45.77160518 -38.48662356 I
OS 45.78177534 -38.48754812
OS 45.79379462 -38.48939724
OS 45.80673846 -38.49217092
OS 45.82060686 -38.49586916
OS 45.8335507 -38.50141652
OS 45.83539982 -38.50234108
OS 45.83909806 -38.5041902
OS 45.84556998 -38.50696388
OS 45.85296646 -38.51158668
OS 45.86221206 -38.51713404
OS 45.8705331 -38.52453052
OS 45.87885414 -38.531927
OS 45.88625062 -38.5411726
OS 45.88717518 -38.54209716
OS 45.8890243 -38.5457954
OS 45.89179798 -38.5504182
OS 45.89642078 -38.55689012
OS 45.90011902 -38.56613572
OS 45.90381726 -38.57538132
OS 45.90844006 -38.58647604
OS 45.91121374 -38.59849532
OS 45.91121374 -38.59941988
OS 45.9121383 -38.60311812
OS 45.91306286 -38.60866548
OS 45.91398742 -38.61606196
OS 45.91398742 -38.62715668
OS 45.91491198 -38.64010052
OS 45.91583654 -38.65581804
OS 45.91583654 -38.6752338
OS 45.91583654 -38.95999828
OS 45.83724894 -38.95999828
OS 45.83724894 -38.67893204
OS 45.83724894 -38.67800748
OS 45.83724894 -38.67708292
OS 45.83724894 -38.670611
OS 45.83724894 -38.66228996
OS 45.83632438 -38.6521198
OS 45.83539982 -38.64010052
OS 45.8335507 -38.62808124
OS 45.83077702 -38.61698652
OS 45.82800334 -38.60681636
OS 45.82800334 -38.6058918
OS 45.82615422 -38.60311812
OS 45.82338054 -38.59849532
OS 45.82060686 -38.59294796
OS 45.81598406 -38.5874006
OS 45.8104367 -38.58092868
OS 45.80304022 -38.57445676
OS 45.79471918 -38.5689094
OS 45.79379462 -38.56798484
OS 45.79102094 -38.56613572
OS 45.78547358 -38.5642866
OS 45.77900166 -38.56151292
OS 45.77160518 -38.55873924
OS 45.76235958 -38.55596556
OS 45.75126486 -38.555041
OS 45.74017014 -38.55411644
OS 45.73554734 -38.55411644
OS 45.7318491 -38.555041
OS 45.7226035 -38.55596556
OS 45.71058422 -38.55781468
OS 45.69764038 -38.56243748
OS 45.68284742 -38.56798484
OS 45.66805446 -38.57538132
OS 45.65418606 -38.58647604
OS 45.65233694 -38.58832516
OS 45.6486387 -38.59294796
OS 45.64586502 -38.5966462
OS 45.64309134 -38.601269
OS 45.6393931 -38.60681636
OS 45.63661942 -38.61328828
OS 45.63292118 -38.62068476
OS 45.62922294 -38.62993036
OS 45.62644926 -38.64010052
OS 45.62367558 -38.65119524
OS 45.62182646 -38.66321452
OS 45.61997734 -38.67615836
OS 45.61812822 -38.69187588
OS 45.61812822 -38.7075934
OS 45.61812822 -38.95999828
OS 45.53954062 -38.95999828
OS 45.53954062 -38.49586916
OS 45.60980718 -38.49586916
OS 45.60980718 -38.56243748
OS 45.61073174 -38.56151292
OS 45.61258086 -38.55873924
OS 45.61535454 -38.555041
OS 45.61905278 -38.5504182
OS 45.62460014 -38.54487084
OS 45.63107206 -38.53839892
OS 45.63846854 -38.53100244
OS 45.64771414 -38.52360596
OS 45.65695974 -38.51713404
OS 45.66805446 -38.50973756
OS 45.68007374 -38.50326564
OS 45.69301758 -38.49771828
OS 45.70781054 -38.49309548
OS 45.7226035 -38.48939724
OS 45.73924558 -38.48662356
OS 45.75681222 -38.485699
OS 45.7642087 -38.485699
OS 45.77160518 -38.48662356
OE
OB 44.2756671 -38.95999828 I
OS 44.1970795 -38.95999828
OS 44.1970795 -38.49586916
OS 44.2756671 -38.49586916
OS 44.2756671 -38.95999828
OE
OB 43.4574315 -38.48662356 I
OS 43.46482798 -38.48754812
OS 43.47407358 -38.48939724
OS 43.48424374 -38.49124636
OS 43.49626302 -38.49402004
OS 43.50735774 -38.49679372
OS 43.52030158 -38.50141652
OS 43.53232086 -38.50603932
OS 43.5452647 -38.51251124
OS 43.55820854 -38.51990772
OS 43.57115238 -38.52822876
OS 43.58317166 -38.53839892
OS 43.59426638 -38.54949364
OS 43.59519094 -38.5504182
OS 43.59704006 -38.55226732
OS 43.59981374 -38.55596556
OS 43.60351198 -38.56151292
OS 43.60813478 -38.56798484
OS 43.61275758 -38.57538132
OS 43.61830494 -38.58462692
OS 43.6238523 -38.59572164
OS 43.62939966 -38.60774092
OS 43.63494702 -38.62068476
OS 43.63956982 -38.63547772
OS 43.64419262 -38.65119524
OS 43.64789086 -38.66876188
OS 43.65066454 -38.68725308
OS 43.65251366 -38.70666884
OS 43.65343822 -38.72793372
OS 43.65343822 -38.72885828
OS 43.65343822 -38.73255652
OS 43.65343822 -38.73902844
OS 43.65251366 -38.74827404
OS 43.30580366 -38.74827404
OS 43.30580366 -38.7491986
OS 43.30580366 -38.75197228
OS 43.30672822 -38.75567052
OS 43.30672822 -38.76121788
OS 43.30765278 -38.7676898
OS 43.3095019 -38.77508628
OS 43.31227558 -38.79172836
OS 43.31782294 -38.81021956
OS 43.32521942 -38.83055988
OS 43.33538958 -38.84905108
OS 43.34833342 -38.86569316
OS 43.34925798 -38.86569316
OS 43.35018254 -38.86754228
OS 43.3557299 -38.87216508
OS 43.36405094 -38.878637
OS 43.37514566 -38.88510892
OS 43.38993862 -38.8925054
OS 43.4065807 -38.89897732
OS 43.4250719 -38.90360012
OS 43.43524206 -38.90452468
OS 43.44633678 -38.90544924
OS 43.45373326 -38.90544924
OS 43.4620543 -38.90452468
OS 43.47222446 -38.90267556
OS 43.48331918 -38.89990188
OS 43.49626302 -38.89620364
OS 43.5082823 -38.89065628
OS 43.52030158 -38.8832598
OS 43.52122614 -38.88233524
OS 43.52584894 -38.878637
OS 43.5313963 -38.87308964
OS 43.53786822 -38.86569316
OS 43.5452647 -38.855523
OS 43.55358574 -38.84257916
OS 43.56190678 -38.8277862
OS 43.56930326 -38.81021956
OS 43.65066454 -38.82038972
OS 43.65066454 -38.82131428
OS 43.64973998 -38.8231634
OS 43.64881542 -38.82686164
OS 43.6469663 -38.832409
OS 43.64419262 -38.83795636
OS 43.64141894 -38.84535284
OS 43.63402246 -38.86107036
OS 43.62477686 -38.878637
OS 43.61183302 -38.8971282
OS 43.59704006 -38.91469484
OS 43.57854886 -38.93133692
OS 43.5776243 -38.93133692
OS 43.57577518 -38.93318604
OS 43.5730015 -38.93503516
OS 43.56930326 -38.93780884
OS 43.5637559 -38.94058252
OS 43.55820854 -38.9433562
OS 43.55081206 -38.94705444
OS 43.54249102 -38.95075268
OS 43.53324542 -38.95445092
OS 43.52399982 -38.95814916
OS 43.50088582 -38.96369652
OS 43.47499814 -38.96831932
OS 43.44633678 -38.97016844
OS 43.43616662 -38.97016844
OS 43.4296947 -38.96924388
OS 43.42137366 -38.96831932
OS 43.4112035 -38.9664702
OS 43.40010878 -38.96462108
OS 43.3880895 -38.96277196
OS 43.36220182 -38.95537548
OS 43.34833342 -38.94982812
OS 43.33538958 -38.94428076
OS 43.32152118 -38.93688428
OS 43.30857734 -38.92856324
OS 43.29655806 -38.91931764
OS 43.28453878 -38.90822292
OS 43.28361422 -38.90729836
OS 43.2817651 -38.90544924
OS 43.27899142 -38.901751
OS 43.27529318 -38.89620364
OS 43.27067038 -38.88973172
OS 43.26604758 -38.88233524
OS 43.26050022 -38.87308964
OS 43.25495286 -38.86291948
OS 43.2494055 -38.8509002
OS 43.24385814 -38.83795636
OS 43.23923534 -38.8231634
OS 43.23461254 -38.80744588
OS 43.2309143 -38.7908038
OS 43.22814062 -38.7723126
OS 43.2262915 -38.75289684
OS 43.22536694 -38.73255652
OS 43.22536694 -38.73163196
OS 43.22536694 -38.72700916
OS 43.22536694 -38.7214618
OS 43.2262915 -38.71314076
OS 43.22721606 -38.7029706
OS 43.22814062 -38.69187588
OS 43.22998974 -38.67893204
OS 43.23276342 -38.6659882
OS 43.2401599 -38.63640228
OS 43.2447827 -38.62160932
OS 43.25033006 -38.6058918
OS 43.25772654 -38.59109884
OS 43.26604758 -38.57723044
OS 43.27529318 -38.56336204
OS 43.28546334 -38.5504182
OS 43.2863879 -38.54949364
OS 43.28823702 -38.54764452
OS 43.29193526 -38.54487084
OS 43.29655806 -38.54024804
OS 43.30210542 -38.53562524
OS 43.3095019 -38.53007788
OS 43.31782294 -38.52360596
OS 43.3279931 -38.5180586
OS 43.33816326 -38.51158668
OS 43.35018254 -38.50603932
OS 43.36312638 -38.50049196
OS 43.37699478 -38.49586916
OS 43.39178774 -38.49124636
OS 43.40750526 -38.48847268
OS 43.42414734 -38.48662356
OS 43.44171398 -38.485699
OS 43.45095958 -38.485699
OS 43.4574315 -38.48662356
OE
OB 43.13938286 -38.48662356 I
OS 43.14955302 -38.48847268
OS 43.1615723 -38.49217092
OS 43.17451614 -38.49679372
OS 43.1893091 -38.50326564
OS 43.20502662 -38.51158668
OS 43.17636526 -38.58370236
OS 43.1754407 -38.5827778
OS 43.17174246 -38.58092868
OS 43.1661951 -38.578155
OS 43.15879862 -38.57538132
OS 43.15047758 -38.57260764
OS 43.14030742 -38.56983396
OS 43.13013726 -38.56798484
OS 43.1199671 -38.56706028
OS 43.1153443 -38.56706028
OS 43.1107215 -38.56798484
OS 43.10424958 -38.5689094
OS 43.09777766 -38.57075852
OS 43.08945662 -38.5735322
OS 43.08113558 -38.57723044
OS 43.0737391 -38.5827778
OS 43.07281454 -38.58370236
OS 43.07004086 -38.58555148
OS 43.06726718 -38.58924972
OS 43.06264438 -38.59387252
OS 43.05802158 -38.60034444
OS 43.05339878 -38.60774092
OS 43.04877598 -38.61606196
OS 43.04507774 -38.62623212
OS 43.04415318 -38.62808124
OS 43.04322862 -38.6336286
OS 43.0413795 -38.64194964
OS 43.03860582 -38.65304436
OS 43.03583214 -38.66691276
OS 43.03398302 -38.68263028
OS 43.03305846 -38.69927236
OS 43.0321339 -38.71776356
OS 43.0321339 -38.95999828
OS 42.9535463 -38.95999828
OS 42.9535463 -38.49586916
OS 43.02473742 -38.49586916
OS 43.02473742 -38.56613572
OS 43.02566198 -38.56521116
OS 43.02936022 -38.55873924
OS 43.03398302 -38.5504182
OS 43.0413795 -38.54024804
OS 43.04877598 -38.53007788
OS 43.05709702 -38.51898316
OS 43.06541806 -38.50973756
OS 43.0737391 -38.50234108
OS 43.07466366 -38.50141652
OS 43.07743734 -38.4995674
OS 43.0829847 -38.49679372
OS 43.08853206 -38.49402004
OS 43.09592854 -38.49124636
OS 43.10517414 -38.48847268
OS 43.11441974 -38.48662356
OS 43.1245899 -38.485699
OS 43.13106182 -38.485699
OS 43.13938286 -38.48662356
OE
OB 43.95022198 -38.95999828 I
OS 43.87533262 -38.95999828
OS 43.70059078 -38.49586916
OS 43.78380118 -38.49586916
OS 43.88365366 -38.77416172
OS 43.88365366 -38.77508628
OS 43.88457822 -38.77601084
OS 43.88550278 -38.77878452
OS 43.88642734 -38.7815582
OS 43.88920102 -38.7908038
OS 43.89289926 -38.80282308
OS 43.89752206 -38.81669148
OS 43.90306942 -38.832409
OS 43.90769222 -38.84997564
OS 43.91323958 -38.86754228
OS 43.91416414 -38.86569316
OS 43.9150887 -38.86107036
OS 43.91786238 -38.85367388
OS 43.92063606 -38.84257916
OS 43.92525886 -38.83055988
OS 43.92988166 -38.81484236
OS 43.93635358 -38.79820028
OS 43.9428255 -38.77970908
OS 44.04545166 -38.49586916
OS 44.12681294 -38.49586916
OS 43.95022198 -38.95999828
OE
OB 44.2756671 -38.40988508 I
OS 44.1970795 -38.40988508
OS 44.1970795 -38.32020276
OS 44.2756671 -38.32020276
OS 44.2756671 -38.40988508
OE
OB 44.5669035 -38.48662356 I
OS 44.5807719 -38.48754812
OS 44.59556486 -38.48939724
OS 44.61128238 -38.49309548
OS 44.62792446 -38.49679372
OS 44.64364198 -38.50234108
OS 44.64456654 -38.50234108
OS 44.6454911 -38.50326564
OS 44.6501139 -38.50511476
OS 44.65751038 -38.508813
OS 44.66675598 -38.5134358
OS 44.67692614 -38.51990772
OS 44.6870963 -38.5273042
OS 44.6963419 -38.53562524
OS 44.70466294 -38.54487084
OS 44.7055875 -38.5457954
OS 44.70743662 -38.54949364
OS 44.71113486 -38.55596556
OS 44.71575766 -38.56336204
OS 44.72038046 -38.57445676
OS 44.72500326 -38.58647604
OS 44.7287015 -38.60034444
OS 44.73239974 -38.61606196
OS 44.65566126 -38.62623212
OS 44.65566126 -38.624383
OS 44.6547367 -38.62068476
OS 44.65288758 -38.61421284
OS 44.6501139 -38.6058918
OS 44.6454911 -38.59757076
OS 44.63994374 -38.58832516
OS 44.63347182 -38.57907956
OS 44.62422622 -38.57075852
OS 44.62330166 -38.56983396
OS 44.61960342 -38.56798484
OS 44.61405606 -38.5642866
OS 44.60573502 -38.56058836
OS 44.59648942 -38.55689012
OS 44.58447014 -38.55319188
OS 44.56967718 -38.55134276
OS 44.55395966 -38.5504182
OS 44.54471406 -38.5504182
OS 44.53546846 -38.55134276
OS 44.52344918 -38.55226732
OS 44.5114299 -38.555041
OS 44.49848606 -38.55781468
OS 44.48646678 -38.56243748
OS 44.47629662 -38.5689094
OS 44.47537206 -38.56983396
OS 44.47259838 -38.57168308
OS 44.46890014 -38.57538132
OS 44.4652019 -38.58092868
OS 44.4605791 -38.58647604
OS 44.45688086 -38.59387252
OS 44.45410718 -38.60219356
OS 44.45318262 -38.6105146
OS 44.45318262 -38.61143916
OS 44.45318262 -38.61328828
OS 44.45410718 -38.61606196
OS 44.45410718 -38.6197602
OS 44.45688086 -38.6290058
OS 44.46242822 -38.6382514
OS 44.46335278 -38.63917596
OS 44.46427734 -38.64010052
OS 44.46612646 -38.6428742
OS 44.4698247 -38.64564788
OS 44.47352294 -38.64842156
OS 44.4790703 -38.6521198
OS 44.48554222 -38.65489348
OS 44.4929387 -38.65859172
OS 44.49386326 -38.65859172
OS 44.49571238 -38.65951628
OS 44.49941062 -38.66044084
OS 44.50588254 -38.66321452
OS 44.51512814 -38.6659882
OS 44.52714742 -38.66876188
OS 44.5345439 -38.67153556
OS 44.54286494 -38.67338468
OS 44.55211054 -38.67615836
OS 44.5622807 -38.67893204
OS 44.56320526 -38.67893204
OS 44.56597894 -38.6798566
OS 44.57060174 -38.68078116
OS 44.5761491 -38.68263028
OS 44.58262102 -38.6844794
OS 44.59094206 -38.68632852
OS 44.6085087 -38.69187588
OS 44.62792446 -38.69742324
OS 44.64734022 -38.70389516
OS 44.66490686 -38.71036708
OS 44.67230334 -38.71314076
OS 44.67877526 -38.71591444
OS 44.68062438 -38.716839
OS 44.68432262 -38.71868812
OS 44.68986998 -38.7214618
OS 44.69819102 -38.7260846
OS 44.70651206 -38.73163196
OS 44.7148331 -38.73902844
OS 44.72315414 -38.74734948
OS 44.73055062 -38.75659508
OS 44.73147518 -38.75751964
OS 44.7333243 -38.76121788
OS 44.73702254 -38.76676524
OS 44.74072078 -38.77508628
OS 44.74349446 -38.78525644
OS 44.7471927 -38.79635116
OS 44.74904182 -38.809295
OS 44.74996638 -38.82408796
OS 44.74996638 -38.82593708
OS 44.74996638 -38.83055988
OS 44.74904182 -38.83795636
OS 44.7471927 -38.84812652
OS 44.74441902 -38.85922124
OS 44.73979622 -38.87124052
OS 44.73424886 -38.88510892
OS 44.72685238 -38.89805276
OS 44.72592782 -38.89990188
OS 44.72222958 -38.90360012
OS 44.71760678 -38.91007204
OS 44.7102103 -38.91746852
OS 44.70004014 -38.92578956
OS 44.68894542 -38.93503516
OS 44.67600158 -38.9433562
OS 44.66028406 -38.95167724
OS 44.6593595 -38.95167724
OS 44.65843494 -38.9526018
OS 44.65288758 -38.95445092
OS 44.64364198 -38.9572246
OS 44.6316227 -38.96092284
OS 44.61682974 -38.96462108
OS 44.60018766 -38.96739476
OS 44.58262102 -38.96924388
OS 44.5622807 -38.97016844
OS 44.55395966 -38.97016844
OS 44.54748774 -38.96924388
OS 44.54009126 -38.96924388
OS 44.53084566 -38.96831932
OS 44.52160006 -38.96739476
OS 44.5114299 -38.96554564
OS 44.48924046 -38.96092284
OS 44.46612646 -38.95445092
OS 44.44393702 -38.94520532
OS 44.43376686 -38.93965796
OS 44.42452126 -38.93318604
OS 44.4235967 -38.93226148
OS 44.42267214 -38.93133692
OS 44.41712478 -38.92578956
OS 44.40880374 -38.91746852
OS 44.39955814 -38.90452468
OS 44.38938798 -38.88880716
OS 44.37921782 -38.87031596
OS 44.37089678 -38.84720196
OS 44.36442486 -38.82131428
OS 44.4420879 -38.809295
OS 44.4420879 -38.81021956
OS 44.4420879 -38.81114412
OS 44.44393702 -38.81669148
OS 44.44578614 -38.82593708
OS 44.44948438 -38.83610724
OS 44.45410718 -38.84720196
OS 44.45965454 -38.85922124
OS 44.46797558 -38.87124052
OS 44.47814574 -38.88141068
OS 44.47999486 -38.88233524
OS 44.4836931 -38.88510892
OS 44.49108958 -38.88880716
OS 44.50033518 -38.89342996
OS 44.51235446 -38.89805276
OS 44.52622286 -38.901751
OS 44.54286494 -38.90452468
OS 44.5622807 -38.90544924
OS 44.5715263 -38.90544924
OS 44.5807719 -38.90452468
OS 44.59279118 -38.90267556
OS 44.60573502 -38.89990188
OS 44.61960342 -38.89620364
OS 44.6316227 -38.89158084
OS 44.64271742 -38.88418436
OS 44.64364198 -38.8832598
OS 44.64734022 -38.88048612
OS 44.65103846 -38.87586332
OS 44.65658582 -38.8693914
OS 44.66120862 -38.86199492
OS 44.66583142 -38.85274932
OS 44.6686051 -38.84350372
OS 44.66952966 -38.832409
OS 44.66952966 -38.83148444
OS 44.66952966 -38.8277862
OS 44.6686051 -38.8231634
OS 44.66675598 -38.81669148
OS 44.6639823 -38.81021956
OS 44.6593595 -38.80374764
OS 44.65381214 -38.79635116
OS 44.6454911 -38.7908038
OS 44.64456654 -38.78987924
OS 44.64179286 -38.78895468
OS 44.63717006 -38.786181
OS 44.62977358 -38.78340732
OS 44.61867886 -38.77970908
OS 44.61220694 -38.7769354
OS 44.60481046 -38.77508628
OS 44.59648942 -38.7723126
OS 44.58724382 -38.76953892
OS 44.57707366 -38.76676524
OS 44.56505438 -38.76399156
OS 44.56412982 -38.76399156
OS 44.56135614 -38.763067
OS 44.55673334 -38.76214244
OS 44.55118598 -38.76029332
OS 44.5437895 -38.7584442
OS 44.53546846 -38.75567052
OS 44.51790182 -38.75104772
OS 44.4975615 -38.7445758
OS 44.47814574 -38.73902844
OS 44.45965454 -38.73255652
OS 44.4513335 -38.72885828
OS 44.44486158 -38.7260846
OS 44.44301246 -38.72516004
OS 44.43931422 -38.72331092
OS 44.43376686 -38.71961268
OS 44.42637038 -38.71498988
OS 44.41804934 -38.70851796
OS 44.4097283 -38.70112148
OS 44.40140726 -38.69280044
OS 44.39401078 -38.68263028
OS 44.39308622 -38.68170572
OS 44.3912371 -38.67800748
OS 44.38846342 -38.67153556
OS 44.38568974 -38.66413908
OS 44.38291606 -38.65489348
OS 44.38014238 -38.64379876
OS 44.37829326 -38.63270404
OS 44.3773687 -38.6197602
OS 44.3773687 -38.61791108
OS 44.3773687 -38.61421284
OS 44.37829326 -38.60866548
OS 44.37921782 -38.60034444
OS 44.38106694 -38.5920234
OS 44.38291606 -38.58185324
OS 44.3866143 -38.57260764
OS 44.3912371 -38.56243748
OS 44.39216166 -38.56151292
OS 44.39401078 -38.55781468
OS 44.39678446 -38.55319188
OS 44.40140726 -38.54671996
OS 44.40695462 -38.54024804
OS 44.41342654 -38.531927
OS 44.42082302 -38.52453052
OS 44.43006862 -38.5180586
OS 44.43099318 -38.51713404
OS 44.43376686 -38.51620948
OS 44.4374651 -38.5134358
OS 44.44301246 -38.51066212
OS 44.45040894 -38.50696388
OS 44.45872998 -38.50326564
OS 44.46890014 -38.4995674
OS 44.47999486 -38.49586916
OS 44.48184398 -38.4949446
OS 44.48554222 -38.49402004
OS 44.49201414 -38.49217092
OS 44.50033518 -38.4903218
OS 44.51050534 -38.48847268
OS 44.52160006 -38.48754812
OS 44.5345439 -38.485699
OS 44.55673334 -38.485699
OS 44.5669035 -38.48662356
OE
OB 33.15968222 -38.32112732 I
OS 33.17539974 -38.32205188
OS 33.19204182 -38.32297644
OS 33.20775934 -38.32482556
OS 33.22162774 -38.32667468
OS 33.22347686 -38.32667468
OS 33.22994878 -38.3285238
OS 33.23826982 -38.33037292
OS 33.24936454 -38.3331466
OS 33.26138382 -38.3377694
OS 33.27432766 -38.34331676
OS 33.28819606 -38.34978868
OS 33.30021534 -38.35718516
OS 33.30206446 -38.35810972
OS 33.3057627 -38.3608834
OS 33.31131006 -38.36643076
OS 33.31870654 -38.37290268
OS 33.32702758 -38.38122372
OS 33.33534862 -38.39231844
OS 33.34459422 -38.40433772
OS 33.3519907 -38.41820612
OS 33.35291526 -38.42005524
OS 33.35476438 -38.42467804
OS 33.35846262 -38.43299908
OS 33.36216086 -38.4440938
OS 33.36493454 -38.45703764
OS 33.36863278 -38.4718306
OS 33.3704819 -38.48847268
OS 33.37140646 -38.50603932
OS 33.37140646 -38.50696388
OS 33.37140646 -38.50973756
OS 33.37140646 -38.5134358
OS 33.3704819 -38.51990772
OS 33.36955734 -38.52637964
OS 33.36863278 -38.53470068
OS 33.36678366 -38.54394628
OS 33.36493454 -38.55411644
OS 33.35846262 -38.57538132
OS 33.35476438 -38.58647604
OS 33.34921702 -38.59849532
OS 33.3427451 -38.6105146
OS 33.33627318 -38.62160932
OS 33.32795214 -38.63270404
OS 33.31870654 -38.64379876
OS 33.31778198 -38.64472332
OS 33.31593286 -38.64657244
OS 33.31315918 -38.64934612
OS 33.30853638 -38.6521198
OS 33.30298902 -38.6567426
OS 33.29559254 -38.6613654
OS 33.28634694 -38.66691276
OS 33.27617678 -38.67153556
OS 33.2641575 -38.67708292
OS 33.2502891 -38.68263028
OS 33.23549614 -38.68725308
OS 33.2179295 -38.69095132
OS 33.1994383 -38.69464956
OS 33.17909798 -38.69742324
OS 33.15598398 -38.69927236
OS 33.13194542 -38.70019692
OS 32.9682983 -38.70019692
OS 32.9682983 -38.95999828
OS 32.88323878 -38.95999828
OS 32.88323878 -38.32020276
OS 33.14581382 -38.32020276
OS 33.15968222 -38.32112732
OE
OB 32.75195126 -38.98403684 I
OS 32.75195126 -38.9849614
OS 32.75195126 -38.98773508
OS 32.75195126 -38.99235788
OS 32.75195126 -38.99790524
OS 32.7510267 -39.00530172
OS 32.7510267 -39.0126982
OS 32.74917758 -39.0311894
OS 32.7464039 -39.05060516
OS 32.74270566 -39.07094548
OS 32.7371583 -39.08851212
OS 32.73346006 -39.09683316
OS 32.72976182 -39.10330508
OS 32.72976182 -39.10422964
OS 32.72883726 -39.1051542
OS 32.72421446 -39.109777
OS 32.71681798 -39.11717348
OS 32.70757238 -39.12549452
OS 32.69462854 -39.13381556
OS 32.67798646 -39.14028748
OS 32.6585707 -39.14583484
OS 32.64747598 -39.1467594
OS 32.6354567 -39.14768396
OS 32.62990934 -39.14768396
OS 32.62436198 -39.1467594
OS 32.61604094 -39.1467594
OS 32.60679534 -39.14583484
OS 32.59662518 -39.14398572
OS 32.57443574 -39.13843836
OS 32.5892287 -39.07187004
OS 32.59015326 -39.07187004
OS 32.59292694 -39.0727946
OS 32.59754974 -39.07371916
OS 32.60217254 -39.07464372
OS 32.61419182 -39.0774174
OS 32.61973918 -39.07834196
OS 32.62898478 -39.07834196
OS 32.63360758 -39.0774174
OS 32.63915494 -39.07649284
OS 32.6447023 -39.07464372
OS 32.65024966 -39.07094548
OS 32.65672158 -39.06724724
OS 32.66134438 -39.06169988
OS 32.66226894 -39.06077532
OS 32.6631935 -39.05800164
OS 32.66504262 -39.05337884
OS 32.6678163 -39.04598236
OS 32.66966542 -39.0358122
OS 32.67058998 -39.02841572
OS 32.67151454 -39.0219438
OS 32.6724391 -39.01362276
OS 32.6724391 -39.0034526
OS 32.67336366 -38.99328244
OS 32.67336366 -38.98218772
OS 32.67336366 -38.49586916
OS 32.75195126 -38.49586916
OS 32.75195126 -38.98403684
OE
OB 33.77174094 -38.3100326 I
OS 33.78006198 -38.31095716
OS 33.79023214 -38.31188172
OS 33.8004023 -38.31280628
OS 33.81242158 -38.31557996
OS 33.8373847 -38.32112732
OS 33.8651215 -38.32944836
OS 33.8789899 -38.33499572
OS 33.89193374 -38.34146764
OS 33.90487758 -38.34978868
OS 33.91782142 -38.35810972
OS 33.91874598 -38.35903428
OS 33.9205951 -38.35995884
OS 33.92429334 -38.36273252
OS 33.92891614 -38.36735532
OS 33.93353894 -38.37197812
OS 33.94001086 -38.37845004
OS 33.94648278 -38.38584652
OS 33.95387926 -38.393243
OS 33.96127574 -38.4024886
OS 33.96867222 -38.41358332
OS 33.97699326 -38.42467804
OS 33.98438974 -38.43669732
OS 33.99086166 -38.45056572
OS 33.99825814 -38.46443412
OS 34.0038055 -38.47922708
OS 34.00935286 -38.49586916
OS 33.92614246 -38.51528492
OS 33.92614246 -38.51436036
OS 33.9252179 -38.51251124
OS 33.92336878 -38.508813
OS 33.92151966 -38.5041902
OS 33.91967054 -38.49864284
OS 33.91689686 -38.49124636
OS 33.90950038 -38.4764534
OS 33.90025478 -38.45981132
OS 33.88916006 -38.44316924
OS 33.87529166 -38.42745172
OS 33.8604987 -38.41358332
OS 33.85864958 -38.4117342
OS 33.85310222 -38.40803596
OS 33.84385662 -38.40341316
OS 33.83183734 -38.39694124
OS 33.81611982 -38.39139388
OS 33.79855318 -38.38584652
OS 33.7772883 -38.38214828
OS 33.7541743 -38.38122372
OS 33.74677782 -38.38122372
OS 33.74215502 -38.38214828
OS 33.7356831 -38.38214828
OS 33.72828662 -38.38307284
OS 33.71071998 -38.38584652
OS 33.69130422 -38.38954476
OS 33.6709639 -38.39601668
OS 33.64969902 -38.40526228
OS 33.63028326 -38.41728156
OS 33.6293587 -38.41728156
OS 33.62843414 -38.41913068
OS 33.62196222 -38.42375348
OS 33.61364118 -38.43114996
OS 33.60347102 -38.44224468
OS 33.59145174 -38.45611308
OS 33.58035702 -38.4718306
OS 33.57018686 -38.49124636
OS 33.56094126 -38.51251124
OS 33.56094126 -38.5134358
OS 33.5600167 -38.51528492
OS 33.55909214 -38.5180586
OS 33.55816758 -38.5226814
OS 33.55631846 -38.52822876
OS 33.55446934 -38.53470068
OS 33.55169566 -38.5504182
OS 33.54799742 -38.5689094
OS 33.54429918 -38.58924972
OS 33.54245006 -38.61143916
OS 33.5415255 -38.63547772
OS 33.5415255 -38.63640228
OS 33.5415255 -38.63917596
OS 33.5415255 -38.64379876
OS 33.5415255 -38.64934612
OS 33.54245006 -38.65581804
OS 33.54245006 -38.66413908
OS 33.54337462 -38.67338468
OS 33.54429918 -38.68355484
OS 33.54707286 -38.70574428
OS 33.55169566 -38.72978284
OS 33.55724302 -38.7538214
OS 33.5646395 -38.77785996
OS 33.5646395 -38.77878452
OS 33.56556406 -38.78063364
OS 33.56741318 -38.78340732
OS 33.5692623 -38.78803012
OS 33.57480966 -38.79912484
OS 33.5831307 -38.81206868
OS 33.59330086 -38.82686164
OS 33.6062447 -38.84257916
OS 33.62103766 -38.85644756
OS 33.6386043 -38.8693914
OS 33.63952886 -38.8693914
OS 33.64137798 -38.87031596
OS 33.64415166 -38.87216508
OS 33.6478499 -38.8740142
OS 33.6524727 -38.87586332
OS 33.65802006 -38.878637
OS 33.6709639 -38.88418436
OS 33.68760598 -38.88973172
OS 33.70609718 -38.89435452
OS 33.7264375 -38.89805276
OS 33.74770238 -38.89897732
OS 33.7541743 -38.89897732
OS 33.75972166 -38.89805276
OS 33.76619358 -38.89805276
OS 33.7726655 -38.8971282
OS 33.78930758 -38.89342996
OS 33.80872334 -38.88880716
OS 33.8281391 -38.88141068
OS 33.84847942 -38.87124052
OS 33.85864958 -38.86569316
OS 33.86789518 -38.85829668
OS 33.86881974 -38.85737212
OS 33.8697443 -38.85644756
OS 33.87251798 -38.85367388
OS 33.87621622 -38.8509002
OS 33.87991446 -38.8462774
OS 33.88453726 -38.84073004
OS 33.89008462 -38.83518268
OS 33.89470742 -38.8277862
OS 33.90025478 -38.81946516
OS 33.9067267 -38.81021956
OS 33.91227406 -38.80097396
OS 33.91782142 -38.78987924
OS 33.92244422 -38.77785996
OS 33.92706702 -38.76491612
OS 33.93168982 -38.75104772
OS 33.93538806 -38.73625476
OS 34.02044758 -38.75751964
OS 34.02044758 -38.7584442
OS 34.01952302 -38.76214244
OS 34.0176739 -38.7676898
OS 34.01490022 -38.77508628
OS 34.01212654 -38.78340732
OS 34.0084283 -38.79357748
OS 34.0038055 -38.8046722
OS 33.99825814 -38.81669148
OS 33.9853143 -38.84257916
OS 33.96867222 -38.86846684
OS 33.95850206 -38.88141068
OS 33.9483319 -38.89435452
OS 33.93723718 -38.90544924
OS 33.92429334 -38.91654396
OS 33.92336878 -38.91746852
OS 33.92151966 -38.91931764
OS 33.91689686 -38.92116676
OS 33.91227406 -38.924865
OS 33.90487758 -38.9294878
OS 33.8974811 -38.9341106
OS 33.88731094 -38.9387334
OS 33.87714078 -38.9433562
OS 33.8651215 -38.94890356
OS 33.85217766 -38.95352636
OS 33.83830926 -38.95814916
OS 33.8235163 -38.96277196
OS 33.80779878 -38.9664702
OS 33.7911567 -38.96831932
OS 33.77359006 -38.97016844
OS 33.75509886 -38.971093
OS 33.7449287 -38.971093
OS 33.73753222 -38.97016844
OS 33.72921118 -38.97016844
OS 33.71904102 -38.96924388
OS 33.7079463 -38.96739476
OS 33.69500246 -38.96554564
OS 33.66819022 -38.96092284
OS 33.64045342 -38.95352636
OS 33.61271662 -38.9433562
OS 33.59977278 -38.93688428
OS 33.58682894 -38.9294878
OS 33.58590438 -38.92856324
OS 33.58405526 -38.92763868
OS 33.58035702 -38.924865
OS 33.57665878 -38.92116676
OS 33.57111142 -38.91746852
OS 33.5646395 -38.91192116
OS 33.55724302 -38.90544924
OS 33.54984654 -38.89805276
OS 33.54245006 -38.88973172
OS 33.53412902 -38.88141068
OS 33.51748694 -38.8601458
OS 33.50176942 -38.83518268
OS 33.48790102 -38.80744588
OS 33.48790102 -38.80652132
OS 33.4860519 -38.80374764
OS 33.48512734 -38.79912484
OS 33.48235366 -38.79357748
OS 33.48050454 -38.786181
OS 33.47773086 -38.7769354
OS 33.47403262 -38.76676524
OS 33.47125894 -38.75567052
OS 33.46848526 -38.74365124
OS 33.46478702 -38.72978284
OS 33.46016422 -38.70112148
OS 33.45646598 -38.66876188
OS 33.45461686 -38.63547772
OS 33.45461686 -38.63455316
OS 33.45461686 -38.63085492
OS 33.45461686 -38.62530756
OS 33.45554142 -38.61883564
OS 33.45554142 -38.60959004
OS 33.45646598 -38.60034444
OS 33.45739054 -38.58832516
OS 33.45923966 -38.57630588
OS 33.46386246 -38.54949364
OS 33.47033438 -38.51990772
OS 33.47957998 -38.4903218
OS 33.49252382 -38.46166044
OS 33.49344838 -38.46073588
OS 33.49437294 -38.4579622
OS 33.49622206 -38.45426396
OS 33.4999203 -38.44964116
OS 33.50361854 -38.44316924
OS 33.50824134 -38.43577276
OS 33.52026062 -38.41913068
OS 33.53597814 -38.40063948
OS 33.55446934 -38.38214828
OS 33.57573422 -38.36365708
OS 33.60069734 -38.34793956
OS 33.6016219 -38.347015
OS 33.60439558 -38.34609044
OS 33.60809382 -38.34424132
OS 33.61271662 -38.34146764
OS 33.6201131 -38.33869396
OS 33.62750958 -38.33592028
OS 33.63675518 -38.33222204
OS 33.64692534 -38.3285238
OS 33.65802006 -38.32482556
OS 33.67003934 -38.32112732
OS 33.69592702 -38.31557996
OS 33.72551294 -38.31095716
OS 33.75602342 -38.30910804
OS 33.76526902 -38.30910804
OS 33.77174094 -38.3100326
OE
OB 35.15858094 -39.1375138 I
OS 34.63805366 -39.1375138
OS 34.63805366 -39.08111564
OS 35.15858094 -39.08111564
OS 35.15858094 -39.1375138
OE
OB 34.37917686 -38.32112732 I
OS 34.38657334 -38.32112732
OS 34.40321542 -38.32297644
OS 34.42170662 -38.32482556
OS 34.44112238 -38.3285238
OS 34.46053814 -38.3331466
OS 34.47810478 -38.33961852
OS 34.47902934 -38.33961852
OS 34.4799539 -38.34054308
OS 34.48550126 -38.34331676
OS 34.4938223 -38.34793956
OS 34.5030679 -38.35441148
OS 34.51416262 -38.36273252
OS 34.5261819 -38.37290268
OS 34.53727662 -38.38584652
OS 34.54744678 -38.39971492
OS 34.54837134 -38.40156404
OS 34.55114502 -38.4071114
OS 34.55576782 -38.41450788
OS 34.56039062 -38.4256026
OS 34.56501342 -38.43854644
OS 34.56963622 -38.45241484
OS 34.5724099 -38.46813236
OS 34.57333446 -38.48384988
OS 34.57333446 -38.485699
OS 34.57333446 -38.4903218
OS 34.5724099 -38.49864284
OS 34.57056078 -38.508813
OS 34.5677871 -38.52083228
OS 34.5631643 -38.53377612
OS 34.55761694 -38.54671996
OS 34.55022046 -38.56058836
OS 34.5492959 -38.56243748
OS 34.54652222 -38.56613572
OS 34.54097486 -38.5735322
OS 34.53357838 -38.58092868
OS 34.52433278 -38.59017428
OS 34.51323806 -38.60034444
OS 34.49936966 -38.60959004
OS 34.48365214 -38.61883564
OS 34.4845767 -38.61883564
OS 34.48642582 -38.6197602
OS 34.4891995 -38.62068476
OS 34.49289774 -38.62253388
OS 34.50399246 -38.62623212
OS 34.5169363 -38.63270404
OS 34.5308047 -38.64102508
OS 34.54652222 -38.65119524
OS 34.56039062 -38.66321452
OS 34.57333446 -38.67800748
OS 34.57425902 -38.6798566
OS 34.57795726 -38.68540396
OS 34.58350462 -38.693725
OS 34.58905198 -38.70481972
OS 34.59459934 -38.71961268
OS 34.6001467 -38.7353302
OS 34.60384494 -38.7538214
OS 34.6047695 -38.77416172
OS 34.6047695 -38.77508628
OS 34.6047695 -38.77601084
OS 34.6047695 -38.7815582
OS 34.60384494 -38.7908038
OS 34.60199582 -38.80189852
OS 34.6001467 -38.81484236
OS 34.59644846 -38.82871076
OS 34.59182566 -38.84350372
OS 34.58535374 -38.85829668
OS 34.58442918 -38.8601458
OS 34.5816555 -38.8647686
OS 34.57795726 -38.87124052
OS 34.5724099 -38.88048612
OS 34.56501342 -38.88973172
OS 34.55761694 -38.89990188
OS 34.54837134 -38.91007204
OS 34.53820118 -38.91839308
OS 34.53727662 -38.91931764
OS 34.53357838 -38.92209132
OS 34.52710646 -38.92578956
OS 34.51878542 -38.9294878
OS 34.50861526 -38.93503516
OS 34.49659598 -38.94058252
OS 34.48365214 -38.94520532
OS 34.46793462 -38.94982812
OS 34.4660855 -38.94982812
OS 34.46053814 -38.95167724
OS 34.45129254 -38.9526018
OS 34.43927326 -38.95445092
OS 34.4244803 -38.95630004
OS 34.40691366 -38.95814916
OS 34.3874979 -38.95907372
OS 34.36530846 -38.95999828
OS 34.12122462 -38.95999828
OS 34.12122462 -38.32020276
OS 34.37270494 -38.32020276
OS 34.37917686 -38.32112732
OE
OB 31.74233174 -38.95999828 I
OS 31.65264942 -38.95999828
OS 31.65264942 -38.87031596
OS 31.74233174 -38.87031596
OS 31.74233174 -38.95999828
OE
OB 31.52968294 -38.42745172 I
OS 31.50841806 -38.54671996
OS 31.45941638 -38.54671996
OS 31.44000062 -38.42745172
OS 31.44000062 -38.32020276
OS 31.52968294 -38.32020276
OS 31.52968294 -38.42745172
OE
OB 32.0992119 -38.48662356 I
OS 32.10568382 -38.48754812
OS 32.11955222 -38.48939724
OS 32.1361943 -38.49309548
OS 32.15376094 -38.49864284
OS 32.17132758 -38.50696388
OS 32.18889422 -38.51713404
OS 32.18981878 -38.51713404
OS 32.19074334 -38.51898316
OS 32.1962907 -38.5226814
OS 32.20461174 -38.53007788
OS 32.2147819 -38.53932348
OS 32.22587662 -38.55134276
OS 32.23697134 -38.56613572
OS 32.24806606 -38.58370236
OS 32.25731166 -38.60311812
OS 32.25731166 -38.60404268
OS 32.25823622 -38.6058918
OS 32.25916078 -38.60866548
OS 32.2610099 -38.61236372
OS 32.26285902 -38.61791108
OS 32.26470814 -38.624383
OS 32.26933094 -38.63917596
OS 32.27395374 -38.65766716
OS 32.27765198 -38.67800748
OS 32.28042566 -38.70112148
OS 32.28135022 -38.72516004
OS 32.28135022 -38.7260846
OS 32.28135022 -38.72793372
OS 32.28135022 -38.73163196
OS 32.28135022 -38.73717932
OS 32.28042566 -38.74365124
OS 32.28042566 -38.75104772
OS 32.27857654 -38.7676898
OS 32.2748783 -38.78803012
OS 32.2702555 -38.809295
OS 32.26378358 -38.83148444
OS 32.25546254 -38.85367388
OS 32.25546254 -38.85459844
OS 32.25453798 -38.85644756
OS 32.25268886 -38.85922124
OS 32.25083974 -38.86291948
OS 32.24436782 -38.87308964
OS 32.23604678 -38.88603348
OS 32.22587662 -38.89990188
OS 32.21293278 -38.91377028
OS 32.19813982 -38.92763868
OS 32.18057318 -38.94058252
OS 32.17964862 -38.94058252
OS 32.17872406 -38.94150708
OS 32.17595038 -38.9433562
OS 32.17225214 -38.94520532
OS 32.16300654 -38.94982812
OS 32.1500627 -38.95537548
OS 32.13434518 -38.96092284
OS 32.1177031 -38.96554564
OS 32.09828734 -38.96924388
OS 32.07887158 -38.97016844
OS 32.07239966 -38.97016844
OS 32.06500318 -38.96924388
OS 32.05575758 -38.96831932
OS 32.04466286 -38.9664702
OS 32.03264358 -38.96369652
OS 32.0206243 -38.95999828
OS 32.00860502 -38.95445092
OS 32.00768046 -38.95352636
OS 32.00305766 -38.95167724
OS 31.9975103 -38.947979
OS 31.99011382 -38.94243164
OS 31.98271734 -38.93688428
OS 31.97347174 -38.9294878
OS 31.9651507 -38.92116676
OS 31.95775422 -38.91192116
OS 31.95775422 -39.1375138
OS 31.87916662 -39.1375138
OS 31.87916662 -38.49586916
OS 31.95035774 -38.49586916
OS 31.95035774 -38.55689012
OS 31.9512823 -38.555041
OS 31.95498054 -38.55134276
OS 31.95960334 -38.54487084
OS 31.96699982 -38.53747436
OS 31.97532086 -38.52822876
OS 31.98456646 -38.51990772
OS 31.99566118 -38.51158668
OS 32.0067559 -38.5041902
OS 32.00860502 -38.50326564
OS 32.01230326 -38.50141652
OS 32.01969974 -38.49864284
OS 32.02894534 -38.4949446
OS 32.04004006 -38.49124636
OS 32.0529839 -38.48847268
OS 32.06777686 -38.48662356
OS 32.08441894 -38.485699
OS 32.0945891 -38.485699
OS 32.0992119 -38.48662356
OE
OB 32.5614919 -38.48662356 I
OS 32.57166206 -38.48847268
OS 32.58368134 -38.49217092
OS 32.59662518 -38.49679372
OS 32.61141814 -38.50326564
OS 32.62713566 -38.51158668
OS 32.5984743 -38.58370236
OS 32.59754974 -38.5827778
OS 32.5938515 -38.58092868
OS 32.58830414 -38.578155
OS 32.58090766 -38.57538132
OS 32.57258662 -38.57260764
OS 32.56241646 -38.56983396
OS 32.5522463 -38.56798484
OS 32.54207614 -38.56706028
OS 32.53745334 -38.56706028
OS 32.53283054 -38.56798484
OS 32.52635862 -38.5689094
OS 32.5198867 -38.57075852
OS 32.51156566 -38.5735322
OS 32.50324462 -38.57723044
OS 32.49584814 -38.5827778
OS 32.49492358 -38.58370236
OS 32.4921499 -38.58555148
OS 32.48937622 -38.58924972
OS 32.48475342 -38.59387252
OS 32.48013062 -38.60034444
OS 32.47550782 -38.60774092
OS 32.47088502 -38.61606196
OS 32.46718678 -38.62623212
OS 32.46626222 -38.62808124
OS 32.46533766 -38.6336286
OS 32.46348854 -38.64194964
OS 32.46071486 -38.65304436
OS 32.45794118 -38.66691276
OS 32.45609206 -38.68263028
OS 32.4551675 -38.69927236
OS 32.45424294 -38.71776356
OS 32.45424294 -38.95999828
OS 32.37565534 -38.95999828
OS 32.37565534 -38.49586916
OS 32.44684646 -38.49586916
OS 32.44684646 -38.56613572
OS 32.44777102 -38.56521116
OS 32.45146926 -38.55873924
OS 32.45609206 -38.5504182
OS 32.46348854 -38.54024804
OS 32.47088502 -38.53007788
OS 32.47920606 -38.51898316
OS 32.4875271 -38.50973756
OS 32.49584814 -38.50234108
OS 32.4967727 -38.50141652
OS 32.49954638 -38.4995674
OS 32.50509374 -38.49679372
OS 32.5106411 -38.49402004
OS 32.51803758 -38.49124636
OS 32.52728318 -38.48847268
OS 32.53652878 -38.48662356
OS 32.54669894 -38.485699
OS 32.55317086 -38.485699
OS 32.5614919 -38.48662356
OE
OB 32.75195126 -38.4117342 I
OS 32.67336366 -38.4117342
OS 32.67336366 -38.32020276
OS 32.75195126 -38.32020276
OS 32.75195126 -38.4117342
OE
OB 36.56668582 -38.95999828 I
OS 36.47885262 -38.95999828
OS 36.1441619 -38.4579622
OS 36.1441619 -38.95999828
OS 36.06280062 -38.95999828
OS 36.06280062 -38.32020276
OS 36.14970926 -38.32020276
OS 36.48532454 -38.8231634
OS 36.48532454 -38.32020276
OS 36.56668582 -38.32020276
OS 36.56668582 -38.95999828
OE
OB 35.74382742 -38.32112732 I
OS 35.75954494 -38.32205188
OS 35.77618702 -38.32297644
OS 35.79190454 -38.32482556
OS 35.80577294 -38.32667468
OS 35.80762206 -38.32667468
OS 35.81409398 -38.3285238
OS 35.82241502 -38.33037292
OS 35.83350974 -38.3331466
OS 35.84552902 -38.3377694
OS 35.85847286 -38.34331676
OS 35.87234126 -38.34978868
OS 35.88436054 -38.35718516
OS 35.88620966 -38.35810972
OS 35.8899079 -38.3608834
OS 35.89545526 -38.36643076
OS 35.90285174 -38.37290268
OS 35.91117278 -38.38122372
OS 35.91949382 -38.39231844
OS 35.92873942 -38.40433772
OS 35.9361359 -38.41820612
OS 35.93706046 -38.42005524
OS 35.93890958 -38.42467804
OS 35.94260782 -38.43299908
OS 35.94630606 -38.4440938
OS 35.94907974 -38.45703764
OS 35.95277798 -38.4718306
OS 35.9546271 -38.48847268
OS 35.95555166 -38.50603932
OS 35.95555166 -38.50696388
OS 35.95555166 -38.50973756
OS 35.95555166 -38.5134358
OS 35.9546271 -38.51990772
OS 35.95370254 -38.52637964
OS 35.95277798 -38.53470068
OS 35.95092886 -38.54394628
OS 35.94907974 -38.55411644
OS 35.94260782 -38.57538132
OS 35.93890958 -38.58647604
OS 35.93336222 -38.59849532
OS 35.9268903 -38.6105146
OS 35.92041838 -38.62160932
OS 35.91209734 -38.63270404
OS 35.90285174 -38.64379876
OS 35.90192718 -38.64472332
OS 35.90007806 -38.64657244
OS 35.89730438 -38.64934612
OS 35.89268158 -38.6521198
OS 35.88713422 -38.6567426
OS 35.87973774 -38.6613654
OS 35.87049214 -38.66691276
OS 35.86032198 -38.67153556
OS 35.8483027 -38.67708292
OS 35.8344343 -38.68263028
OS 35.81964134 -38.68725308
OS 35.8020747 -38.69095132
OS 35.7835835 -38.69464956
OS 35.76324318 -38.69742324
OS 35.74012918 -38.69927236
OS 35.71609062 -38.70019692
OS 35.5524435 -38.70019692
OS 35.5524435 -38.95999828
OS 35.46738398 -38.95999828
OS 35.46738398 -38.32020276
OS 35.72995902 -38.32020276
OS 35.74382742 -38.32112732
OE
OB 36.76916446 -38.42745172 I
OS 36.74789958 -38.54671996
OS 36.6988979 -38.54671996
OS 36.67948214 -38.42745172
OS 36.67948214 -38.32020276
OS 36.76916446 -38.32020276
OS 36.76916446 -38.42745172
OE
OB 38.2382903 -38.39601668 I
OS 37.86014526 -38.39601668
OS 37.86014526 -38.59109884
OS 38.21425174 -38.59109884
OS 38.21425174 -38.66691276
OS 37.86014526 -38.66691276
OS 37.86014526 -38.88418436
OS 38.25308326 -38.88418436
OS 38.25308326 -38.95999828
OS 37.77508574 -38.95999828
OS 37.77508574 -38.32020276
OS 38.2382903 -38.32020276
OS 38.2382903 -38.39601668
OE
OB 37.4339231 -38.32112732 I
OS 37.44224414 -38.32112732
OS 37.4616599 -38.32205188
OS 37.48200022 -38.32482556
OS 37.50418966 -38.32759924
OS 37.52452998 -38.33222204
OS 37.53470014 -38.33499572
OS 37.54302118 -38.3377694
OS 37.54394574 -38.3377694
OS 37.5448703 -38.33869396
OS 37.55041766 -38.34146764
OS 37.5587387 -38.34516588
OS 37.56890886 -38.3516378
OS 37.58000358 -38.35995884
OS 37.59202286 -38.37105356
OS 37.60311758 -38.3839974
OS 37.6142123 -38.39879036
OS 37.6142123 -38.39971492
OS 37.61513686 -38.40063948
OS 37.6188351 -38.40618684
OS 37.62253334 -38.41543244
OS 37.6280807 -38.42745172
OS 37.6327035 -38.44132012
OS 37.6373263 -38.4579622
OS 37.64009998 -38.47552884
OS 37.64102454 -38.4949446
OS 37.64102454 -38.49586916
OS 37.64102454 -38.49771828
OS 37.64102454 -38.50141652
OS 37.64009998 -38.50603932
OS 37.64009998 -38.51251124
OS 37.63917542 -38.51898316
OS 37.63547718 -38.53470068
OS 37.62992982 -38.55319188
OS 37.62253334 -38.57260764
OS 37.61143862 -38.5920234
OS 37.60404214 -38.601269
OS 37.59664566 -38.6105146
OS 37.5957211 -38.61143916
OS 37.59479654 -38.61236372
OS 37.59202286 -38.6151374
OS 37.58832462 -38.61791108
OS 37.58370182 -38.62160932
OS 37.57815446 -38.62530756
OS 37.57075798 -38.62993036
OS 37.5633615 -38.63547772
OS 37.5541159 -38.64010052
OS 37.54394574 -38.64472332
OS 37.53285102 -38.65027068
OS 37.52083174 -38.65489348
OS 37.50696334 -38.65859172
OS 37.49309494 -38.66321452
OS 37.47737742 -38.6659882
OS 37.46073534 -38.66876188
OS 37.46258446 -38.66968644
OS 37.4662827 -38.67153556
OS 37.47183006 -38.6752338
OS 37.47922654 -38.67893204
OS 37.49586862 -38.6891022
OS 37.50418966 -38.69557412
OS 37.51158614 -38.70112148
OS 37.51343526 -38.7029706
OS 37.51805806 -38.7075934
OS 37.52545454 -38.71498988
OS 37.53470014 -38.72423548
OS 37.5448703 -38.73717932
OS 37.55688958 -38.75104772
OS 37.56890886 -38.7676898
OS 37.5818527 -38.786181
OS 37.69187534 -38.95999828
OS 37.5864755 -38.95999828
OS 37.50234054 -38.82686164
OS 37.50234054 -38.82593708
OS 37.50049142 -38.82408796
OS 37.4986423 -38.82131428
OS 37.49586862 -38.81761604
OS 37.4893967 -38.80744588
OS 37.48107566 -38.79450204
OS 37.4709055 -38.78063364
OS 37.46073534 -38.76584068
OS 37.45056518 -38.75197228
OS 37.44131958 -38.73902844
OS 37.44039502 -38.73810388
OS 37.43762134 -38.73440564
OS 37.43299854 -38.72885828
OS 37.42652662 -38.72238636
OS 37.41265822 -38.70851796
OS 37.40526174 -38.70204604
OS 37.39786526 -38.69649868
OS 37.3969407 -38.69557412
OS 37.39509158 -38.69464956
OS 37.39139334 -38.69280044
OS 37.38584598 -38.69002676
OS 37.38029862 -38.68725308
OS 37.3738267 -38.6844794
OS 37.35903374 -38.6798566
OS 37.35810918 -38.6798566
OS 37.35626006 -38.67893204
OS 37.35256182 -38.67893204
OS 37.34793902 -38.67800748
OS 37.3414671 -38.67708292
OS 37.33407062 -38.67708292
OS 37.32390046 -38.67615836
OS 37.21480238 -38.67615836
OS 37.21480238 -38.95999828
OS 37.12974286 -38.95999828
OS 37.12974286 -38.32020276
OS 37.42652662 -38.32020276
OS 37.4339231 -38.32112732
OE
OB 35.31760526 -38.95999828 I
OS 35.23254574 -38.95999828
OS 35.23254574 -38.32020276
OS 35.31760526 -38.32020276
OS 35.31760526 -38.95999828
OE
OB 42.12051774 -38.66413908 H
OS 41.95224782 -38.66413908
OS 41.95224782 -38.88418436
OS 42.13438614 -38.88418436
OS 42.1538019 -38.8832598
OS 42.16212294 -38.88233524
OS 42.16951942 -38.88141068
OS 42.17044398 -38.88141068
OS 42.17414222 -38.88048612
OS 42.17968958 -38.87956156
OS 42.1861615 -38.87771244
OS 42.20187902 -38.87216508
OS 42.21759654 -38.8647686
OS 42.2185211 -38.86384404
OS 42.22129478 -38.86199492
OS 42.22499302 -38.85922124
OS 42.22961582 -38.855523
OS 42.23423862 -38.84997564
OS 42.24071054 -38.84442828
OS 42.24533334 -38.8370318
OS 42.2508807 -38.82871076
OS 42.25180526 -38.8277862
OS 42.25272982 -38.82501252
OS 42.25457894 -38.81946516
OS 42.25735262 -38.81299324
OS 42.2601263 -38.80559676
OS 42.26197542 -38.79635116
OS 42.26289998 -38.78525644
OS 42.26382454 -38.77416172
OS 42.26382454 -38.7723126
OS 42.26382454 -38.76861436
OS 42.26289998 -38.76121788
OS 42.26105086 -38.75289684
OS 42.25920174 -38.74365124
OS 42.2555035 -38.73348108
OS 42.2508807 -38.72331092
OS 42.24440878 -38.71314076
OS 42.24348422 -38.7122162
OS 42.24071054 -38.70851796
OS 42.2370123 -38.70389516
OS 42.23146494 -38.6983478
OS 42.22406846 -38.69187588
OS 42.21482286 -38.68540396
OS 42.2046527 -38.6798566
OS 42.19263342 -38.6752338
OS 42.1907843 -38.67430924
OS 42.18708606 -38.67338468
OS 42.17876502 -38.67153556
OS 42.16859486 -38.66968644
OS 42.15565102 -38.66783732
OS 42.1399335 -38.6659882
OS 42.12051774 -38.66413908
OE
OB 45.22981302 -38.5504182 H
OS 45.22426566 -38.5504182
OS 45.21964286 -38.55134276
OS 45.2094727 -38.55226732
OS 45.1956043 -38.55596556
OS 45.17988678 -38.56151292
OS 45.1632447 -38.5689094
OS 45.14752718 -38.58000412
OS 45.13920614 -38.5874006
OS 45.13180966 -38.59479708
OS 45.13180966 -38.59572164
OS 45.12996054 -38.5966462
OS 45.12811142 -38.59941988
OS 45.12533774 -38.60311812
OS 45.12256406 -38.60774092
OS 45.11979038 -38.61328828
OS 45.11609214 -38.62068476
OS 45.1123939 -38.62808124
OS 45.10869566 -38.63732684
OS 45.10499742 -38.64657244
OS 45.10222374 -38.65766716
OS 45.09945006 -38.66968644
OS 45.09667638 -38.68263028
OS 45.09482726 -38.69649868
OS 45.0939027 -38.7122162
OS 45.09297814 -38.72793372
OS 45.09297814 -38.72885828
OS 45.09297814 -38.73163196
OS 45.09297814 -38.73625476
OS 45.0939027 -38.74272668
OS 45.0939027 -38.75012316
OS 45.09482726 -38.7584442
OS 45.09760094 -38.77785996
OS 45.10222374 -38.8000494
OS 45.10962022 -38.82223884
OS 45.11886582 -38.84350372
OS 45.12533774 -38.85274932
OS 45.13180966 -38.86199492
OS 45.13273422 -38.86199492
OS 45.13365878 -38.86384404
OS 45.13920614 -38.86846684
OS 45.14752718 -38.87586332
OS 45.1586219 -38.8832598
OS 45.1724903 -38.89158084
OS 45.18913238 -38.89897732
OS 45.20854814 -38.90360012
OS 45.2187183 -38.90452468
OS 45.22981302 -38.90544924
OS 45.23536038 -38.90544924
OS 45.23998318 -38.90452468
OS 45.25015334 -38.90267556
OS 45.26402174 -38.89990188
OS 45.2788147 -38.89435452
OS 45.29545678 -38.88695804
OS 45.3111743 -38.87586332
OS 45.31949534 -38.86846684
OS 45.32689182 -38.86107036
OS 45.32781638 -38.8601458
OS 45.32874094 -38.85922124
OS 45.33059006 -38.85644756
OS 45.33336374 -38.85274932
OS 45.33613742 -38.84812652
OS 45.33983566 -38.84257916
OS 45.3435339 -38.83518268
OS 45.34723214 -38.8277862
OS 45.35093038 -38.8185406
OS 45.35370406 -38.80837044
OS 45.3574023 -38.79727572
OS 45.36017598 -38.78525644
OS 45.36294966 -38.77138804
OS 45.36479878 -38.75751964
OS 45.3666479 -38.74180212
OS 45.3666479 -38.72516004
OS 45.3666479 -38.72423548
OS 45.3666479 -38.7214618
OS 45.3666479 -38.716839
OS 45.36572334 -38.71129164
OS 45.36572334 -38.70389516
OS 45.36479878 -38.69557412
OS 45.3620251 -38.67615836
OS 45.3574023 -38.65581804
OS 45.35000582 -38.6336286
OS 45.33983566 -38.61328828
OS 45.3342883 -38.60311812
OS 45.32689182 -38.59479708
OS 45.32689182 -38.59387252
OS 45.3250427 -38.59294796
OS 45.31949534 -38.5874006
OS 45.3111743 -38.58092868
OS 45.30007958 -38.57260764
OS 45.28621118 -38.5642866
OS 45.2695691 -38.55689012
OS 45.2510779 -38.55226732
OS 45.24090774 -38.55134276
OS 45.22981302 -38.5504182
OE
OB 32.07702246 -38.54764452 H
OS 32.07239966 -38.54764452
OS 32.06870142 -38.54856908
OS 32.05945582 -38.5504182
OS 32.04743654 -38.55319188
OS 32.03356814 -38.55873924
OS 32.01877518 -38.56706028
OS 32.01045414 -38.57260764
OS 32.00305766 -38.57907956
OS 31.99566118 -38.58647604
OS 31.9882647 -38.59479708
OS 31.9882647 -38.59572164
OS 31.98641558 -38.5966462
OS 31.98456646 -38.59941988
OS 31.98271734 -38.60311812
OS 31.97994366 -38.60866548
OS 31.97624542 -38.61421284
OS 31.97254718 -38.62160932
OS 31.9697735 -38.6290058
OS 31.96607526 -38.6382514
OS 31.96237702 -38.64842156
OS 31.95960334 -38.65951628
OS 31.9559051 -38.67153556
OS 31.95405598 -38.68540396
OS 31.95220686 -38.69927236
OS 31.95035774 -38.71406532
OS 31.95035774 -38.7307074
OS 31.95035774 -38.73163196
OS 31.95035774 -38.73440564
OS 31.95035774 -38.73902844
OS 31.9512823 -38.74550036
OS 31.9512823 -38.75289684
OS 31.95220686 -38.76121788
OS 31.95498054 -38.78063364
OS 31.95960334 -38.80282308
OS 31.9651507 -38.82408796
OS 31.9743963 -38.84535284
OS 31.97994366 -38.85459844
OS 31.98641558 -38.86291948
OS 31.9882647 -38.8647686
OS 31.9928875 -38.8693914
OS 32.00028398 -38.87678788
OS 32.01045414 -38.88418436
OS 32.02339798 -38.89158084
OS 32.03819094 -38.89897732
OS 32.05483302 -38.90360012
OS 32.06407862 -38.90452468
OS 32.07332422 -38.90544924
OS 32.07887158 -38.90544924
OS 32.08256982 -38.90452468
OS 32.09181542 -38.90267556
OS 32.10475926 -38.89990188
OS 32.11862766 -38.89435452
OS 32.13342062 -38.88695804
OS 32.14821358 -38.87586332
OS 32.15561006 -38.8693914
OS 32.16300654 -38.86199492
OS 32.16300654 -38.86107036
OS 32.16485566 -38.8601458
OS 32.16670478 -38.85737212
OS 32.1685539 -38.85367388
OS 32.17225214 -38.84905108
OS 32.17502582 -38.84257916
OS 32.17872406 -38.83610724
OS 32.1824223 -38.8277862
OS 32.18519598 -38.81946516
OS 32.18889422 -38.80837044
OS 32.19259246 -38.79727572
OS 32.19536614 -38.78525644
OS 32.19721526 -38.77138804
OS 32.19906438 -38.75659508
OS 32.2009135 -38.74087756
OS 32.2009135 -38.72423548
OS 32.2009135 -38.72331092
OS 32.2009135 -38.72053724
OS 32.2009135 -38.71591444
OS 32.19998894 -38.70944252
OS 32.19998894 -38.70204604
OS 32.19906438 -38.693725
OS 32.1962907 -38.67430924
OS 32.1916679 -38.65304436
OS 32.18519598 -38.63177948
OS 32.17595038 -38.6105146
OS 32.17040302 -38.60034444
OS 32.1639311 -38.5920234
OS 32.1639311 -38.59109884
OS 32.16208198 -38.59017428
OS 32.15745918 -38.58462692
OS 32.1500627 -38.578155
OS 32.13989254 -38.56983396
OS 32.1269487 -38.56151292
OS 32.11215574 -38.55411644
OS 32.09551366 -38.54949364
OS 32.08626806 -38.54856908
OS 32.07702246 -38.54764452
OE
OB 42.10387566 -38.39601668 H
OS 41.95224782 -38.39601668
OS 41.95224782 -38.58832516
OS 42.10942302 -38.58832516
OS 42.1214423 -38.5874006
OS 42.13438614 -38.58647604
OS 42.14732998 -38.58555148
OS 42.16027382 -38.58370236
OS 42.17044398 -38.58185324
OS 42.1722931 -38.58092868
OS 42.17599134 -38.58000412
OS 42.1815387 -38.57723044
OS 42.18893518 -38.5735322
OS 42.19633166 -38.56983396
OS 42.2046527 -38.5642866
OS 42.21297374 -38.55689012
OS 42.21944566 -38.54949364
OS 42.22037022 -38.54856908
OS 42.22221934 -38.5457954
OS 42.22499302 -38.54024804
OS 42.2277667 -38.53377612
OS 42.23054038 -38.52637964
OS 42.23331406 -38.51713404
OS 42.23516318 -38.50603932
OS 42.23608774 -38.49402004
OS 42.23608774 -38.49217092
OS 42.23608774 -38.48847268
OS 42.23516318 -38.48292532
OS 42.23423862 -38.47552884
OS 42.2323895 -38.46628324
OS 42.22961582 -38.45703764
OS 42.22591758 -38.44779204
OS 42.22037022 -38.43854644
OS 42.21944566 -38.43762188
OS 42.21759654 -38.4348482
OS 42.2138983 -38.4302254
OS 42.2092755 -38.4256026
OS 42.20280358 -38.42005524
OS 42.1954071 -38.41450788
OS 42.1861615 -38.40896052
OS 42.17599134 -38.40526228
OS 42.17506678 -38.40526228
OS 42.17044398 -38.40341316
OS 42.16397206 -38.4024886
OS 42.1538019 -38.40063948
OS 42.1399335 -38.39879036
OS 42.12421598 -38.3978658
OS 42.10387566 -38.39601668
OE
OB 37.41635646 -38.39139388 H
OS 37.21480238 -38.39139388
OS 37.21480238 -38.60311812
OS 37.40526174 -38.60311812
OS 37.41635646 -38.60219356
OS 37.4293003 -38.601269
OS 37.44409326 -38.60034444
OS 37.45888622 -38.59849532
OS 37.47367918 -38.59572164
OS 37.48662302 -38.5920234
OS 37.48847214 -38.59109884
OS 37.49217038 -38.58924972
OS 37.49771774 -38.58647604
OS 37.50511422 -38.5827778
OS 37.51343526 -38.57723044
OS 37.5217563 -38.57075852
OS 37.53007734 -38.56243748
OS 37.53654926 -38.55319188
OS 37.53747382 -38.55226732
OS 37.53932294 -38.54856908
OS 37.54209662 -38.54302172
OS 37.54579486 -38.53562524
OS 37.54856854 -38.5273042
OS 37.55134222 -38.5180586
OS 37.55319134 -38.50696388
OS 37.5541159 -38.49586916
OS 37.5541159 -38.4949446
OS 37.5541159 -38.49402004
OS 37.55319134 -38.48847268
OS 37.55226678 -38.48015164
OS 37.55041766 -38.46905692
OS 37.54579486 -38.4579622
OS 37.5402475 -38.44501836
OS 37.53192646 -38.43299908
OS 37.52083174 -38.4209798
OS 37.51898262 -38.42005524
OS 37.51435982 -38.416357
OS 37.50696334 -38.4117342
OS 37.49494406 -38.40618684
OS 37.48107566 -38.40063948
OS 37.46258446 -38.39601668
OS 37.44131958 -38.39231844
OS 37.41635646 -38.39139388
OE
OB 39.82298614 -38.54764452 H
OS 39.81836334 -38.54764452
OS 39.8146651 -38.54856908
OS 39.8054195 -38.5504182
OS 39.79340022 -38.55319188
OS 39.77953182 -38.55873924
OS 39.76473886 -38.56706028
OS 39.75641782 -38.57260764
OS 39.74902134 -38.57907956
OS 39.74162486 -38.58647604
OS 39.73422838 -38.59479708
OS 39.73422838 -38.59572164
OS 39.73237926 -38.5966462
OS 39.73053014 -38.59941988
OS 39.72868102 -38.60311812
OS 39.72590734 -38.60866548
OS 39.7222091 -38.61421284
OS 39.71851086 -38.62160932
OS 39.71573718 -38.6290058
OS 39.71203894 -38.6382514
OS 39.7083407 -38.64842156
OS 39.70556702 -38.65951628
OS 39.70186878 -38.67153556
OS 39.70001966 -38.68540396
OS 39.69817054 -38.69927236
OS 39.69632142 -38.71406532
OS 39.69632142 -38.7307074
OS 39.69632142 -38.73163196
OS 39.69632142 -38.73440564
OS 39.69632142 -38.73902844
OS 39.69724598 -38.74550036
OS 39.69724598 -38.75289684
OS 39.69817054 -38.76121788
OS 39.70094422 -38.78063364
OS 39.70556702 -38.80282308
OS 39.71111438 -38.82408796
OS 39.72035998 -38.84535284
OS 39.72590734 -38.85459844
OS 39.73237926 -38.86291948
OS 39.73422838 -38.8647686
OS 39.73885118 -38.8693914
OS 39.74624766 -38.87678788
OS 39.75641782 -38.88418436
OS 39.76936166 -38.89158084
OS 39.78415462 -38.89897732
OS 39.8007967 -38.90360012
OS 39.8100423 -38.90452468
OS 39.8192879 -38.90544924
OS 39.82483526 -38.90544924
OS 39.8285335 -38.90452468
OS 39.8377791 -38.90267556
OS 39.85072294 -38.89990188
OS 39.86459134 -38.89435452
OS 39.8793843 -38.88695804
OS 39.89417726 -38.87586332
OS 39.90157374 -38.8693914
OS 39.90897022 -38.86199492
OS 39.90897022 -38.86107036
OS 39.91081934 -38.8601458
OS 39.91266846 -38.85737212
OS 39.91451758 -38.85367388
OS 39.91821582 -38.84905108
OS 39.9209895 -38.84257916
OS 39.92468774 -38.83610724
OS 39.92838598 -38.8277862
OS 39.93115966 -38.81946516
OS 39.9348579 -38.80837044
OS 39.93855614 -38.79727572
OS 39.94132982 -38.78525644
OS 39.94317894 -38.77138804
OS 39.94502806 -38.75659508
OS 39.94687718 -38.74087756
OS 39.94687718 -38.72423548
OS 39.94687718 -38.72331092
OS 39.94687718 -38.72053724
OS 39.94687718 -38.71591444
OS 39.94595262 -38.70944252
OS 39.94595262 -38.70204604
OS 39.94502806 -38.693725
OS 39.94225438 -38.67430924
OS 39.93763158 -38.65304436
OS 39.93115966 -38.63177948
OS 39.92191406 -38.6105146
OS 39.9163667 -38.60034444
OS 39.90989478 -38.5920234
OS 39.90989478 -38.59109884
OS 39.90804566 -38.59017428
OS 39.90342286 -38.58462692
OS 39.89602638 -38.578155
OS 39.88585622 -38.56983396
OS 39.87291238 -38.56151292
OS 39.85811942 -38.55411644
OS 39.84147734 -38.54949364
OS 39.83223174 -38.54856908
OS 39.82298614 -38.54764452
OE
OB 35.73550638 -38.39601668 H
OS 35.5524435 -38.39601668
OS 35.5524435 -38.624383
OS 35.72441166 -38.624383
OS 35.73088358 -38.62345844
OS 35.7373555 -38.62345844
OS 35.74475198 -38.62253388
OS 35.76231862 -38.62068476
OS 35.78173438 -38.61698652
OS 35.80115014 -38.61143916
OS 35.81871678 -38.60404268
OS 35.82703782 -38.59941988
OS 35.83350974 -38.59387252
OS 35.83535886 -38.5920234
OS 35.8390571 -38.58832516
OS 35.84460446 -38.58092868
OS 35.85107638 -38.57168308
OS 35.8575483 -38.5596638
OS 35.86309566 -38.54487084
OS 35.8667939 -38.52822876
OS 35.86864302 -38.508813
OS 35.86864302 -38.50788844
OS 35.86864302 -38.50696388
OS 35.86864302 -38.50234108
OS 35.86771846 -38.49402004
OS 35.86586934 -38.48477444
OS 35.86402022 -38.47460428
OS 35.86032198 -38.462585
OS 35.85477462 -38.45149028
OS 35.8483027 -38.44039556
OS 35.84737814 -38.439471
OS 35.84460446 -38.43577276
OS 35.83998166 -38.43114996
OS 35.8344343 -38.42467804
OS 35.82611326 -38.41820612
OS 35.81686766 -38.41265876
OS 35.8066975 -38.4071114
OS 35.79467822 -38.4024886
OS 35.79375366 -38.4024886
OS 35.79005542 -38.40156404
OS 35.78450806 -38.40063948
OS 35.77711158 -38.39879036
OS 35.76601686 -38.3978658
OS 35.75214846 -38.39694124
OS 35.73550638 -38.39601668
OE
OB 43.44263854 -38.5504182 H
OS 43.43709118 -38.5504182
OS 43.43339294 -38.55134276
OS 43.42322278 -38.55226732
OS 43.4112035 -38.555041
OS 43.39641054 -38.5596638
OS 43.38069302 -38.56613572
OS 43.36590006 -38.57538132
OS 43.3511071 -38.5874006
OS 43.34925798 -38.58924972
OS 43.34555974 -38.59387252
OS 43.33908782 -38.60219356
OS 43.3326159 -38.61328828
OS 43.32521942 -38.62623212
OS 43.3187475 -38.6428742
OS 43.31320014 -38.66228996
OS 43.31042646 -38.68355484
OS 43.57022782 -38.68355484
OS 43.57022782 -38.68263028
OS 43.57022782 -38.68078116
OS 43.56930326 -38.67800748
OS 43.56930326 -38.67430924
OS 43.56745414 -38.66321452
OS 43.56468046 -38.65119524
OS 43.56005766 -38.63640228
OS 43.55543486 -38.62253388
OS 43.54803838 -38.60866548
OS 43.53971734 -38.5966462
OS 43.53971734 -38.59572164
OS 43.53786822 -38.59479708
OS 43.53324542 -38.58924972
OS 43.52492438 -38.58185324
OS 43.51382966 -38.5735322
OS 43.49996126 -38.56521116
OS 43.48331918 -38.55781468
OS 43.46390342 -38.55226732
OS 43.45373326 -38.55134276
OS 43.44263854 -38.5504182
OE
OB 34.35791198 -38.39601668 H
OS 34.20628414 -38.39601668
OS 34.20628414 -38.58832516
OS 34.36345934 -38.58832516
OS 34.37547862 -38.5874006
OS 34.38842246 -38.58647604
OS 34.4013663 -38.58555148
OS 34.41431014 -38.58370236
OS 34.4244803 -38.58185324
OS 34.42632942 -38.58092868
OS 34.43002766 -38.58000412
OS 34.43557502 -38.57723044
OS 34.4429715 -38.5735322
OS 34.45036798 -38.56983396
OS 34.45868902 -38.5642866
OS 34.46701006 -38.55689012
OS 34.47348198 -38.54949364
OS 34.47440654 -38.54856908
OS 34.47625566 -38.5457954
OS 34.47902934 -38.54024804
OS 34.48180302 -38.53377612
OS 34.4845767 -38.52637964
OS 34.48735038 -38.51713404
OS 34.4891995 -38.50603932
OS 34.49012406 -38.49402004
OS 34.49012406 -38.49217092
OS 34.49012406 -38.48847268
OS 34.4891995 -38.48292532
OS 34.48827494 -38.47552884
OS 34.48642582 -38.46628324
OS 34.48365214 -38.45703764
OS 34.4799539 -38.44779204
OS 34.47440654 -38.43854644
OS 34.47348198 -38.43762188
OS 34.47163286 -38.4348482
OS 34.46793462 -38.4302254
OS 34.46331182 -38.4256026
OS 34.4568399 -38.42005524
OS 34.44944342 -38.41450788
OS 34.44019782 -38.40896052
OS 34.43002766 -38.40526228
OS 34.4291031 -38.40526228
OS 34.4244803 -38.40341316
OS 34.41800838 -38.4024886
OS 34.40783822 -38.40063948
OS 34.39396982 -38.39879036
OS 34.3782523 -38.3978658
OS 34.35791198 -38.39601668
OE
OB 40.89732486 -38.39601668 H
OS 40.71426198 -38.39601668
OS 40.71426198 -38.624383
OS 40.88623014 -38.624383
OS 40.89270206 -38.62345844
OS 40.89917398 -38.62345844
OS 40.90657046 -38.62253388
OS 40.9241371 -38.62068476
OS 40.94355286 -38.61698652
OS 40.96296862 -38.61143916
OS 40.98053526 -38.60404268
OS 40.9888563 -38.59941988
OS 40.99532822 -38.59387252
OS 40.99717734 -38.5920234
OS 41.00087558 -38.58832516
OS 41.00642294 -38.58092868
OS 41.01289486 -38.57168308
OS 41.01936678 -38.5596638
OS 41.02491414 -38.54487084
OS 41.02861238 -38.52822876
OS 41.0304615 -38.508813
OS 41.0304615 -38.50788844
OS 41.0304615 -38.50696388
OS 41.0304615 -38.50234108
OS 41.02953694 -38.49402004
OS 41.02768782 -38.48477444
OS 41.0258387 -38.47460428
OS 41.02214046 -38.462585
OS 41.0165931 -38.45149028
OS 41.01012118 -38.44039556
OS 41.00919662 -38.439471
OS 41.00642294 -38.43577276
OS 41.00180014 -38.43114996
OS 40.99625278 -38.42467804
OS 40.98793174 -38.41820612
OS 40.97868614 -38.41265876
OS 40.96851598 -38.4071114
OS 40.9564967 -38.4024886
OS 40.95557214 -38.4024886
OS 40.9518739 -38.40156404
OS 40.94632654 -38.40063948
OS 40.93893006 -38.39879036
OS 40.92783534 -38.3978658
OS 40.91396694 -38.39694124
OS 40.89732486 -38.39601668
OE
OB 33.15136118 -38.39601668 H
OS 32.9682983 -38.39601668
OS 32.9682983 -38.624383
OS 33.14026646 -38.624383
OS 33.14673838 -38.62345844
OS 33.1532103 -38.62345844
OS 33.16060678 -38.62253388
OS 33.17817342 -38.62068476
OS 33.19758918 -38.61698652
OS 33.21700494 -38.61143916
OS 33.23457158 -38.60404268
OS 33.24289262 -38.59941988
OS 33.24936454 -38.59387252
OS 33.25121366 -38.5920234
OS 33.2549119 -38.58832516
OS 33.26045926 -38.58092868
OS 33.26693118 -38.57168308
OS 33.2734031 -38.5596638
OS 33.27895046 -38.54487084
OS 33.2826487 -38.52822876
OS 33.28449782 -38.508813
OS 33.28449782 -38.50788844
OS 33.28449782 -38.50696388
OS 33.28449782 -38.50234108
OS 33.28357326 -38.49402004
OS 33.28172414 -38.48477444
OS 33.27987502 -38.47460428
OS 33.27617678 -38.462585
OS 33.27062942 -38.45149028
OS 33.2641575 -38.44039556
OS 33.26323294 -38.439471
OS 33.26045926 -38.43577276
OS 33.25583646 -38.43114996
OS 33.2502891 -38.42467804
OS 33.24196806 -38.41820612
OS 33.23272246 -38.41265876
OS 33.2225523 -38.4071114
OS 33.21053302 -38.4024886
OS 33.20960846 -38.4024886
OS 33.20591022 -38.40156404
OS 33.20036286 -38.40063948
OS 33.19296638 -38.39879036
OS 33.18187166 -38.3978658
OS 33.16800326 -38.39694124
OS 33.15136118 -38.39601668
OE
OB 34.37455406 -38.66413908 H
OS 34.20628414 -38.66413908
OS 34.20628414 -38.88418436
OS 34.38842246 -38.88418436
OS 34.40783822 -38.8832598
OS 34.41615926 -38.88233524
OS 34.42355574 -38.88141068
OS 34.4244803 -38.88141068
OS 34.42817854 -38.88048612
OS 34.4337259 -38.87956156
OS 34.44019782 -38.87771244
OS 34.45591534 -38.87216508
OS 34.47163286 -38.8647686
OS 34.47255742 -38.86384404
OS 34.4753311 -38.86199492
OS 34.47902934 -38.85922124
OS 34.48365214 -38.855523
OS 34.48827494 -38.84997564
OS 34.49474686 -38.84442828
OS 34.49936966 -38.8370318
OS 34.50491702 -38.82871076
OS 34.50584158 -38.8277862
OS 34.50676614 -38.82501252
OS 34.50861526 -38.81946516
OS 34.51138894 -38.81299324
OS 34.51416262 -38.80559676
OS 34.51601174 -38.79635116
OS 34.5169363 -38.78525644
OS 34.51786086 -38.77416172
OS 34.51786086 -38.7723126
OS 34.51786086 -38.76861436
OS 34.5169363 -38.76121788
OS 34.51508718 -38.75289684
OS 34.51323806 -38.74365124
OS 34.50953982 -38.73348108
OS 34.50491702 -38.72331092
OS 34.4984451 -38.71314076
OS 34.49752054 -38.7122162
OS 34.49474686 -38.70851796
OS 34.49104862 -38.70389516
OS 34.48550126 -38.6983478
OS 34.47810478 -38.69187588
OS 34.46885918 -38.68540396
OS 34.45868902 -38.6798566
OS 34.44666974 -38.6752338
OS 34.44482062 -38.67430924
OS 34.44112238 -38.67338468
OS 34.43280134 -38.67153556
OS 34.42263118 -38.66968644
OS 34.40968734 -38.66783732
OS 34.39396982 -38.6659882
OS 34.37455406 -38.66413908
OE
SE
S P 0
OB 48.49040086 -36.61402634 I
OS 48.17420134 -36.61402634
OS 48.17420134 -37.45999874
OS 48.04661206 -37.45999874
OS 48.04661206 -36.61402634
OS 47.73041254 -36.61402634
OS 47.73041254 -36.50030546
OS 48.49040086 -36.50030546
OS 48.49040086 -36.61402634
OE
OB 47.69990206 -37.45999874 I
OS 47.5556707 -37.45999874
OS 47.44333666 -37.16876234
OS 47.04115306 -37.16876234
OS 46.93714006 -37.45999874
OS 46.80261658 -37.45999874
OS 47.16874234 -36.50030546
OS 47.30742634 -36.50030546
OS 47.69990206 -37.45999874
OE
OB 49.31834434 -36.61402634 I
OS 48.75112678 -36.61402634
OS 48.75112678 -36.90664958
OS 49.2822865 -36.90664958
OS 49.2822865 -37.02037046
OS 48.75112678 -37.02037046
OS 48.75112678 -37.34627786
OS 49.34053378 -37.34627786
OS 49.34053378 -37.45999874
OS 48.6235375 -37.45999874
OS 48.6235375 -36.50030546
OS 49.31834434 -36.50030546
OS 49.31834434 -36.61402634
OE
OB 46.33386466 -36.5016923 I
OS 46.36160146 -36.50307914
OS 46.38933826 -36.50585282
OS 46.41707506 -36.51001334
OS 46.44065134 -36.51417386
OS 46.44203818 -36.51417386
OS 46.44481186 -36.5155607
OS 46.44897238 -36.5155607
OS 46.45451974 -36.51833438
OS 46.46977498 -36.5224949
OS 46.48919074 -36.5294291
OS 46.51138018 -36.53913698
OS 46.53495646 -36.55161854
OS 46.55853274 -36.56548694
OS 46.58072218 -36.58351586
OS 46.58210902 -36.5849027
OS 46.58349586 -36.58628954
OS 46.58765638 -36.59045006
OS 46.59320374 -36.59461058
OS 46.60707214 -36.60847898
OS 46.62371422 -36.62789474
OS 46.64174314 -36.65147102
OS 46.6611589 -36.67920782
OS 46.67918782 -36.71110514
OS 46.69444306 -36.74716298
OS 46.69444306 -36.74854982
OS 46.6958299 -36.7513235
OS 46.69860358 -36.75687086
OS 46.69999042 -36.7651919
OS 46.70415094 -36.77489978
OS 46.70692462 -36.7859945
OS 46.7096983 -36.79847606
OS 46.71385882 -36.8137313
OS 46.71801934 -36.82898654
OS 46.72079302 -36.84701546
OS 46.72772722 -36.88584698
OS 46.73188774 -36.92883902
OS 46.73327458 -36.97599158
OS 46.73327458 -36.97737842
OS 46.73327458 -36.9801521
OS 46.73327458 -36.9870863
OS 46.73327458 -36.9940205
OS 46.73188774 -37.00372838
OS 46.73188774 -37.0148231
OS 46.7305009 -37.04117306
OS 46.72634038 -37.07168354
OS 46.72217986 -37.10358086
OS 46.71524566 -37.13686502
OS 46.70692462 -37.17014918
OS 46.70692462 -37.17153602
OS 46.70553778 -37.1743097
OS 46.70415094 -37.17847022
OS 46.7027641 -37.18401758
OS 46.69721674 -37.19927282
OS 46.6888957 -37.21868858
OS 46.68057466 -37.24087802
OS 46.66947994 -37.26306746
OS 46.65561154 -37.28664374
OS 46.64174314 -37.30883318
OS 46.6403563 -37.31160686
OS 46.63480894 -37.31854106
OS 46.6264879 -37.32824894
OS 46.61539318 -37.3407305
OS 46.60291162 -37.3545989
OS 46.58765638 -37.3684673
OS 46.57240114 -37.38372254
OS 46.55437222 -37.3962041
OS 46.55159854 -37.39759094
OS 46.54605118 -37.40175146
OS 46.5363433 -37.40729882
OS 46.5224749 -37.41423302
OS 46.50583282 -37.42255406
OS 46.48641706 -37.42948826
OS 46.46422762 -37.4378093
OS 46.4392645 -37.4447435
OS 46.43649082 -37.4447435
OS 46.4323303 -37.44613034
OS 46.42816978 -37.44751718
OS 46.41430138 -37.44890402
OS 46.39488562 -37.4516777
OS 46.37269618 -37.45445138
OS 46.34634622 -37.45722506
OS 46.31722258 -37.4586119
OS 46.28532526 -37.45999874
OS 45.9400021 -37.45999874
OS 45.9400021 -36.50030546
OS 46.30890154 -36.50030546
OS 46.33386466 -36.5016923
OE
OB 46.28948578 -36.61402634 H
OS 46.06759138 -36.61402634
OS 46.06759138 -37.34627786
OS 46.29503314 -37.34627786
OS 46.30474102 -37.34489102
OS 46.32554362 -37.34350418
OS 46.3491199 -37.34211734
OS 46.37408302 -37.33934366
OS 46.39904614 -37.33518314
OS 46.41984874 -37.32963578
OS 46.42262242 -37.32824894
OS 46.42955662 -37.3268621
OS 46.4392645 -37.32270158
OS 46.45174606 -37.31715422
OS 46.46561446 -37.30883318
OS 46.47948286 -37.30051214
OS 46.49335126 -37.29080426
OS 46.50721966 -37.27970954
OS 46.5086065 -37.27693586
OS 46.51415386 -37.2713885
OS 46.5224749 -37.26168062
OS 46.53218278 -37.24781222
OS 46.5432775 -37.2297833
OS 46.55575906 -37.2089807
OS 46.56685378 -37.18540442
OS 46.57656166 -37.15905446
OS 46.57656166 -37.15766762
OS 46.5779485 -37.15489394
OS 46.57933534 -37.15073342
OS 46.58072218 -37.14518606
OS 46.58210902 -37.13825186
OS 46.5848827 -37.12854398
OS 46.58765638 -37.1188361
OS 46.59043006 -37.10774138
OS 46.59459058 -37.08000458
OS 46.5987511 -37.04810726
OS 46.60152478 -37.01204942
OS 46.60291162 -36.9732179
OS 46.60291162 -36.97183106
OS 46.60291162 -36.9662837
OS 46.60291162 -36.9593495
OS 46.60152478 -36.94825478
OS 46.60152478 -36.93577322
OS 46.60013794 -36.92190482
OS 46.5987511 -36.90526274
OS 46.59736426 -36.88862066
OS 46.59043006 -36.85117598
OS 46.58210902 -36.81234446
OS 46.56962746 -36.77628662
OS 46.56130642 -36.7582577
OS 46.55298538 -36.74300246
OS 46.55298538 -36.74161562
OS 46.5502117 -36.73884194
OS 46.54743802 -36.73468142
OS 46.54466434 -36.72913406
OS 46.53356962 -36.71526566
OS 46.51970122 -36.69862358
OS 46.5016723 -36.68059466
OS 46.4808697 -36.66256574
OS 46.45729342 -36.6473105
OS 46.4323303 -36.63482894
OS 46.42955662 -36.6334421
OS 46.42262242 -36.63205526
OS 46.41014086 -36.62789474
OS 46.39211194 -36.62373422
OS 46.3699225 -36.62096054
OS 46.3421857 -36.61680002
OS 46.32554362 -36.61541318
OS 46.3075147 -36.61541318
OS 46.28948578 -36.61402634
OE
OB 47.23531066 -36.60015794 H
OS 47.23531066 -36.60154478
OS 47.23392382 -36.60431846
OS 47.23392382 -36.60986582
OS 47.23115014 -36.61541318
OS 47.2297633 -36.62512106
OS 47.22698962 -36.63482894
OS 47.22144226 -36.65840522
OS 47.21450806 -36.68614202
OS 47.20480018 -36.7166525
OS 47.1950923 -36.74993666
OS 47.18261074 -36.78460766
OS 47.07859774 -37.06474934
OS 47.4031183 -37.06474934
OS 47.30326582 -36.80124974
OS 47.30326582 -36.7998629
OS 47.30187898 -36.79570238
OS 47.2991053 -36.78876818
OS 47.29633162 -36.78044714
OS 47.2921711 -36.77073926
OS 47.28801058 -36.7582577
OS 47.28385006 -36.7443893
OS 47.2783027 -36.7305209
OS 47.26720798 -36.69862358
OS 47.25611326 -36.66533942
OS 47.24501854 -36.63205526
OS 47.23531066 -36.60015794
OE
SE
S P 0
OB 53.64989524 -38.94890356 I
OS 53.57130764 -38.94890356
OS 53.57130764 -38.4487166
OS 53.57038308 -38.44964116
OS 53.56576028 -38.4533394
OS 53.56021292 -38.45888676
OS 53.55096732 -38.46535868
OS 53.54079716 -38.47367972
OS 53.52785332 -38.48292532
OS 53.51306036 -38.49309548
OS 53.49641828 -38.50326564
OS 53.49549372 -38.50326564
OS 53.49456916 -38.5041902
OS 53.4890218 -38.50788844
OS 53.4797762 -38.51251124
OS 53.46868148 -38.5180586
OS 53.45573764 -38.52453052
OS 53.44186924 -38.53100244
OS 53.42800084 -38.53747436
OS 53.41413244 -38.54302172
OS 53.41413244 -38.4672078
OS 53.415057 -38.4672078
OS 53.41690612 -38.46535868
OS 53.42060436 -38.46443412
OS 53.42522716 -38.46166044
OS 53.43077452 -38.45888676
OS 53.43724644 -38.45518852
OS 53.45296396 -38.44594292
OS 53.47145516 -38.43577276
OS 53.48994636 -38.42282892
OS 53.50936212 -38.40803596
OS 53.52877788 -38.39231844
OS 53.52970244 -38.39139388
OS 53.530627 -38.39046932
OS 53.53340068 -38.38769564
OS 53.53709892 -38.38492196
OS 53.54541996 -38.37567636
OS 53.55651468 -38.36458164
OS 53.5676094 -38.3516378
OS 53.57962868 -38.33684484
OS 53.58979884 -38.32205188
OS 53.59904444 -38.30633436
OS 53.64989524 -38.30633436
OS 53.64989524 -38.94890356
OE
OB 54.07334372 -38.30725892 I
OS 54.0807402 -38.30818348
OS 54.08906124 -38.30910804
OS 54.09830684 -38.3100326
OS 54.10755244 -38.31280628
OS 54.12974188 -38.31835364
OS 54.15193132 -38.32667468
OS 54.16302604 -38.33222204
OS 54.17412076 -38.33869396
OS 54.18429092 -38.347015
OS 54.19446108 -38.35533604
OS 54.19538564 -38.3562606
OS 54.1963102 -38.35718516
OS 54.19908388 -38.35995884
OS 54.20278212 -38.36365708
OS 54.20648036 -38.36920444
OS 54.21110316 -38.3747518
OS 54.22034876 -38.3886202
OS 54.22959436 -38.40618684
OS 54.2379154 -38.42652716
OS 54.24438732 -38.44964116
OS 54.24531188 -38.46166044
OS 54.24623644 -38.47460428
OS 54.24623644 -38.47552884
OS 54.24623644 -38.4764534
OS 54.24623644 -38.48200076
OS 54.24531188 -38.4903218
OS 54.24346276 -38.50049196
OS 54.24068908 -38.5134358
OS 54.23606628 -38.52637964
OS 54.23051892 -38.53932348
OS 54.22219788 -38.55226732
OS 54.22127332 -38.55411644
OS 54.21757508 -38.55781468
OS 54.21202772 -38.56336204
OS 54.20463124 -38.57075852
OS 54.19446108 -38.57907956
OS 54.1824418 -38.5874006
OS 54.1685734 -38.59572164
OS 54.15193132 -38.60311812
OS 54.15285588 -38.60311812
OS 54.154705 -38.60404268
OS 54.15747868 -38.60496724
OS 54.16117692 -38.60681636
OS 54.17227164 -38.61143916
OS 54.18521548 -38.61791108
OS 54.19908388 -38.62715668
OS 54.21387684 -38.63732684
OS 54.22774524 -38.65027068
OS 54.24068908 -38.66506364
OS 54.24068908 -38.6659882
OS 54.24161364 -38.66691276
OS 54.24531188 -38.67246012
OS 54.25085924 -38.68170572
OS 54.2564066 -38.693725
OS 54.26195396 -38.70851796
OS 54.26750132 -38.7260846
OS 54.27119956 -38.74550036
OS 54.27212412 -38.76676524
OS 54.27212412 -38.7676898
OS 54.27212412 -38.77046348
OS 54.27212412 -38.77508628
OS 54.27119956 -38.78063364
OS 54.270275 -38.78710556
OS 54.26935044 -38.7954266
OS 54.26750132 -38.8046722
OS 54.26472764 -38.81484236
OS 54.25825572 -38.83610724
OS 54.25363292 -38.84812652
OS 54.247161 -38.85922124
OS 54.24068908 -38.87124052
OS 54.2332926 -38.88233524
OS 54.224047 -38.89342996
OS 54.21387684 -38.90452468
OS 54.21295228 -38.90544924
OS 54.21110316 -38.90729836
OS 54.20832948 -38.91007204
OS 54.20370668 -38.91284572
OS 54.19723476 -38.91746852
OS 54.19076284 -38.92209132
OS 54.1824418 -38.92671412
OS 54.1731962 -38.93226148
OS 54.16302604 -38.93780884
OS 54.15100676 -38.94243164
OS 54.13806292 -38.94705444
OS 54.12511908 -38.95167724
OS 54.11032612 -38.95445092
OS 54.0946086 -38.9572246
OS 54.07889108 -38.95907372
OS 54.06132444 -38.95999828
OS 54.05207884 -38.95999828
OS 54.04560692 -38.95907372
OS 54.03728588 -38.95814916
OS 54.02804028 -38.9572246
OS 54.01787012 -38.95537548
OS 54.0067754 -38.9526018
OS 53.98181228 -38.94612988
OS 53.96886844 -38.94150708
OS 53.95684916 -38.93688428
OS 53.94390532 -38.93041236
OS 53.93096148 -38.92301588
OS 53.9189422 -38.91469484
OS 53.90784748 -38.90452468
OS 53.90692292 -38.90360012
OS 53.9050738 -38.901751
OS 53.90230012 -38.89897732
OS 53.89860188 -38.89435452
OS 53.89490364 -38.88880716
OS 53.88935628 -38.88233524
OS 53.88473348 -38.87493876
OS 53.87918612 -38.86569316
OS 53.87363876 -38.85644756
OS 53.86901596 -38.84535284
OS 53.85977036 -38.82223884
OS 53.85607212 -38.80837044
OS 53.85329844 -38.79450204
OS 53.85144932 -38.77970908
OS 53.85052476 -38.76491612
OS 53.85052476 -38.76399156
OS 53.85052476 -38.76214244
OS 53.85052476 -38.7584442
OS 53.85144932 -38.75474596
OS 53.85144932 -38.7491986
OS 53.85237388 -38.74272668
OS 53.854223 -38.72793372
OS 53.85792124 -38.71129164
OS 53.8634686 -38.69464956
OS 53.87178964 -38.67708292
OS 53.8819598 -38.66044084
OS 53.8819598 -38.65951628
OS 53.88380892 -38.65859172
OS 53.88750716 -38.65396892
OS 53.89490364 -38.64657244
OS 53.9050738 -38.63732684
OS 53.91801764 -38.62808124
OS 53.93373516 -38.61791108
OS 53.9513018 -38.60959004
OS 53.97256668 -38.60311812
OS 53.97164212 -38.60311812
OS 53.97071756 -38.60219356
OS 53.96794388 -38.601269
OS 53.96424564 -38.59941988
OS 53.9559246 -38.59572164
OS 53.94482988 -38.59017428
OS 53.9328106 -38.5827778
OS 53.92079132 -38.5735322
OS 53.9096966 -38.56336204
OS 53.89952644 -38.55226732
OS 53.89860188 -38.5504182
OS 53.8958282 -38.54671996
OS 53.89212996 -38.53932348
OS 53.88843172 -38.53007788
OS 53.88380892 -38.5180586
OS 53.88011068 -38.5041902
OS 53.877337 -38.48847268
OS 53.87641244 -38.4718306
OS 53.87641244 -38.47090604
OS 53.87641244 -38.46905692
OS 53.87641244 -38.46535868
OS 53.877337 -38.45981132
OS 53.87826156 -38.45426396
OS 53.87918612 -38.44686748
OS 53.88288436 -38.43114996
OS 53.88843172 -38.41265876
OS 53.89767732 -38.393243
OS 53.90322468 -38.38307284
OS 53.9096966 -38.37290268
OS 53.91801764 -38.36365708
OS 53.92633868 -38.35441148
OS 53.92726324 -38.35348692
OS 53.92911236 -38.35256236
OS 53.93188604 -38.34978868
OS 53.93558428 -38.347015
OS 53.94020708 -38.34331676
OS 53.946679 -38.33961852
OS 53.95407548 -38.33499572
OS 53.96147196 -38.33037292
OS 53.97071756 -38.32575012
OS 53.98088772 -38.32112732
OS 53.99198244 -38.31742908
OS 54.00400172 -38.31373084
OS 54.0298894 -38.30818348
OS 54.04468236 -38.30725892
OS 54.05947532 -38.30633436
OS 54.06779636 -38.30633436
OS 54.07334372 -38.30725892
OE
OB 53.23846604 -38.94890356 I
OS 53.14878372 -38.94890356
OS 53.14878372 -38.85922124
OS 53.23846604 -38.85922124
OS 53.23846604 -38.94890356
OE
OB 53.00177868 -38.39231844 I
OS 52.74567556 -38.39231844
OS 52.71146684 -38.56521116
OS 52.7123914 -38.5642866
OS 52.71424052 -38.56336204
OS 52.7170142 -38.56151292
OS 52.721637 -38.55873924
OS 52.72718436 -38.55596556
OS 52.73365628 -38.55226732
OS 52.74844924 -38.54487084
OS 52.76694044 -38.53747436
OS 52.78728076 -38.53100244
OS 52.8094702 -38.52637964
OS 52.82056492 -38.52453052
OS 52.84090524 -38.52453052
OS 52.8464526 -38.52545508
OS 52.85384908 -38.52637964
OS 52.86217012 -38.5273042
OS 52.87141572 -38.52915332
OS 52.88158588 -38.531927
OS 52.90377532 -38.53839892
OS 52.9157946 -38.54302172
OS 52.92781388 -38.54949364
OS 52.93983316 -38.55596556
OS 52.95185244 -38.56336204
OS 52.96294716 -38.57260764
OS 52.97404188 -38.5827778
OS 52.97496644 -38.58370236
OS 52.97681556 -38.58555148
OS 52.97958924 -38.58832516
OS 52.98328748 -38.59294796
OS 52.98791028 -38.59941988
OS 52.99253308 -38.6058918
OS 52.99808044 -38.61421284
OS 53.0036278 -38.62345844
OS 53.0082506 -38.6336286
OS 53.01379796 -38.64472332
OS 53.01842076 -38.65766716
OS 53.02304356 -38.670611
OS 53.0267418 -38.6844794
OS 53.02951548 -38.70019692
OS 53.0313646 -38.71591444
OS 53.03228916 -38.73255652
OS 53.03228916 -38.73348108
OS 53.03228916 -38.73625476
OS 53.03228916 -38.74087756
OS 53.0313646 -38.74734948
OS 53.03044004 -38.75474596
OS 53.02951548 -38.763067
OS 53.02766636 -38.77323716
OS 53.02581724 -38.78340732
OS 53.02026988 -38.80744588
OS 53.01102428 -38.832409
OS 53.00547692 -38.84535284
OS 52.99808044 -38.85737212
OS 52.99068396 -38.87031596
OS 52.98143836 -38.88233524
OS 52.9805138 -38.8832598
OS 52.97866468 -38.88603348
OS 52.97496644 -38.88973172
OS 52.97034364 -38.89435452
OS 52.96387172 -38.89990188
OS 52.95647524 -38.90729836
OS 52.94722964 -38.91377028
OS 52.93705948 -38.92116676
OS 52.92596476 -38.92856324
OS 52.91302092 -38.93503516
OS 52.89915252 -38.94150708
OS 52.88435956 -38.947979
OS 52.86864204 -38.9526018
OS 52.8510754 -38.95630004
OS 52.8325842 -38.95907372
OS 52.81316844 -38.95999828
OS 52.8048474 -38.95999828
OS 52.79837548 -38.95907372
OS 52.790979 -38.95814916
OS 52.78265796 -38.9572246
OS 52.7724878 -38.95630004
OS 52.76231764 -38.95352636
OS 52.73920364 -38.947979
OS 52.71608964 -38.93965796
OS 52.70407036 -38.9341106
OS 52.69205108 -38.92763868
OS 52.68095636 -38.9202422
OS 52.66986164 -38.91192116
OS 52.66893708 -38.9109966
OS 52.66708796 -38.91007204
OS 52.66523884 -38.9063738
OS 52.6615406 -38.90267556
OS 52.6569178 -38.89805276
OS 52.652295 -38.8925054
OS 52.64674764 -38.88510892
OS 52.64212484 -38.87678788
OS 52.63657748 -38.86846684
OS 52.63103012 -38.85829668
OS 52.62085996 -38.83610724
OS 52.61253892 -38.81021956
OS 52.60976524 -38.79635116
OS 52.60791612 -38.7815582
OS 52.69020196 -38.77508628
OS 52.69020196 -38.77601084
OS 52.69020196 -38.77785996
OS 52.69112652 -38.78063364
OS 52.69205108 -38.78525644
OS 52.69482476 -38.7954266
OS 52.698523 -38.809295
OS 52.70407036 -38.8231634
OS 52.71146684 -38.83888092
OS 52.72071244 -38.85274932
OS 52.73180716 -38.86569316
OS 52.73365628 -38.86661772
OS 52.73735452 -38.87031596
OS 52.744751 -38.87493876
OS 52.75492116 -38.88048612
OS 52.76601588 -38.88603348
OS 52.77988428 -38.89065628
OS 52.7956018 -38.89435452
OS 52.81316844 -38.89527908
OS 52.8187158 -38.89527908
OS 52.82241404 -38.89435452
OS 52.83350876 -38.89342996
OS 52.8464526 -38.88973172
OS 52.86217012 -38.88510892
OS 52.87788764 -38.87771244
OS 52.89452972 -38.86661772
OS 52.9019262 -38.8601458
OS 52.90932268 -38.85274932
OS 52.91024724 -38.85182476
OS 52.9111718 -38.8509002
OS 52.91302092 -38.84812652
OS 52.9157946 -38.84535284
OS 52.92226652 -38.83518268
OS 52.929663 -38.82223884
OS 52.93613492 -38.80652132
OS 52.94260684 -38.78710556
OS 52.94722964 -38.76399156
OS 52.94907876 -38.75197228
OS 52.94907876 -38.73902844
OS 52.94907876 -38.73810388
OS 52.94907876 -38.73625476
OS 52.94907876 -38.73255652
OS 52.9481542 -38.72793372
OS 52.9481542 -38.72238636
OS 52.94722964 -38.71591444
OS 52.94445596 -38.70112148
OS 52.93983316 -38.68355484
OS 52.93336124 -38.6659882
OS 52.92411564 -38.64934612
OS 52.9111718 -38.6336286
OS 52.9111718 -38.63270404
OS 52.90932268 -38.63177948
OS 52.90469988 -38.62715668
OS 52.89637884 -38.62068476
OS 52.88528412 -38.61328828
OS 52.87049116 -38.60681636
OS 52.85384908 -38.60034444
OS 52.83443332 -38.59572164
OS 52.8233386 -38.59387252
OS 52.80577196 -38.59387252
OS 52.79837548 -38.59479708
OS 52.78912988 -38.59572164
OS 52.77803516 -38.59849532
OS 52.76694044 -38.601269
OS 52.75492116 -38.6058918
OS 52.74290188 -38.61143916
OS 52.74197732 -38.61236372
OS 52.73827908 -38.61421284
OS 52.73273172 -38.61883564
OS 52.72533524 -38.62345844
OS 52.71793876 -38.62993036
OS 52.71054228 -38.6382514
OS 52.70222124 -38.64657244
OS 52.69574932 -38.6567426
OS 52.62178452 -38.64657244
OS 52.68373004 -38.31742908
OS 53.00177868 -38.31742908
OS 53.00177868 -38.39231844
OE
OB 53.23846604 -38.57445676 I
OS 53.14878372 -38.57445676
OS 53.14878372 -38.48477444
OS 53.23846604 -38.48477444
OS 53.23846604 -38.57445676
OE
OB 54.48199924 -38.57445676 I
OS 54.39231692 -38.57445676
OS 54.39231692 -38.48477444
OS 54.48199924 -38.48477444
OS 54.48199924 -38.57445676
OE
OB 56.14990548 -38.3100326 I
OS 56.165623 -38.31095716
OS 56.18226508 -38.31188172
OS 56.1979826 -38.31373084
OS 56.211851 -38.31557996
OS 56.21370012 -38.31557996
OS 56.22017204 -38.31742908
OS 56.22849308 -38.3192782
OS 56.2395878 -38.32205188
OS 56.25160708 -38.32667468
OS 56.26455092 -38.33222204
OS 56.27841932 -38.33869396
OS 56.2904386 -38.34609044
OS 56.29228772 -38.347015
OS 56.29598596 -38.34978868
OS 56.30153332 -38.35533604
OS 56.3089298 -38.36180796
OS 56.31725084 -38.370129
OS 56.32557188 -38.38122372
OS 56.33481748 -38.393243
OS 56.34221396 -38.4071114
OS 56.34313852 -38.40896052
OS 56.34498764 -38.41358332
OS 56.34868588 -38.42190436
OS 56.35238412 -38.43299908
OS 56.3551578 -38.44594292
OS 56.35885604 -38.46073588
OS 56.36070516 -38.47737796
OS 56.36162972 -38.4949446
OS 56.36162972 -38.49586916
OS 56.36162972 -38.49864284
OS 56.36162972 -38.50234108
OS 56.36070516 -38.508813
OS 56.3597806 -38.51528492
OS 56.35885604 -38.52360596
OS 56.35700692 -38.53285156
OS 56.3551578 -38.54302172
OS 56.34868588 -38.5642866
OS 56.34498764 -38.57538132
OS 56.33944028 -38.5874006
OS 56.33296836 -38.59941988
OS 56.32649644 -38.6105146
OS 56.3181754 -38.62160932
OS 56.3089298 -38.63270404
OS 56.30800524 -38.6336286
OS 56.30615612 -38.63547772
OS 56.30338244 -38.6382514
OS 56.29875964 -38.64102508
OS 56.29321228 -38.64564788
OS 56.2858158 -38.65027068
OS 56.2765702 -38.65581804
OS 56.26640004 -38.66044084
OS 56.25438076 -38.6659882
OS 56.24051236 -38.67153556
OS 56.2257194 -38.67615836
OS 56.20815276 -38.6798566
OS 56.18966156 -38.68355484
OS 56.16932124 -38.68632852
OS 56.14620724 -38.68817764
OS 56.12216868 -38.6891022
OS 55.95852156 -38.6891022
OS 55.95852156 -38.94890356
OS 55.87346204 -38.94890356
OS 55.87346204 -38.30910804
OS 56.13603708 -38.30910804
OS 56.14990548 -38.3100326
OE
OB 57.07723916 -38.94890356 I
OS 56.99587788 -38.94890356
OS 56.99587788 -38.41358332
OS 56.80911676 -38.94890356
OS 56.73330284 -38.94890356
OS 56.54839084 -38.40433772
OS 56.54839084 -38.94890356
OS 56.46702956 -38.94890356
OS 56.46702956 -38.30910804
OS 56.59369428 -38.30910804
OS 56.74532212 -38.763067
OS 56.74532212 -38.76399156
OS 56.74624668 -38.76584068
OS 56.74717124 -38.76861436
OS 56.74902036 -38.77323716
OS 56.7527186 -38.78433188
OS 56.7573414 -38.79820028
OS 56.7619642 -38.8139178
OS 56.76751156 -38.82963532
OS 56.77213436 -38.84442828
OS 56.7758326 -38.85737212
OS 56.77675716 -38.855523
OS 56.77768172 -38.8509002
OS 56.7804554 -38.84257916
OS 56.78415364 -38.83148444
OS 56.78877644 -38.81669148
OS 56.79524836 -38.79912484
OS 56.80172028 -38.77878452
OS 56.81004132 -38.75474596
OS 56.96351828 -38.30910804
OS 57.07723916 -38.30910804
OS 57.07723916 -38.94890356
OE
OB 55.39084172 -38.94890356 I
OS 55.31225412 -38.94890356
OS 55.31225412 -38.4487166
OS 55.31132956 -38.44964116
OS 55.30670676 -38.4533394
OS 55.3011594 -38.45888676
OS 55.2919138 -38.46535868
OS 55.28174364 -38.47367972
OS 55.2687998 -38.48292532
OS 55.25400684 -38.49309548
OS 55.23736476 -38.50326564
OS 55.2364402 -38.50326564
OS 55.23551564 -38.5041902
OS 55.22996828 -38.50788844
OS 55.22072268 -38.51251124
OS 55.20962796 -38.5180586
OS 55.19668412 -38.52453052
OS 55.18281572 -38.53100244
OS 55.16894732 -38.53747436
OS 55.15507892 -38.54302172
OS 55.15507892 -38.4672078
OS 55.15600348 -38.4672078
OS 55.1578526 -38.46535868
OS 55.16155084 -38.46443412
OS 55.16617364 -38.46166044
OS 55.171721 -38.45888676
OS 55.17819292 -38.45518852
OS 55.19391044 -38.44594292
OS 55.21240164 -38.43577276
OS 55.23089284 -38.42282892
OS 55.2503086 -38.40803596
OS 55.26972436 -38.39231844
OS 55.27064892 -38.39139388
OS 55.27157348 -38.39046932
OS 55.27434716 -38.38769564
OS 55.2780454 -38.38492196
OS 55.28636644 -38.37567636
OS 55.29746116 -38.36458164
OS 55.30855588 -38.3516378
OS 55.32057516 -38.33684484
OS 55.33074532 -38.32205188
OS 55.33999092 -38.30633436
OS 55.39084172 -38.30633436
OS 55.39084172 -38.94890356
OE
OB 54.48199924 -38.94890356 I
OS 54.39231692 -38.94890356
OS 54.39231692 -38.85922124
OS 54.48199924 -38.85922124
OS 54.48199924 -38.94890356
OE
OB 54.825011 -38.30725892 I
OS 54.83703028 -38.30910804
OS 54.85089868 -38.31188172
OS 54.86569164 -38.31557996
OS 54.88140916 -38.32020276
OS 54.89620212 -38.32759924
OS 54.89712668 -38.32759924
OS 54.89805124 -38.3285238
OS 54.90267404 -38.33129748
OS 54.91007052 -38.33592028
OS 54.91931612 -38.3423922
OS 54.92948628 -38.3516378
OS 54.940581 -38.36180796
OS 54.95075116 -38.37382724
OS 54.96092132 -38.38769564
OS 54.96184588 -38.38954476
OS 54.96554412 -38.39416756
OS 54.96924236 -38.4024886
OS 54.97571428 -38.41450788
OS 54.98126164 -38.42837628
OS 54.98865812 -38.4440938
OS 54.99513004 -38.462585
OS 55.0006774 -38.48292532
OS 55.0006774 -38.48384988
OS 55.00160196 -38.485699
OS 55.00252652 -38.48847268
OS 55.00345108 -38.49309548
OS 55.00437564 -38.49864284
OS 55.0053002 -38.50511476
OS 55.00714932 -38.5134358
OS 55.00807388 -38.5226814
OS 55.009923 -38.53285156
OS 55.01084756 -38.54394628
OS 55.01177212 -38.55689012
OS 55.01362124 -38.56983396
OS 55.0145458 -38.58462692
OS 55.0145458 -38.59941988
OS 55.01547036 -38.61606196
OS 55.01547036 -38.6336286
OS 55.01547036 -38.63455316
OS 55.01547036 -38.6382514
OS 55.01547036 -38.64472332
OS 55.01547036 -38.6521198
OS 55.0145458 -38.66228996
OS 55.0145458 -38.67338468
OS 55.01362124 -38.68540396
OS 55.01269668 -38.6983478
OS 55.009923 -38.72793372
OS 55.0053002 -38.7584442
OS 54.99975284 -38.78803012
OS 54.9960546 -38.80189852
OS 54.9914318 -38.81576692
OS 54.9914318 -38.81669148
OS 54.99050724 -38.8185406
OS 54.98865812 -38.82223884
OS 54.986809 -38.82686164
OS 54.98495988 -38.83333356
OS 54.98126164 -38.83980548
OS 54.97386516 -38.855523
OS 54.96461956 -38.87216508
OS 54.95260028 -38.89065628
OS 54.93873188 -38.90729836
OS 54.9220898 -38.92301588
OS 54.92116524 -38.92301588
OS 54.92024068 -38.924865
OS 54.917467 -38.92671412
OS 54.91376876 -38.92856324
OS 54.90914596 -38.93133692
OS 54.90452316 -38.93503516
OS 54.89065476 -38.94150708
OS 54.87401268 -38.947979
OS 54.85459692 -38.95445092
OS 54.83148292 -38.95814916
OS 54.8065198 -38.95999828
OS 54.7972742 -38.95999828
OS 54.79080228 -38.95907372
OS 54.7834058 -38.95814916
OS 54.7741602 -38.95630004
OS 54.76399004 -38.95445092
OS 54.75289532 -38.95167724
OS 54.7418006 -38.947979
OS 54.72978132 -38.94428076
OS 54.71776204 -38.9387334
OS 54.70574276 -38.93226148
OS 54.69372348 -38.924865
OS 54.6817042 -38.9156194
OS 54.67060948 -38.90544924
OS 54.66043932 -38.89435452
OS 54.65951476 -38.89342996
OS 54.65766564 -38.89065628
OS 54.65489196 -38.88603348
OS 54.65026916 -38.878637
OS 54.64564636 -38.87031596
OS 54.64102356 -38.85922124
OS 54.63455164 -38.8462774
OS 54.62900428 -38.83148444
OS 54.62345692 -38.81484236
OS 54.61790956 -38.7954266
OS 54.6123622 -38.77416172
OS 54.6077394 -38.75012316
OS 54.6031166 -38.72423548
OS 54.60034292 -38.69649868
OS 54.5984938 -38.6659882
OS 54.59756924 -38.6336286
OS 54.59756924 -38.63270404
OS 54.59756924 -38.6290058
OS 54.59756924 -38.62253388
OS 54.59756924 -38.6151374
OS 54.5984938 -38.60496724
OS 54.5984938 -38.59387252
OS 54.59941836 -38.58185324
OS 54.60034292 -38.56798484
OS 54.6031166 -38.53932348
OS 54.6077394 -38.508813
OS 54.61328676 -38.47830252
OS 54.616985 -38.46443412
OS 54.62068324 -38.45056572
OS 54.62068324 -38.44964116
OS 54.6216078 -38.44779204
OS 54.62345692 -38.4440938
OS 54.62530604 -38.439471
OS 54.62715516 -38.43299908
OS 54.6308534 -38.42652716
OS 54.63824988 -38.41080964
OS 54.64749548 -38.39416756
OS 54.65951476 -38.37660092
OS 54.67338316 -38.35903428
OS 54.69002524 -38.34424132
OS 54.6909498 -38.34424132
OS 54.69187436 -38.3423922
OS 54.69464804 -38.34054308
OS 54.69834628 -38.33869396
OS 54.70296908 -38.33499572
OS 54.70851644 -38.33222204
OS 54.72238484 -38.32482556
OS 54.73902692 -38.31835364
OS 54.75844268 -38.31188172
OS 54.78155668 -38.30818348
OS 54.8065198 -38.30633436
OS 54.81484084 -38.30633436
OS 54.825011 -38.30725892
OE
OB 49.95350436 -38.72331092 I
OS 50.040413 -38.72331092
OS 50.040413 -38.7954266
OS 49.95350436 -38.7954266
OS 49.95350436 -38.94890356
OS 49.87491676 -38.94890356
OS 49.87491676 -38.7954266
OS 49.5966242 -38.7954266
OS 49.5966242 -38.72331092
OS 49.88970972 -38.30910804
OS 49.95350436 -38.30910804
OS 49.95350436 -38.72331092
OE
OB 50.1467374 -38.95999828 I
OS 50.08386732 -38.95999828
OS 50.26970388 -38.29801332
OS 50.33257396 -38.29801332
OS 50.1467374 -38.95999828
OE
OB 50.59699812 -38.30725892 I
OS 50.6043946 -38.30818348
OS 50.6136402 -38.30910804
OS 50.62381036 -38.31095716
OS 50.63398052 -38.31280628
OS 50.65801908 -38.3192782
OS 50.68205764 -38.3285238
OS 50.69407692 -38.33407116
OS 50.7060962 -38.34054308
OS 50.71719092 -38.34886412
OS 50.72736108 -38.35810972
OS 50.72828564 -38.35903428
OS 50.73013476 -38.35995884
OS 50.73198388 -38.36365708
OS 50.73568212 -38.36735532
OS 50.74030492 -38.37197812
OS 50.74492772 -38.37845004
OS 50.74955052 -38.38492196
OS 50.75509788 -38.393243
OS 50.76434348 -38.41080964
OS 50.77358908 -38.43299908
OS 50.77728732 -38.4440938
OS 50.77913644 -38.45703764
OS 50.78098556 -38.46998148
OS 50.78191012 -38.48384988
OS 50.78191012 -38.485699
OS 50.78191012 -38.4903218
OS 50.78098556 -38.49771828
OS 50.780061 -38.50788844
OS 50.77821188 -38.51898316
OS 50.77451364 -38.531927
OS 50.7708154 -38.5457954
OS 50.76526804 -38.5596638
OS 50.76434348 -38.56151292
OS 50.76249436 -38.56613572
OS 50.75879612 -38.5735322
OS 50.75324876 -38.58370236
OS 50.74585228 -38.59479708
OS 50.73660668 -38.60866548
OS 50.72551196 -38.62253388
OS 50.71256812 -38.6382514
OS 50.710719 -38.64010052
OS 50.7060962 -38.64564788
OS 50.7014734 -38.65027068
OS 50.6968506 -38.65489348
OS 50.69130324 -38.66044084
OS 50.68390676 -38.66783732
OS 50.67651028 -38.6752338
OS 50.66726468 -38.68355484
OS 50.65801908 -38.69280044
OS 50.64692436 -38.7029706
OS 50.63490508 -38.71314076
OS 50.62196124 -38.72516004
OS 50.60716828 -38.73717932
OS 50.59237532 -38.75012316
OS 50.59145076 -38.75104772
OS 50.58960164 -38.75289684
OS 50.5859034 -38.75567052
OS 50.5812806 -38.75936876
OS 50.57573324 -38.76491612
OS 50.56926132 -38.77046348
OS 50.55446836 -38.78248276
OS 50.53875084 -38.79635116
OS 50.52395788 -38.81021956
OS 50.51101404 -38.82223884
OS 50.50546668 -38.82686164
OS 50.50084388 -38.83148444
OS 50.49991932 -38.832409
OS 50.49714564 -38.83518268
OS 50.4934474 -38.83888092
OS 50.4888246 -38.84442828
OS 50.4842018 -38.8509002
OS 50.47865444 -38.85737212
OS 50.46755972 -38.87308964
OS 50.78283468 -38.87308964
OS 50.78283468 -38.94890356
OS 50.35846164 -38.94890356
OS 50.35846164 -38.947979
OS 50.35846164 -38.94428076
OS 50.35846164 -38.9387334
OS 50.3593862 -38.93133692
OS 50.36031076 -38.92301588
OS 50.36215988 -38.91377028
OS 50.364009 -38.90452468
OS 50.36770724 -38.89435452
OS 50.36770724 -38.89342996
OS 50.3686318 -38.8925054
OS 50.37048092 -38.88695804
OS 50.37417916 -38.878637
OS 50.37972652 -38.86754228
OS 50.387123 -38.85459844
OS 50.3963686 -38.83980548
OS 50.40653876 -38.82501252
OS 50.4194826 -38.809295
OS 50.4194826 -38.80837044
OS 50.42133172 -38.80744588
OS 50.42595452 -38.80189852
OS 50.43427556 -38.79357748
OS 50.44629484 -38.7815582
OS 50.46016324 -38.7676898
OS 50.47772988 -38.75104772
OS 50.49899476 -38.73255652
OS 50.52210876 -38.71314076
OS 50.52303332 -38.7122162
OS 50.52673156 -38.70944252
OS 50.53227892 -38.70481972
OS 50.53875084 -38.69927236
OS 50.54707188 -38.69187588
OS 50.55724204 -38.68355484
OS 50.5674122 -38.67430924
OS 50.57943148 -38.66413908
OS 50.60254548 -38.64194964
OS 50.62565948 -38.6197602
OS 50.6367542 -38.60866548
OS 50.64692436 -38.59757076
OS 50.65616996 -38.5874006
OS 50.66356644 -38.57723044
OS 50.66356644 -38.57630588
OS 50.66541556 -38.57538132
OS 50.66726468 -38.57260764
OS 50.6691138 -38.5689094
OS 50.67558572 -38.55873924
OS 50.6829822 -38.54671996
OS 50.68945412 -38.531927
OS 50.69592604 -38.51620948
OS 50.69962428 -38.49864284
OS 50.7014734 -38.48200076
OS 50.7014734 -38.4810762
OS 50.7014734 -38.48015164
OS 50.70054884 -38.47460428
OS 50.69962428 -38.46535868
OS 50.6968506 -38.45518852
OS 50.69315236 -38.44224468
OS 50.68668044 -38.42930084
OS 50.6783594 -38.416357
OS 50.66726468 -38.40341316
OS 50.66541556 -38.40156404
OS 50.66079276 -38.3978658
OS 50.65432084 -38.393243
OS 50.64415068 -38.38677108
OS 50.63120684 -38.38122372
OS 50.61641388 -38.37567636
OS 50.59884724 -38.37197812
OS 50.57943148 -38.37105356
OS 50.57388412 -38.37105356
OS 50.57018588 -38.37197812
OS 50.55909116 -38.37290268
OS 50.54614732 -38.37567636
OS 50.53227892 -38.3793746
OS 50.5165614 -38.38584652
OS 50.50176844 -38.39416756
OS 50.48790004 -38.40526228
OS 50.48605092 -38.4071114
OS 50.48235268 -38.4117342
OS 50.47680532 -38.41913068
OS 50.47125796 -38.4302254
OS 50.46478604 -38.44316924
OS 50.45923868 -38.45981132
OS 50.45554044 -38.47830252
OS 50.45369132 -38.4995674
OS 50.3732546 -38.49124636
OS 50.3732546 -38.4903218
OS 50.37417916 -38.48754812
OS 50.37417916 -38.48292532
OS 50.37510372 -38.4764534
OS 50.37695284 -38.46905692
OS 50.37880196 -38.46073588
OS 50.38157564 -38.45056572
OS 50.38434932 -38.44039556
OS 50.3917458 -38.41820612
OS 50.40284052 -38.39601668
OS 50.40931244 -38.38492196
OS 50.41763348 -38.37382724
OS 50.42595452 -38.36365708
OS 50.43520012 -38.35441148
OS 50.43612468 -38.35348692
OS 50.4379738 -38.35256236
OS 50.44074748 -38.34978868
OS 50.44537028 -38.347015
OS 50.45091764 -38.34331676
OS 50.45738956 -38.33961852
OS 50.46478604 -38.33499572
OS 50.47403164 -38.33037292
OS 50.4842018 -38.32575012
OS 50.49529652 -38.32112732
OS 50.5073158 -38.31742908
OS 50.52025964 -38.31373084
OS 50.53412804 -38.31095716
OS 50.548921 -38.30818348
OS 50.56463852 -38.30725892
OS 50.5812806 -38.30633436
OS 50.5905262 -38.30633436
OS 50.59699812 -38.30725892
OE
OB 48.67576244 -38.94890356 I
OS 48.59717484 -38.94890356
OS 48.59717484 -38.4487166
OS 48.59625028 -38.44964116
OS 48.59162748 -38.4533394
OS 48.58608012 -38.45888676
OS 48.57683452 -38.46535868
OS 48.56666436 -38.47367972
OS 48.55372052 -38.48292532
OS 48.53892756 -38.49309548
OS 48.52228548 -38.50326564
OS 48.52136092 -38.50326564
OS 48.52043636 -38.5041902
OS 48.514889 -38.50788844
OS 48.5056434 -38.51251124
OS 48.49454868 -38.5180586
OS 48.48160484 -38.52453052
OS 48.46773644 -38.53100244
OS 48.45386804 -38.53747436
OS 48.43999964 -38.54302172
OS 48.43999964 -38.4672078
OS 48.4409242 -38.4672078
OS 48.44277332 -38.46535868
OS 48.44647156 -38.46443412
OS 48.45109436 -38.46166044
OS 48.45664172 -38.45888676
OS 48.46311364 -38.45518852
OS 48.47883116 -38.44594292
OS 48.49732236 -38.43577276
OS 48.51581356 -38.42282892
OS 48.53522932 -38.40803596
OS 48.55464508 -38.39231844
OS 48.55556964 -38.39139388
OS 48.5564942 -38.39046932
OS 48.55926788 -38.38769564
OS 48.56296612 -38.38492196
OS 48.57128716 -38.37567636
OS 48.58238188 -38.36458164
OS 48.5934766 -38.3516378
OS 48.60549588 -38.33684484
OS 48.61566604 -38.32205188
OS 48.62491164 -38.30633436
OS 48.67576244 -38.30633436
OS 48.67576244 -38.94890356
OE
OB 48.9032042 -38.95999828 I
OS 48.84033412 -38.95999828
OS 49.02617068 -38.29801332
OS 49.08904076 -38.29801332
OS 48.9032042 -38.95999828
OE
OB 49.35346492 -38.30725892 I
OS 49.3608614 -38.30818348
OS 49.370107 -38.30910804
OS 49.38027716 -38.31095716
OS 49.39044732 -38.31280628
OS 49.41448588 -38.3192782
OS 49.43852444 -38.3285238
OS 49.45054372 -38.33407116
OS 49.462563 -38.34054308
OS 49.47365772 -38.34886412
OS 49.48382788 -38.35810972
OS 49.48475244 -38.35903428
OS 49.48660156 -38.35995884
OS 49.48845068 -38.36365708
OS 49.49214892 -38.36735532
OS 49.49677172 -38.37197812
OS 49.50139452 -38.37845004
OS 49.50601732 -38.38492196
OS 49.51156468 -38.393243
OS 49.52081028 -38.41080964
OS 49.53005588 -38.43299908
OS 49.53375412 -38.4440938
OS 49.53560324 -38.45703764
OS 49.53745236 -38.46998148
OS 49.53837692 -38.48384988
OS 49.53837692 -38.485699
OS 49.53837692 -38.4903218
OS 49.53745236 -38.49771828
OS 49.5365278 -38.50788844
OS 49.53467868 -38.51898316
OS 49.53098044 -38.531927
OS 49.5272822 -38.5457954
OS 49.52173484 -38.5596638
OS 49.52081028 -38.56151292
OS 49.51896116 -38.56613572
OS 49.51526292 -38.5735322
OS 49.50971556 -38.58370236
OS 49.50231908 -38.59479708
OS 49.49307348 -38.60866548
OS 49.48197876 -38.62253388
OS 49.46903492 -38.6382514
OS 49.4671858 -38.64010052
OS 49.462563 -38.64564788
OS 49.4579402 -38.65027068
OS 49.4533174 -38.65489348
OS 49.44777004 -38.66044084
OS 49.44037356 -38.66783732
OS 49.43297708 -38.6752338
OS 49.42373148 -38.68355484
OS 49.41448588 -38.69280044
OS 49.40339116 -38.7029706
OS 49.39137188 -38.71314076
OS 49.37842804 -38.72516004
OS 49.36363508 -38.73717932
OS 49.34884212 -38.75012316
OS 49.34791756 -38.75104772
OS 49.34606844 -38.75289684
OS 49.3423702 -38.75567052
OS 49.3377474 -38.75936876
OS 49.33220004 -38.76491612
OS 49.32572812 -38.77046348
OS 49.31093516 -38.78248276
OS 49.29521764 -38.79635116
OS 49.28042468 -38.81021956
OS 49.26748084 -38.82223884
OS 49.26193348 -38.82686164
OS 49.25731068 -38.83148444
OS 49.25638612 -38.832409
OS 49.25361244 -38.83518268
OS 49.2499142 -38.83888092
OS 49.2452914 -38.84442828
OS 49.2406686 -38.8509002
OS 49.23512124 -38.85737212
OS 49.22402652 -38.87308964
OS 49.53930148 -38.87308964
OS 49.53930148 -38.94890356
OS 49.11492844 -38.94890356
OS 49.11492844 -38.947979
OS 49.11492844 -38.94428076
OS 49.11492844 -38.9387334
OS 49.115853 -38.93133692
OS 49.11677756 -38.92301588
OS 49.11862668 -38.91377028
OS 49.1204758 -38.90452468
OS 49.12417404 -38.89435452
OS 49.12417404 -38.89342996
OS 49.1250986 -38.8925054
OS 49.12694772 -38.88695804
OS 49.13064596 -38.878637
OS 49.13619332 -38.86754228
OS 49.1435898 -38.85459844
OS 49.1528354 -38.83980548
OS 49.16300556 -38.82501252
OS 49.1759494 -38.809295
OS 49.1759494 -38.80837044
OS 49.17779852 -38.80744588
OS 49.18242132 -38.80189852
OS 49.19074236 -38.79357748
OS 49.20276164 -38.7815582
OS 49.21663004 -38.7676898
OS 49.23419668 -38.75104772
OS 49.25546156 -38.73255652
OS 49.27857556 -38.71314076
OS 49.27950012 -38.7122162
OS 49.28319836 -38.70944252
OS 49.28874572 -38.70481972
OS 49.29521764 -38.69927236
OS 49.30353868 -38.69187588
OS 49.31370884 -38.68355484
OS 49.323879 -38.67430924
OS 49.33589828 -38.66413908
OS 49.35901228 -38.64194964
OS 49.38212628 -38.6197602
OS 49.393221 -38.60866548
OS 49.40339116 -38.59757076
OS 49.41263676 -38.5874006
OS 49.42003324 -38.57723044
OS 49.42003324 -38.57630588
OS 49.42188236 -38.57538132
OS 49.42373148 -38.57260764
OS 49.4255806 -38.5689094
OS 49.43205252 -38.55873924
OS 49.439449 -38.54671996
OS 49.44592092 -38.531927
OS 49.45239284 -38.51620948
OS 49.45609108 -38.49864284
OS 49.4579402 -38.48200076
OS 49.4579402 -38.4810762
OS 49.4579402 -38.48015164
OS 49.45701564 -38.47460428
OS 49.45609108 -38.46535868
OS 49.4533174 -38.45518852
OS 49.44961916 -38.44224468
OS 49.44314724 -38.42930084
OS 49.4348262 -38.416357
OS 49.42373148 -38.40341316
OS 49.42188236 -38.40156404
OS 49.41725956 -38.3978658
OS 49.41078764 -38.393243
OS 49.40061748 -38.38677108
OS 49.38767364 -38.38122372
OS 49.37288068 -38.37567636
OS 49.35531404 -38.37197812
OS 49.33589828 -38.37105356
OS 49.33035092 -38.37105356
OS 49.32665268 -38.37197812
OS 49.31555796 -38.37290268
OS 49.30261412 -38.37567636
OS 49.28874572 -38.3793746
OS 49.2730282 -38.38584652
OS 49.25823524 -38.39416756
OS 49.24436684 -38.40526228
OS 49.24251772 -38.4071114
OS 49.23881948 -38.4117342
OS 49.23327212 -38.41913068
OS 49.22772476 -38.4302254
OS 49.22125284 -38.44316924
OS 49.21570548 -38.45981132
OS 49.21200724 -38.47830252
OS 49.21015812 -38.4995674
OS 49.1297214 -38.49124636
OS 49.1297214 -38.4903218
OS 49.13064596 -38.48754812
OS 49.13064596 -38.48292532
OS 49.13157052 -38.4764534
OS 49.13341964 -38.46905692
OS 49.13526876 -38.46073588
OS 49.13804244 -38.45056572
OS 49.14081612 -38.44039556
OS 49.1482126 -38.41820612
OS 49.15930732 -38.39601668
OS 49.16577924 -38.38492196
OS 49.17410028 -38.37382724
OS 49.18242132 -38.36365708
OS 49.19166692 -38.35441148
OS 49.19259148 -38.35348692
OS 49.1944406 -38.35256236
OS 49.19721428 -38.34978868
OS 49.20183708 -38.347015
OS 49.20738444 -38.34331676
OS 49.21385636 -38.33961852
OS 49.22125284 -38.33499572
OS 49.23049844 -38.33037292
OS 49.2406686 -38.32575012
OS 49.25176332 -38.32112732
OS 49.2637826 -38.31742908
OS 49.27672644 -38.31373084
OS 49.29059484 -38.31095716
OS 49.3053878 -38.30818348
OS 49.32110532 -38.30725892
OS 49.3377474 -38.30633436
OS 49.346993 -38.30633436
OS 49.35346492 -38.30725892
OE
OB 51.0944114 -38.30725892 I
OS 51.10643068 -38.30910804
OS 51.12029908 -38.31188172
OS 51.13509204 -38.31557996
OS 51.15080956 -38.32020276
OS 51.16560252 -38.32759924
OS 51.16652708 -38.32759924
OS 51.16745164 -38.3285238
OS 51.17207444 -38.33129748
OS 51.17947092 -38.33592028
OS 51.18871652 -38.3423922
OS 51.19888668 -38.3516378
OS 51.2099814 -38.36180796
OS 51.22015156 -38.37382724
OS 51.23032172 -38.38769564
OS 51.23124628 -38.38954476
OS 51.23494452 -38.39416756
OS 51.23864276 -38.4024886
OS 51.24511468 -38.41450788
OS 51.25066204 -38.42837628
OS 51.25805852 -38.4440938
OS 51.26453044 -38.462585
OS 51.2700778 -38.48292532
OS 51.2700778 -38.48384988
OS 51.27100236 -38.485699
OS 51.27192692 -38.48847268
OS 51.27285148 -38.49309548
OS 51.27377604 -38.49864284
OS 51.2747006 -38.50511476
OS 51.27654972 -38.5134358
OS 51.27747428 -38.5226814
OS 51.2793234 -38.53285156
OS 51.28024796 -38.54394628
OS 51.28117252 -38.55689012
OS 51.28302164 -38.56983396
OS 51.2839462 -38.58462692
OS 51.2839462 -38.59941988
OS 51.28487076 -38.61606196
OS 51.28487076 -38.6336286
OS 51.28487076 -38.63455316
OS 51.28487076 -38.6382514
OS 51.28487076 -38.64472332
OS 51.28487076 -38.6521198
OS 51.2839462 -38.66228996
OS 51.2839462 -38.67338468
OS 51.28302164 -38.68540396
OS 51.28209708 -38.6983478
OS 51.2793234 -38.72793372
OS 51.2747006 -38.7584442
OS 51.26915324 -38.78803012
OS 51.265455 -38.80189852
OS 51.2608322 -38.81576692
OS 51.2608322 -38.81669148
OS 51.25990764 -38.8185406
OS 51.25805852 -38.82223884
OS 51.2562094 -38.82686164
OS 51.25436028 -38.83333356
OS 51.25066204 -38.83980548
OS 51.24326556 -38.855523
OS 51.23401996 -38.87216508
OS 51.22200068 -38.89065628
OS 51.20813228 -38.90729836
OS 51.1914902 -38.92301588
OS 51.19056564 -38.92301588
OS 51.18964108 -38.924865
OS 51.1868674 -38.92671412
OS 51.18316916 -38.92856324
OS 51.17854636 -38.93133692
OS 51.17392356 -38.93503516
OS 51.16005516 -38.94150708
OS 51.14341308 -38.947979
OS 51.12399732 -38.95445092
OS 51.10088332 -38.95814916
OS 51.0759202 -38.95999828
OS 51.0666746 -38.95999828
OS 51.06020268 -38.95907372
OS 51.0528062 -38.95814916
OS 51.0435606 -38.95630004
OS 51.03339044 -38.95445092
OS 51.02229572 -38.95167724
OS 51.011201 -38.947979
OS 50.99918172 -38.94428076
OS 50.98716244 -38.9387334
OS 50.97514316 -38.93226148
OS 50.96312388 -38.924865
OS 50.9511046 -38.9156194
OS 50.94000988 -38.90544924
OS 50.92983972 -38.89435452
OS 50.92891516 -38.89342996
OS 50.92706604 -38.89065628
OS 50.92429236 -38.88603348
OS 50.91966956 -38.878637
OS 50.91504676 -38.87031596
OS 50.91042396 -38.85922124
OS 50.90395204 -38.8462774
OS 50.89840468 -38.83148444
OS 50.89285732 -38.81484236
OS 50.88730996 -38.7954266
OS 50.8817626 -38.77416172
OS 50.8771398 -38.75012316
OS 50.872517 -38.72423548
OS 50.86974332 -38.69649868
OS 50.8678942 -38.6659882
OS 50.86696964 -38.6336286
OS 50.86696964 -38.63270404
OS 50.86696964 -38.6290058
OS 50.86696964 -38.62253388
OS 50.86696964 -38.6151374
OS 50.8678942 -38.60496724
OS 50.8678942 -38.59387252
OS 50.86881876 -38.58185324
OS 50.86974332 -38.56798484
OS 50.872517 -38.53932348
OS 50.8771398 -38.508813
OS 50.88268716 -38.47830252
OS 50.8863854 -38.46443412
OS 50.89008364 -38.45056572
OS 50.89008364 -38.44964116
OS 50.8910082 -38.44779204
OS 50.89285732 -38.4440938
OS 50.89470644 -38.439471
OS 50.89655556 -38.43299908
OS 50.9002538 -38.42652716
OS 50.90765028 -38.41080964
OS 50.91689588 -38.39416756
OS 50.92891516 -38.37660092
OS 50.94278356 -38.35903428
OS 50.95942564 -38.34424132
OS 50.9603502 -38.34424132
OS 50.96127476 -38.3423922
OS 50.96404844 -38.34054308
OS 50.96774668 -38.33869396
OS 50.97236948 -38.33499572
OS 50.97791684 -38.33222204
OS 50.99178524 -38.32482556
OS 51.00842732 -38.31835364
OS 51.02784308 -38.31188172
OS 51.05095708 -38.30818348
OS 51.0759202 -38.30633436
OS 51.08424124 -38.30633436
OS 51.0944114 -38.30725892
OE
OB 51.59182468 -38.30725892 I
OS 51.59922116 -38.30818348
OS 51.60846676 -38.30910804
OS 51.61863692 -38.31095716
OS 51.62880708 -38.31280628
OS 51.65284564 -38.3192782
OS 51.6768842 -38.3285238
OS 51.68890348 -38.33407116
OS 51.70092276 -38.34054308
OS 51.71201748 -38.34886412
OS 51.72218764 -38.35810972
OS 51.7231122 -38.35903428
OS 51.72496132 -38.35995884
OS 51.72681044 -38.36365708
OS 51.73050868 -38.36735532
OS 51.73513148 -38.37197812
OS 51.73975428 -38.37845004
OS 51.74437708 -38.38492196
OS 51.74992444 -38.393243
OS 51.75917004 -38.41080964
OS 51.76841564 -38.43299908
OS 51.77211388 -38.4440938
OS 51.773963 -38.45703764
OS 51.77581212 -38.46998148
OS 51.77673668 -38.48384988
OS 51.77673668 -38.485699
OS 51.77673668 -38.4903218
OS 51.77581212 -38.49771828
OS 51.77488756 -38.50788844
OS 51.77303844 -38.51898316
OS 51.7693402 -38.531927
OS 51.76564196 -38.5457954
OS 51.7600946 -38.5596638
OS 51.75917004 -38.56151292
OS 51.75732092 -38.56613572
OS 51.75362268 -38.5735322
OS 51.74807532 -38.58370236
OS 51.74067884 -38.59479708
OS 51.73143324 -38.60866548
OS 51.72033852 -38.62253388
OS 51.70739468 -38.6382514
OS 51.70554556 -38.64010052
OS 51.70092276 -38.64564788
OS 51.69629996 -38.65027068
OS 51.69167716 -38.65489348
OS 51.6861298 -38.66044084
OS 51.67873332 -38.66783732
OS 51.67133684 -38.6752338
OS 51.66209124 -38.68355484
OS 51.65284564 -38.69280044
OS 51.64175092 -38.7029706
OS 51.62973164 -38.71314076
OS 51.6167878 -38.72516004
OS 51.60199484 -38.73717932
OS 51.58720188 -38.75012316
OS 51.58627732 -38.75104772
OS 51.5844282 -38.75289684
OS 51.58072996 -38.75567052
OS 51.57610716 -38.75936876
OS 51.5705598 -38.76491612
OS 51.56408788 -38.77046348
OS 51.54929492 -38.78248276
OS 51.5335774 -38.79635116
OS 51.51878444 -38.81021956
OS 51.5058406 -38.82223884
OS 51.50029324 -38.82686164
OS 51.49567044 -38.83148444
OS 51.49474588 -38.832409
OS 51.4919722 -38.83518268
OS 51.48827396 -38.83888092
OS 51.48365116 -38.84442828
OS 51.47902836 -38.8509002
OS 51.473481 -38.85737212
OS 51.46238628 -38.87308964
OS 51.77766124 -38.87308964
OS 51.77766124 -38.94890356
OS 51.3532882 -38.94890356
OS 51.3532882 -38.947979
OS 51.3532882 -38.94428076
OS 51.3532882 -38.9387334
OS 51.35421276 -38.93133692
OS 51.35513732 -38.92301588
OS 51.35698644 -38.91377028
OS 51.35883556 -38.90452468
OS 51.3625338 -38.89435452
OS 51.3625338 -38.89342996
OS 51.36345836 -38.8925054
OS 51.36530748 -38.88695804
OS 51.36900572 -38.878637
OS 51.37455308 -38.86754228
OS 51.38194956 -38.85459844
OS 51.39119516 -38.83980548
OS 51.40136532 -38.82501252
OS 51.41430916 -38.809295
OS 51.41430916 -38.80837044
OS 51.41615828 -38.80744588
OS 51.42078108 -38.80189852
OS 51.42910212 -38.79357748
OS 51.4411214 -38.7815582
OS 51.4549898 -38.7676898
OS 51.47255644 -38.75104772
OS 51.49382132 -38.73255652
OS 51.51693532 -38.71314076
OS 51.51785988 -38.7122162
OS 51.52155812 -38.70944252
OS 51.52710548 -38.70481972
OS 51.5335774 -38.69927236
OS 51.54189844 -38.69187588
OS 51.5520686 -38.68355484
OS 51.56223876 -38.67430924
OS 51.57425804 -38.66413908
OS 51.59737204 -38.64194964
OS 51.62048604 -38.6197602
OS 51.63158076 -38.60866548
OS 51.64175092 -38.59757076
OS 51.65099652 -38.5874006
OS 51.658393 -38.57723044
OS 51.658393 -38.57630588
OS 51.66024212 -38.57538132
OS 51.66209124 -38.57260764
OS 51.66394036 -38.5689094
OS 51.67041228 -38.55873924
OS 51.67780876 -38.54671996
OS 51.68428068 -38.531927
OS 51.6907526 -38.51620948
OS 51.69445084 -38.49864284
OS 51.69629996 -38.48200076
OS 51.69629996 -38.4810762
OS 51.69629996 -38.48015164
OS 51.6953754 -38.47460428
OS 51.69445084 -38.46535868
OS 51.69167716 -38.45518852
OS 51.68797892 -38.44224468
OS 51.681507 -38.42930084
OS 51.67318596 -38.416357
OS 51.66209124 -38.40341316
OS 51.66024212 -38.40156404
OS 51.65561932 -38.3978658
OS 51.6491474 -38.393243
OS 51.63897724 -38.38677108
OS 51.6260334 -38.38122372
OS 51.61124044 -38.37567636
OS 51.5936738 -38.37197812
OS 51.57425804 -38.37105356
OS 51.56871068 -38.37105356
OS 51.56501244 -38.37197812
OS 51.55391772 -38.37290268
OS 51.54097388 -38.37567636
OS 51.52710548 -38.3793746
OS 51.51138796 -38.38584652
OS 51.496595 -38.39416756
OS 51.4827266 -38.40526228
OS 51.48087748 -38.4071114
OS 51.47717924 -38.4117342
OS 51.47163188 -38.41913068
OS 51.46608452 -38.4302254
OS 51.4596126 -38.44316924
OS 51.45406524 -38.45981132
OS 51.450367 -38.47830252
OS 51.44851788 -38.4995674
OS 51.36808116 -38.49124636
OS 51.36808116 -38.4903218
OS 51.36900572 -38.48754812
OS 51.36900572 -38.48292532
OS 51.36993028 -38.4764534
OS 51.3717794 -38.46905692
OS 51.37362852 -38.46073588
OS 51.3764022 -38.45056572
OS 51.37917588 -38.44039556
OS 51.38657236 -38.41820612
OS 51.39766708 -38.39601668
OS 51.404139 -38.38492196
OS 51.41246004 -38.37382724
OS 51.42078108 -38.36365708
OS 51.43002668 -38.35441148
OS 51.43095124 -38.35348692
OS 51.43280036 -38.35256236
OS 51.43557404 -38.34978868
OS 51.44019684 -38.347015
OS 51.4457442 -38.34331676
OS 51.45221612 -38.33961852
OS 51.4596126 -38.33499572
OS 51.4688582 -38.33037292
OS 51.47902836 -38.32575012
OS 51.49012308 -38.32112732
OS 51.50214236 -38.31742908
OS 51.5150862 -38.31373084
OS 51.5289546 -38.31095716
OS 51.54374756 -38.30818348
OS 51.55946508 -38.30725892
OS 51.57610716 -38.30633436
OS 51.58535276 -38.30633436
OS 51.59182468 -38.30725892
OE
OB 52.08184148 -38.30725892 I
OS 52.09386076 -38.30910804
OS 52.10865372 -38.31188172
OS 52.1252958 -38.31650452
OS 52.14193788 -38.32205188
OS 52.15857996 -38.32944836
OS 52.15950452 -38.32944836
OS 52.16042908 -38.33037292
OS 52.16597644 -38.3331466
OS 52.17429748 -38.33869396
OS 52.18354308 -38.34516588
OS 52.1946378 -38.35441148
OS 52.20573252 -38.36458164
OS 52.21682724 -38.37660092
OS 52.22607284 -38.39046932
OS 52.2269974 -38.39231844
OS 52.22977108 -38.39694124
OS 52.23346932 -38.40526228
OS 52.23809212 -38.41543244
OS 52.24271492 -38.42745172
OS 52.24641316 -38.44132012
OS 52.24918684 -38.45703764
OS 52.2501114 -38.47275516
OS 52.2501114 -38.47460428
OS 52.2501114 -38.48015164
OS 52.24918684 -38.48754812
OS 52.24733772 -38.49771828
OS 52.24456404 -38.50973756
OS 52.23994124 -38.5226814
OS 52.23439388 -38.53562524
OS 52.2269974 -38.54856908
OS 52.22607284 -38.5504182
OS 52.22329916 -38.55411644
OS 52.2177518 -38.56058836
OS 52.21035532 -38.56798484
OS 52.20110972 -38.57630588
OS 52.190015 -38.58555148
OS 52.17707116 -38.59387252
OS 52.16135364 -38.60219356
OS 52.1622782 -38.60219356
OS 52.16412732 -38.60311812
OS 52.166901 -38.60404268
OS 52.17059924 -38.60496724
OS 52.1807694 -38.60866548
OS 52.19371324 -38.61421284
OS 52.2085062 -38.62160932
OS 52.22329916 -38.63085492
OS 52.23716756 -38.6428742
OS 52.2501114 -38.6567426
OS 52.25103596 -38.65859172
OS 52.2547342 -38.66413908
OS 52.26028156 -38.67338468
OS 52.26582892 -38.68540396
OS 52.27137628 -38.70019692
OS 52.27692364 -38.71776356
OS 52.28062188 -38.73810388
OS 52.28154644 -38.76029332
OS 52.28154644 -38.76121788
OS 52.28154644 -38.76399156
OS 52.28154644 -38.76861436
OS 52.28062188 -38.77416172
OS 52.27969732 -38.7815582
OS 52.2778482 -38.78987924
OS 52.27599908 -38.79912484
OS 52.27414996 -38.809295
OS 52.26675348 -38.83148444
OS 52.26120612 -38.84350372
OS 52.25565876 -38.85459844
OS 52.24826228 -38.86661772
OS 52.23994124 -38.878637
OS 52.23069564 -38.89065628
OS 52.21960092 -38.901751
OS 52.21867636 -38.90267556
OS 52.21682724 -38.90452468
OS 52.213129 -38.90729836
OS 52.2085062 -38.9109966
OS 52.20295884 -38.9156194
OS 52.19556236 -38.9202422
OS 52.18724132 -38.92578956
OS 52.17707116 -38.93041236
OS 52.166901 -38.93595972
OS 52.15488172 -38.94150708
OS 52.14286244 -38.94612988
OS 52.12899404 -38.95075268
OS 52.11420108 -38.95445092
OS 52.09848356 -38.9572246
OS 52.08276604 -38.95907372
OS 52.0651994 -38.95999828
OS 52.05687836 -38.95999828
OS 52.051331 -38.95907372
OS 52.04393452 -38.95814916
OS 52.03561348 -38.9572246
OS 52.02636788 -38.95537548
OS 52.01619772 -38.95352636
OS 51.99400828 -38.947979
OS 51.97089428 -38.9387334
OS 51.958875 -38.93318604
OS 51.94778028 -38.92671412
OS 51.93668556 -38.91839308
OS 51.92559084 -38.91007204
OS 51.92466628 -38.90914748
OS 51.92281716 -38.90729836
OS 51.92004348 -38.90452468
OS 51.9172698 -38.90082644
OS 51.912647 -38.89620364
OS 51.9080242 -38.88973172
OS 51.90247684 -38.8832598
OS 51.89692948 -38.87493876
OS 51.89138212 -38.86569316
OS 51.88583476 -38.85644756
OS 51.8756646 -38.83425812
OS 51.86734356 -38.80837044
OS 51.86456988 -38.79450204
OS 51.86272076 -38.77970908
OS 51.94130836 -38.76953892
OS 51.94130836 -38.77046348
OS 51.94223292 -38.7723126
OS 51.94315748 -38.77601084
OS 51.94408204 -38.78063364
OS 51.9450066 -38.786181
OS 51.94685572 -38.79265292
OS 51.95147852 -38.80652132
OS 51.95795044 -38.8231634
OS 51.96627148 -38.83888092
OS 51.97551708 -38.85367388
OS 51.9866118 -38.86661772
OS 51.98846092 -38.86754228
OS 51.99215916 -38.87124052
OS 51.99955564 -38.87586332
OS 52.00880124 -38.88048612
OS 52.01989596 -38.88603348
OS 52.03376436 -38.89065628
OS 52.04948188 -38.89435452
OS 52.06612396 -38.89527908
OS 52.07167132 -38.89527908
OS 52.07536956 -38.89435452
OS 52.08553972 -38.89342996
OS 52.09848356 -38.89065628
OS 52.11327652 -38.88603348
OS 52.12899404 -38.87956156
OS 52.14471156 -38.87031596
OS 52.15950452 -38.85737212
OS 52.16135364 -38.855523
OS 52.16597644 -38.84997564
OS 52.1715238 -38.8416546
OS 52.17892028 -38.83055988
OS 52.18631676 -38.81669148
OS 52.19186412 -38.80097396
OS 52.19648692 -38.78248276
OS 52.19833604 -38.76214244
OS 52.19833604 -38.76121788
OS 52.19833604 -38.75936876
OS 52.19833604 -38.75659508
OS 52.19741148 -38.75289684
OS 52.19648692 -38.74272668
OS 52.19371324 -38.7307074
OS 52.190015 -38.71591444
OS 52.18354308 -38.70112148
OS 52.17429748 -38.68632852
OS 52.1622782 -38.67246012
OS 52.16042908 -38.670611
OS 52.15580628 -38.66691276
OS 52.1484098 -38.6613654
OS 52.13823964 -38.65489348
OS 52.1252958 -38.64842156
OS 52.10957828 -38.6428742
OS 52.09201164 -38.63917596
OS 52.07259588 -38.63732684
OS 52.06427484 -38.63732684
OS 52.05780292 -38.6382514
OS 52.04948188 -38.63917596
OS 52.04023628 -38.64102508
OS 52.02914156 -38.6428742
OS 52.01712228 -38.64564788
OS 52.02636788 -38.57630588
OS 52.03099068 -38.57630588
OS 52.03468892 -38.57723044
OS 52.0467082 -38.57723044
OS 52.05687836 -38.57538132
OS 52.06889764 -38.5735322
OS 52.08276604 -38.57075852
OS 52.09848356 -38.56613572
OS 52.11327652 -38.5596638
OS 52.12899404 -38.55134276
OS 52.1299186 -38.55134276
OS 52.13084316 -38.5504182
OS 52.13546596 -38.54671996
OS 52.14193788 -38.54024804
OS 52.14933436 -38.531927
OS 52.15673084 -38.51990772
OS 52.16320276 -38.50603932
OS 52.16782556 -38.4903218
OS 52.16967468 -38.4810762
OS 52.16967468 -38.47090604
OS 52.16967468 -38.46998148
OS 52.16967468 -38.46905692
OS 52.16967468 -38.46350956
OS 52.16782556 -38.45611308
OS 52.16597644 -38.44594292
OS 52.1622782 -38.4348482
OS 52.1576554 -38.42282892
OS 52.15025892 -38.41080964
OS 52.14008876 -38.39971492
OS 52.1391642 -38.39879036
OS 52.1345414 -38.39509212
OS 52.12806948 -38.39046932
OS 52.11974844 -38.38492196
OS 52.10865372 -38.38029916
OS 52.09570988 -38.37567636
OS 52.08091692 -38.37197812
OS 52.06427484 -38.37105356
OS 52.05687836 -38.37105356
OS 52.04855732 -38.37290268
OS 52.0374626 -38.3747518
OS 52.02544332 -38.37845004
OS 52.01342404 -38.38307284
OS 52.0004802 -38.39046932
OS 51.98846092 -38.39971492
OS 51.98753636 -38.40063948
OS 51.98383812 -38.40526228
OS 51.97829076 -38.4117342
OS 51.97181884 -38.4209798
OS 51.96534692 -38.43299908
OS 51.958875 -38.44779204
OS 51.95332764 -38.46535868
OS 51.9496294 -38.485699
OS 51.8710418 -38.4718306
OS 51.8710418 -38.47090604
OS 51.87196636 -38.46813236
OS 51.87289092 -38.46443412
OS 51.87381548 -38.45888676
OS 51.8756646 -38.45241484
OS 51.87843828 -38.44501836
OS 51.88398564 -38.42745172
OS 51.89323124 -38.4071114
OS 51.90432596 -38.38677108
OS 51.91819436 -38.36735532
OS 51.935761 -38.34978868
OS 51.93668556 -38.34886412
OS 51.93853468 -38.34793956
OS 51.94130836 -38.34609044
OS 51.9450066 -38.34331676
OS 51.9496294 -38.33961852
OS 51.95610132 -38.33592028
OS 51.96257324 -38.33222204
OS 51.97089428 -38.32759924
OS 51.98938548 -38.32020276
OS 52.01065036 -38.31280628
OS 52.03561348 -38.30818348
OS 52.04855732 -38.30633436
OS 52.07167132 -38.30633436
OS 52.08184148 -38.30725892
OE
OB 56.14158444 -38.38492196 H
OS 55.95852156 -38.38492196
OS 55.95852156 -38.61328828
OS 56.13048972 -38.61328828
OS 56.13696164 -38.61236372
OS 56.14343356 -38.61236372
OS 56.15083004 -38.61143916
OS 56.16839668 -38.60959004
OS 56.18781244 -38.6058918
OS 56.2072282 -38.60034444
OS 56.22479484 -38.59294796
OS 56.23311588 -38.58832516
OS 56.2395878 -38.5827778
OS 56.24143692 -38.58092868
OS 56.24513516 -38.57723044
OS 56.25068252 -38.56983396
OS 56.25715444 -38.56058836
OS 56.26362636 -38.54856908
OS 56.26917372 -38.53377612
OS 56.27287196 -38.51713404
OS 56.27472108 -38.49771828
OS 56.27472108 -38.49679372
OS 56.27472108 -38.49586916
OS 56.27472108 -38.49124636
OS 56.27379652 -38.48292532
OS 56.2719474 -38.47367972
OS 56.27009828 -38.46350956
OS 56.26640004 -38.45149028
OS 56.26085268 -38.44039556
OS 56.25438076 -38.42930084
OS 56.2534562 -38.42837628
OS 56.25068252 -38.42467804
OS 56.24605972 -38.42005524
OS 56.24051236 -38.41358332
OS 56.23219132 -38.4071114
OS 56.22294572 -38.40156404
OS 56.21277556 -38.39601668
OS 56.20075628 -38.39139388
OS 56.19983172 -38.39139388
OS 56.19613348 -38.39046932
OS 56.19058612 -38.38954476
OS 56.18318964 -38.38769564
OS 56.17209492 -38.38677108
OS 56.15822652 -38.38584652
OS 56.14158444 -38.38492196
OE
OB 49.87491676 -38.43669732 H
OS 49.67336268 -38.72331092
OS 49.87491676 -38.72331092
OS 49.87491676 -38.43669732
OE
OB 54.06132444 -38.37105356 H
OS 54.05392796 -38.37105356
OS 54.04560692 -38.37290268
OS 54.0345122 -38.3747518
OS 54.02249292 -38.37845004
OS 54.00954908 -38.38307284
OS 53.9975298 -38.39046932
OS 53.98551052 -38.40063948
OS 53.98458596 -38.40156404
OS 53.98088772 -38.40526228
OS 53.97626492 -38.4117342
OS 53.97164212 -38.42005524
OS 53.96609476 -38.4302254
OS 53.96147196 -38.44224468
OS 53.95777372 -38.45518852
OS 53.95684916 -38.46998148
OS 53.95684916 -38.47090604
OS 53.95684916 -38.4718306
OS 53.95777372 -38.47737796
OS 53.95869828 -38.485699
OS 53.9605474 -38.49586916
OS 53.96424564 -38.50788844
OS 53.96886844 -38.51990772
OS 53.97626492 -38.53285156
OS 53.98551052 -38.54394628
OS 53.98643508 -38.54487084
OS 53.99105788 -38.54856908
OS 53.9975298 -38.55319188
OS 54.00585084 -38.55781468
OS 54.01694556 -38.56336204
OS 54.0298894 -38.56798484
OS 54.04468236 -38.57168308
OS 54.06132444 -38.57260764
OS 54.06317356 -38.57260764
OS 54.06872092 -38.57168308
OS 54.07704196 -38.57075852
OS 54.08813668 -38.5689094
OS 54.10015596 -38.56521116
OS 54.11217524 -38.56058836
OS 54.12511908 -38.55319188
OS 54.1362138 -38.54394628
OS 54.13713836 -38.54302172
OS 54.1408366 -38.53839892
OS 54.1454594 -38.53285156
OS 54.15100676 -38.52453052
OS 54.15655412 -38.51436036
OS 54.16117692 -38.50234108
OS 54.16487516 -38.48847268
OS 54.16579972 -38.47367972
OS 54.16579972 -38.47275516
OS 54.16579972 -38.4718306
OS 54.16579972 -38.46628324
OS 54.1639506 -38.4579622
OS 54.16210148 -38.44779204
OS 54.15840324 -38.43669732
OS 54.15285588 -38.42467804
OS 54.1454594 -38.41265876
OS 54.13528924 -38.40063948
OS 54.13436468 -38.39971492
OS 54.12974188 -38.39601668
OS 54.12326996 -38.39139388
OS 54.11494892 -38.38584652
OS 54.1038542 -38.38029916
OS 54.09183492 -38.37567636
OS 54.07704196 -38.37197812
OS 54.06132444 -38.37105356
OE
OB 54.05855076 -38.63640228 H
OS 54.0530034 -38.63640228
OS 54.04930516 -38.63732684
OS 54.039135 -38.6382514
OS 54.02619116 -38.64102508
OS 54.0113982 -38.64564788
OS 53.99660524 -38.6521198
OS 53.98088772 -38.6613654
OS 53.96701932 -38.67338468
OS 53.9651702 -38.6752338
OS 53.96147196 -38.6798566
OS 53.9559246 -38.68817764
OS 53.94945268 -38.6983478
OS 53.9420562 -38.7122162
OS 53.93650884 -38.72793372
OS 53.9328106 -38.74550036
OS 53.93096148 -38.76491612
OS 53.93096148 -38.76676524
OS 53.93096148 -38.77046348
OS 53.93188604 -38.7769354
OS 53.9328106 -38.78525644
OS 53.93465972 -38.7954266
OS 53.9374334 -38.80652132
OS 53.94113164 -38.81761604
OS 53.94575444 -38.82963532
OS 53.946679 -38.83055988
OS 53.94852812 -38.83518268
OS 53.95222636 -38.84073004
OS 53.95777372 -38.84720196
OS 53.96424564 -38.855523
OS 53.97256668 -38.86384404
OS 53.98181228 -38.87124052
OS 53.992907 -38.878637
OS 53.99475612 -38.87956156
OS 53.99845436 -38.88141068
OS 54.00492628 -38.88418436
OS 54.01324732 -38.88695804
OS 54.02341748 -38.88973172
OS 54.03543676 -38.8925054
OS 54.0483806 -38.89435452
OS 54.06132444 -38.89527908
OS 54.0668718 -38.89527908
OS 54.07057004 -38.89435452
OS 54.08166476 -38.89342996
OS 54.0946086 -38.89065628
OS 54.10940156 -38.88603348
OS 54.12511908 -38.88048612
OS 54.13991204 -38.87124052
OS 54.154705 -38.85922124
OS 54.15655412 -38.85737212
OS 54.16025236 -38.85274932
OS 54.16672428 -38.84442828
OS 54.1731962 -38.83425812
OS 54.17966812 -38.82131428
OS 54.18614004 -38.80559676
OS 54.18983828 -38.78710556
OS 54.1916874 -38.7676898
OS 54.1916874 -38.76676524
OS 54.1916874 -38.76491612
OS 54.1916874 -38.76214244
OS 54.19076284 -38.7584442
OS 54.18983828 -38.74827404
OS 54.1870646 -38.73440564
OS 54.1824418 -38.72053724
OS 54.17596988 -38.70481972
OS 54.16672428 -38.6891022
OS 54.15378044 -38.67430924
OS 54.15193132 -38.67246012
OS 54.14730852 -38.66876188
OS 54.13898748 -38.66228996
OS 54.12789276 -38.65489348
OS 54.11402436 -38.64842156
OS 54.09738228 -38.64194964
OS 54.07889108 -38.6382514
OS 54.05855076 -38.63640228
OE
OB 54.80559524 -38.37105356 H
OS 54.80004788 -38.37105356
OS 54.79634964 -38.37197812
OS 54.78617948 -38.37382724
OS 54.7741602 -38.37660092
OS 54.7602918 -38.38214828
OS 54.74549884 -38.39046932
OS 54.73810236 -38.39601668
OS 54.73070588 -38.40156404
OS 54.72423396 -38.40896052
OS 54.71776204 -38.41728156
OS 54.71776204 -38.41820612
OS 54.71591292 -38.42005524
OS 54.7140638 -38.42375348
OS 54.71129012 -38.42837628
OS 54.70851644 -38.43577276
OS 54.7048182 -38.4440938
OS 54.70204452 -38.45426396
OS 54.69834628 -38.46628324
OS 54.69464804 -38.48015164
OS 54.6909498 -38.49586916
OS 54.68725156 -38.5134358
OS 54.68447788 -38.53285156
OS 54.6817042 -38.555041
OS 54.67985508 -38.57907956
OS 54.67893052 -38.60496724
OS 54.67800596 -38.6336286
OS 54.67800596 -38.63547772
OS 54.67800596 -38.64010052
OS 54.67800596 -38.64842156
OS 54.67893052 -38.65951628
OS 54.67893052 -38.67153556
OS 54.67985508 -38.68632852
OS 54.68077964 -38.70204604
OS 54.68262876 -38.71868812
OS 54.68725156 -38.75474596
OS 54.69002524 -38.7723126
OS 54.69372348 -38.78895468
OS 54.69742172 -38.8046722
OS 54.70296908 -38.81946516
OS 54.70851644 -38.832409
OS 54.71498836 -38.84350372
OS 54.71498836 -38.84442828
OS 54.71683748 -38.84535284
OS 54.72146028 -38.85182476
OS 54.72978132 -38.8601458
OS 54.73995148 -38.8693914
OS 54.75381988 -38.878637
OS 54.7695374 -38.88695804
OS 54.78710404 -38.89342996
OS 54.79634964 -38.89435452
OS 54.8065198 -38.89527908
OS 54.81206716 -38.89527908
OS 54.8157654 -38.89435452
OS 54.825011 -38.8925054
OS 54.83795484 -38.88880716
OS 54.85182324 -38.88233524
OS 54.86754076 -38.87308964
OS 54.87493724 -38.86754228
OS 54.88233372 -38.8601458
OS 54.8897302 -38.85274932
OS 54.89712668 -38.84350372
OS 54.89712668 -38.84257916
OS 54.8989758 -38.84073004
OS 54.90082492 -38.83795636
OS 54.90267404 -38.83333356
OS 54.90637228 -38.82686164
OS 54.90914596 -38.8185406
OS 54.9128442 -38.809295
OS 54.91654244 -38.79820028
OS 54.91931612 -38.78433188
OS 54.92301436 -38.76953892
OS 54.9267126 -38.75197228
OS 54.92948628 -38.73348108
OS 54.9313354 -38.71129164
OS 54.93318452 -38.68817764
OS 54.93503364 -38.66228996
OS 54.93503364 -38.6336286
OS 54.93503364 -38.63270404
OS 54.93503364 -38.63177948
OS 54.93503364 -38.62715668
OS 54.93503364 -38.61883564
OS 54.93410908 -38.60774092
OS 54.93410908 -38.59572164
OS 54.93318452 -38.58092868
OS 54.93225996 -38.56521116
OS 54.93041084 -38.54764452
OS 54.92578804 -38.51251124
OS 54.92301436 -38.4949446
OS 54.91931612 -38.47830252
OS 54.91561788 -38.462585
OS 54.91007052 -38.44779204
OS 54.90452316 -38.4348482
OS 54.89805124 -38.42375348
OS 54.89805124 -38.42282892
OS 54.89620212 -38.42190436
OS 54.894353 -38.41913068
OS 54.89157932 -38.41543244
OS 54.88325828 -38.4071114
OS 54.87308812 -38.39694124
OS 54.85921972 -38.38769564
OS 54.8435022 -38.3793746
OS 54.83518116 -38.37567636
OS 54.82593556 -38.37290268
OS 54.8157654 -38.37197812
OS 54.80559524 -38.37105356
OE
OB 51.07499564 -38.37105356 H
OS 51.06944828 -38.37105356
OS 51.06575004 -38.37197812
OS 51.05557988 -38.37382724
OS 51.0435606 -38.37660092
OS 51.0296922 -38.38214828
OS 51.01489924 -38.39046932
OS 51.00750276 -38.39601668
OS 51.00010628 -38.40156404
OS 50.99363436 -38.40896052
OS 50.98716244 -38.41728156
OS 50.98716244 -38.41820612
OS 50.98531332 -38.42005524
OS 50.9834642 -38.42375348
OS 50.98069052 -38.42837628
OS 50.97791684 -38.43577276
OS 50.9742186 -38.4440938
OS 50.97144492 -38.45426396
OS 50.96774668 -38.46628324
OS 50.96404844 -38.48015164
OS 50.9603502 -38.49586916
OS 50.95665196 -38.5134358
OS 50.95387828 -38.53285156
OS 50.9511046 -38.555041
OS 50.94925548 -38.57907956
OS 50.94833092 -38.60496724
OS 50.94740636 -38.6336286
OS 50.94740636 -38.63547772
OS 50.94740636 -38.64010052
OS 50.94740636 -38.64842156
OS 50.94833092 -38.65951628
OS 50.94833092 -38.67153556
OS 50.94925548 -38.68632852
OS 50.95018004 -38.70204604
OS 50.95202916 -38.71868812
OS 50.95665196 -38.75474596
OS 50.95942564 -38.7723126
OS 50.96312388 -38.78895468
OS 50.96682212 -38.8046722
OS 50.97236948 -38.81946516
OS 50.97791684 -38.832409
OS 50.98438876 -38.84350372
OS 50.98438876 -38.84442828
OS 50.98623788 -38.84535284
OS 50.99086068 -38.85182476
OS 50.99918172 -38.8601458
OS 51.00935188 -38.8693914
OS 51.02322028 -38.878637
OS 51.0389378 -38.88695804
OS 51.05650444 -38.89342996
OS 51.06575004 -38.89435452
OS 51.0759202 -38.89527908
OS 51.08146756 -38.89527908
OS 51.0851658 -38.89435452
OS 51.0944114 -38.8925054
OS 51.10735524 -38.88880716
OS 51.12122364 -38.88233524
OS 51.13694116 -38.87308964
OS 51.14433764 -38.86754228
OS 51.15173412 -38.8601458
OS 51.1591306 -38.85274932
OS 51.16652708 -38.84350372
OS 51.16652708 -38.84257916
OS 51.1683762 -38.84073004
OS 51.17022532 -38.83795636
OS 51.17207444 -38.83333356
OS 51.17577268 -38.82686164
OS 51.17854636 -38.8185406
OS 51.1822446 -38.809295
OS 51.18594284 -38.79820028
OS 51.18871652 -38.78433188
OS 51.19241476 -38.76953892
OS 51.196113 -38.75197228
OS 51.19888668 -38.73348108
OS 51.2007358 -38.71129164
OS 51.20258492 -38.68817764
OS 51.20443404 -38.66228996
OS 51.20443404 -38.6336286
OS 51.20443404 -38.63270404
OS 51.20443404 -38.63177948
OS 51.20443404 -38.62715668
OS 51.20443404 -38.61883564
OS 51.20350948 -38.60774092
OS 51.20350948 -38.59572164
OS 51.20258492 -38.58092868
OS 51.20166036 -38.56521116
OS 51.19981124 -38.54764452
OS 51.19518844 -38.51251124
OS 51.19241476 -38.4949446
OS 51.18871652 -38.47830252
OS 51.18501828 -38.462585
OS 51.17947092 -38.44779204
OS 51.17392356 -38.4348482
OS 51.16745164 -38.42375348
OS 51.16745164 -38.42282892
OS 51.16560252 -38.42190436
OS 51.1637534 -38.41913068
OS 51.16097972 -38.41543244
OS 51.15265868 -38.4071114
OS 51.14248852 -38.39694124
OS 51.12862012 -38.38769564
OS 51.1129026 -38.3793746
OS 51.10458156 -38.37567636
OS 51.09533596 -38.37290268
OS 51.0851658 -38.37197812
OS 51.07499564 -38.37105356
OE
SE

### steps/pcb/layers/top_paste/features
UNITS=MM
#Layer_Color=8421504
#
#Feature symbol names
#
$0 r99.9998

#
#Feature attribute names
#
@0 .nomenclature
@1 .string
@2 .string_angle
@3 .geometry
@4 .pad_usage

#
#Feature attribute text strings
#

#
#Layer features
#
L -9.5600012 -24.45999934 40.4400004 -24.45999934 0 P 0
L -9.5600012 -35.9599992 -9.5600012 -24.45999934 0 P 0
L -9.5600012 -35.9599992 28.439999 -35.9599992 0 P 0
L -9.5600012 -39.45999982 -9.5600012 -35.9599992 0 P 0
L -9.5600012 -39.45999982 28.439999 -39.45999982 0 P 0
L -9.5600012 -42.96000044 -9.5600012 -39.45999982 0 P 0
L -9.5600012 -42.96000044 28.439999 -42.96000044 0 P 0
L -10.0600002 -23.96000034 62.93999858 -23.96000034 0 P 0
L -10.0600002 -43.45999944 -10.0600002 -23.96000034 0 P 0
L -10.0600002 -43.45999944 62.93999858 -43.45999944 0 P 0
L 28.439999 -35.96000174 45.44000056 -35.9599992 0 P 0
L 28.439999 -39.45999982 28.439999 -35.9599992 0 P 0
L 28.439999 -39.46000236 45.44000056 -39.45999982 0 P 0
L 28.439999 -42.96000044 28.439999 -39.45999982 0 P 0
L 28.439999 -42.96000298 45.44000056 -42.96000044 0 P 0
L 40.4400004 -24.45999934 62.43999958 -24.45999934 0 P 0
L 40.4400004 -35.9599992 40.4400004 -24.45999934 0 P 0
L 45.44000056 -35.9599992 62.43999958 -35.9599992 0 P 0
L 45.44000056 -39.45999982 62.43999958 -39.45999982 0 P 0
L 45.44000056 -42.96000044 45.44000056 -35.9599992 0 P 0
L 45.44000056 -42.96000044 62.43999958 -42.96000044 0 P 0
L 62.43999958 -35.9599992 62.43999958 -24.45999934 0 P 0
L 62.43999958 -42.96000044 62.43999958 -35.9599992 0 P 0
L 62.93999858 -43.45999944 62.93999858 -23.96000034 0 P 0
S P 0
OB -2.96272458 -38.48662356 I
OS -2.94885618 -38.48754812
OS -2.93406322 -38.48939724
OS -2.9183457 -38.49309548
OS -2.90170362 -38.49679372
OS -2.8859861 -38.50234108
OS -2.88506154 -38.50234108
OS -2.88413698 -38.50326564
OS -2.87951418 -38.50511476
OS -2.8721177 -38.508813
OS -2.8628721 -38.5134358
OS -2.85270194 -38.51990772
OS -2.84253178 -38.5273042
OS -2.83328618 -38.53562524
OS -2.82496514 -38.54487084
OS -2.82404058 -38.5457954
OS -2.82219146 -38.54949364
OS -2.81849322 -38.55596556
OS -2.81387042 -38.56336204
OS -2.80924762 -38.57445676
OS -2.80462482 -38.58647604
OS -2.80092658 -38.60034444
OS -2.79722834 -38.61606196
OS -2.87396682 -38.62623212
OS -2.87396682 -38.624383
OS -2.87489138 -38.62068476
OS -2.8767405 -38.61421284
OS -2.87951418 -38.6058918
OS -2.88413698 -38.59757076
OS -2.88968434 -38.58832516
OS -2.89615626 -38.57907956
OS -2.90540186 -38.57075852
OS -2.90632642 -38.56983396
OS -2.91002466 -38.56798484
OS -2.91557202 -38.5642866
OS -2.92389306 -38.56058836
OS -2.93313866 -38.55689012
OS -2.94515794 -38.55319188
OS -2.9599509 -38.55134276
OS -2.97566842 -38.5504182
OS -2.98491402 -38.5504182
OS -2.99415962 -38.55134276
OS -3.0061789 -38.55226732
OS -3.01819818 -38.555041
OS -3.03114202 -38.55781468
OS -3.0431613 -38.56243748
OS -3.05333146 -38.5689094
OS -3.05425602 -38.56983396
OS -3.0570297 -38.57168308
OS -3.06072794 -38.57538132
OS -3.06442618 -38.58092868
OS -3.06904898 -38.58647604
OS -3.07274722 -38.59387252
OS -3.0755209 -38.60219356
OS -3.07644546 -38.6105146
OS -3.07644546 -38.61143916
OS -3.07644546 -38.61328828
OS -3.0755209 -38.61606196
OS -3.0755209 -38.6197602
OS -3.07274722 -38.6290058
OS -3.06719986 -38.6382514
OS -3.0662753 -38.63917596
OS -3.06535074 -38.64010052
OS -3.06350162 -38.6428742
OS -3.05980338 -38.64564788
OS -3.05610514 -38.64842156
OS -3.05055778 -38.6521198
OS -3.04408586 -38.65489348
OS -3.03668938 -38.65859172
OS -3.03576482 -38.65859172
OS -3.0339157 -38.65951628
OS -3.03021746 -38.66044084
OS -3.02374554 -38.66321452
OS -3.01449994 -38.6659882
OS -3.00248066 -38.66876188
OS -2.99508418 -38.67153556
OS -2.98676314 -38.67338468
OS -2.97751754 -38.67615836
OS -2.96734738 -38.67893204
OS -2.96642282 -38.67893204
OS -2.96364914 -38.6798566
OS -2.95902634 -38.68078116
OS -2.95347898 -38.68263028
OS -2.94700706 -38.6844794
OS -2.93868602 -38.68632852
OS -2.92111938 -38.69187588
OS -2.90170362 -38.69742324
OS -2.88228786 -38.70389516
OS -2.86472122 -38.71036708
OS -2.85732474 -38.71314076
OS -2.85085282 -38.71591444
OS -2.8490037 -38.716839
OS -2.84530546 -38.71868812
OS -2.8397581 -38.7214618
OS -2.83143706 -38.7260846
OS -2.82311602 -38.73163196
OS -2.81479498 -38.73902844
OS -2.80647394 -38.74734948
OS -2.79907746 -38.75659508
OS -2.7981529 -38.75751964
OS -2.79630378 -38.76121788
OS -2.79260554 -38.76676524
OS -2.7889073 -38.77508628
OS -2.78613362 -38.78525644
OS -2.78243538 -38.79635116
OS -2.78058626 -38.809295
OS -2.7796617 -38.82408796
OS -2.7796617 -38.82593708
OS -2.7796617 -38.83055988
OS -2.78058626 -38.83795636
OS -2.78243538 -38.84812652
OS -2.78520906 -38.85922124
OS -2.78983186 -38.87124052
OS -2.79537922 -38.88510892
OS -2.8027757 -38.89805276
OS -2.80370026 -38.89990188
OS -2.8073985 -38.90360012
OS -2.8120213 -38.91007204
OS -2.81941778 -38.91746852
OS -2.82958794 -38.92578956
OS -2.84068266 -38.93503516
OS -2.8536265 -38.9433562
OS -2.86934402 -38.95167724
OS -2.87026858 -38.95167724
OS -2.87119314 -38.9526018
OS -2.8767405 -38.95445092
OS -2.8859861 -38.9572246
OS -2.89800538 -38.96092284
OS -2.91279834 -38.96462108
OS -2.92944042 -38.96739476
OS -2.94700706 -38.96924388
OS -2.96734738 -38.97016844
OS -2.97566842 -38.97016844
OS -2.98214034 -38.96924388
OS -2.98953682 -38.96924388
OS -2.99878242 -38.96831932
OS -3.00802802 -38.96739476
OS -3.01819818 -38.96554564
OS -3.04038762 -38.96092284
OS -3.06350162 -38.95445092
OS -3.08569106 -38.94520532
OS -3.09586122 -38.93965796
OS -3.10510682 -38.93318604
OS -3.10603138 -38.93226148
OS -3.10695594 -38.93133692
OS -3.1125033 -38.92578956
OS -3.12082434 -38.91746852
OS -3.13006994 -38.90452468
OS -3.1402401 -38.88880716
OS -3.15041026 -38.87031596
OS -3.1587313 -38.84720196
OS -3.16520322 -38.82131428
OS -3.08754018 -38.809295
OS -3.08754018 -38.81021956
OS -3.08754018 -38.81114412
OS -3.08569106 -38.81669148
OS -3.08384194 -38.82593708
OS -3.0801437 -38.83610724
OS -3.0755209 -38.84720196
OS -3.06997354 -38.85922124
OS -3.0616525 -38.87124052
OS -3.05148234 -38.88141068
OS -3.04963322 -38.88233524
OS -3.04593498 -38.88510892
OS -3.0385385 -38.88880716
OS -3.0292929 -38.89342996
OS -3.01727362 -38.89805276
OS -3.00340522 -38.901751
OS -2.98676314 -38.90452468
OS -2.96734738 -38.90544924
OS -2.95810178 -38.90544924
OS -2.94885618 -38.90452468
OS -2.9368369 -38.90267556
OS -2.92389306 -38.89990188
OS -2.91002466 -38.89620364
OS -2.89800538 -38.89158084
OS -2.88691066 -38.88418436
OS -2.8859861 -38.8832598
OS -2.88228786 -38.88048612
OS -2.87858962 -38.87586332
OS -2.87304226 -38.8693914
OS -2.86841946 -38.86199492
OS -2.86379666 -38.85274932
OS -2.86102298 -38.84350372
OS -2.86009842 -38.832409
OS -2.86009842 -38.83148444
OS -2.86009842 -38.8277862
OS -2.86102298 -38.8231634
OS -2.8628721 -38.81669148
OS -2.86564578 -38.81021956
OS -2.87026858 -38.80374764
OS -2.87581594 -38.79635116
OS -2.88413698 -38.7908038
OS -2.88506154 -38.78987924
OS -2.88783522 -38.78895468
OS -2.89245802 -38.786181
OS -2.8998545 -38.78340732
OS -2.91094922 -38.77970908
OS -2.91742114 -38.7769354
OS -2.92481762 -38.77508628
OS -2.93313866 -38.7723126
OS -2.94238426 -38.76953892
OS -2.95255442 -38.76676524
OS -2.9645737 -38.76399156
OS -2.96549826 -38.76399156
OS -2.96827194 -38.763067
OS -2.97289474 -38.76214244
OS -2.9784421 -38.76029332
OS -2.98583858 -38.7584442
OS -2.99415962 -38.75567052
OS -3.01172626 -38.75104772
OS -3.03206658 -38.7445758
OS -3.05148234 -38.73902844
OS -3.06997354 -38.73255652
OS -3.07829458 -38.72885828
OS -3.0847665 -38.7260846
OS -3.08661562 -38.72516004
OS -3.09031386 -38.72331092
OS -3.09586122 -38.71961268
OS -3.1032577 -38.71498988
OS -3.11157874 -38.70851796
OS -3.11989978 -38.70112148
OS -3.12822082 -38.69280044
OS -3.1356173 -38.68263028
OS -3.13654186 -38.68170572
OS -3.13839098 -38.67800748
OS -3.14116466 -38.67153556
OS -3.14393834 -38.66413908
OS -3.14671202 -38.65489348
OS -3.1494857 -38.64379876
OS -3.15133482 -38.63270404
OS -3.15225938 -38.6197602
OS -3.15225938 -38.61791108
OS -3.15225938 -38.61421284
OS -3.15133482 -38.60866548
OS -3.15041026 -38.60034444
OS -3.14856114 -38.5920234
OS -3.14671202 -38.58185324
OS -3.14301378 -38.57260764
OS -3.13839098 -38.56243748
OS -3.13746642 -38.56151292
OS -3.1356173 -38.55781468
OS -3.13284362 -38.55319188
OS -3.12822082 -38.54671996
OS -3.12267346 -38.54024804
OS -3.11620154 -38.531927
OS -3.10880506 -38.52453052
OS -3.09955946 -38.5180586
OS -3.0986349 -38.51713404
OS -3.09586122 -38.51620948
OS -3.09216298 -38.5134358
OS -3.08661562 -38.51066212
OS -3.07921914 -38.50696388
OS -3.0708981 -38.50326564
OS -3.06072794 -38.4995674
OS -3.04963322 -38.49586916
OS -3.0477841 -38.4949446
OS -3.04408586 -38.49402004
OS -3.03761394 -38.49217092
OS -3.0292929 -38.4903218
OS -3.01912274 -38.48847268
OS -3.00802802 -38.48754812
OS -2.99508418 -38.485699
OS -2.97289474 -38.485699
OS -2.96272458 -38.48662356
OE
OB -3.41483442 -38.48662356 I
OS -3.40096602 -38.48754812
OS -3.3852485 -38.48939724
OS -3.36953098 -38.49217092
OS -3.35381346 -38.49586916
OS -3.3390205 -38.50049196
OS -3.33717138 -38.50141652
OS -3.33254858 -38.50326564
OS -3.32607666 -38.50603932
OS -3.31775562 -38.50973756
OS -3.30851002 -38.51528492
OS -3.29926442 -38.52083228
OS -3.29094338 -38.52822876
OS -3.2835469 -38.53562524
OS -3.28262234 -38.5365498
OS -3.28077322 -38.53932348
OS -3.27799954 -38.54394628
OS -3.2743013 -38.54949364
OS -3.2696785 -38.55781468
OS -3.26598026 -38.56613572
OS -3.26228202 -38.57630588
OS -3.25950834 -38.58832516
OS -3.25950834 -38.58924972
OS -3.25858378 -38.5920234
OS -3.25765922 -38.59757076
OS -3.25673466 -38.60496724
OS -3.25673466 -38.6151374
OS -3.2558101 -38.62715668
OS -3.25488554 -38.6428742
OS -3.25488554 -38.66044084
OS -3.25488554 -38.76584068
OS -3.25488554 -38.76676524
OS -3.25488554 -38.77046348
OS -3.25488554 -38.77601084
OS -3.25488554 -38.78340732
OS -3.25488554 -38.79172836
OS -3.25488554 -38.80189852
OS -3.25396098 -38.82408796
OS -3.25396098 -38.84720196
OS -3.25303642 -38.87031596
OS -3.25211186 -38.88048612
OS -3.25211186 -38.88973172
OS -3.2511873 -38.89805276
OS -3.25026274 -38.90452468
OS -3.25026274 -38.90544924
OS -3.24933818 -38.90914748
OS -3.24841362 -38.91469484
OS -3.24563994 -38.92209132
OS -3.24379082 -38.93041236
OS -3.24009258 -38.93965796
OS -3.23546978 -38.94982812
OS -3.23084698 -38.95999828
OS -3.31313282 -38.95999828
OS -3.31405738 -38.95907372
OS -3.31498194 -38.95537548
OS -3.31683106 -38.95075268
OS -3.31960474 -38.9433562
OS -3.32237842 -38.93503516
OS -3.32422754 -38.924865
OS -3.32607666 -38.91377028
OS -3.32792578 -38.901751
OS -3.32885034 -38.901751
OS -3.3297749 -38.90360012
OS -3.33532226 -38.90822292
OS -3.3436433 -38.91469484
OS -3.35473802 -38.92301588
OS -3.36860642 -38.93133692
OS -3.38247482 -38.94058252
OS -3.39726778 -38.94890356
OS -3.4129853 -38.95537548
OS -3.41483442 -38.95630004
OS -3.42038178 -38.9572246
OS -3.42870282 -38.95999828
OS -3.43887298 -38.96277196
OS -3.45181682 -38.96554564
OS -3.46660978 -38.96739476
OS -3.48325186 -38.96924388
OS -3.49989394 -38.97016844
OS -3.50729042 -38.97016844
OS -3.51283778 -38.96924388
OS -3.5193097 -38.96924388
OS -3.52670618 -38.96831932
OS -3.54334826 -38.96554564
OS -3.56183946 -38.96092284
OS -3.58217978 -38.95445092
OS -3.60067098 -38.94520532
OS -3.61731306 -38.93318604
OS -3.61916218 -38.93133692
OS -3.62378498 -38.92671412
OS -3.6302569 -38.91839308
OS -3.63765338 -38.90729836
OS -3.64504986 -38.89342996
OS -3.65152178 -38.87771244
OS -3.65614458 -38.85829668
OS -3.65706914 -38.84905108
OS -3.6579937 -38.83795636
OS -3.6579937 -38.83610724
OS -3.6579937 -38.832409
OS -3.65706914 -38.82593708
OS -3.65614458 -38.81761604
OS -3.65429546 -38.80744588
OS -3.65152178 -38.79727572
OS -3.64782354 -38.786181
OS -3.64320074 -38.77601084
OS -3.64227618 -38.77508628
OS -3.64042706 -38.77138804
OS -3.63672882 -38.76584068
OS -3.63210602 -38.75936876
OS -3.62655866 -38.75197228
OS -3.61916218 -38.7445758
OS -3.6117657 -38.73717932
OS -3.6025201 -38.7307074
OS -3.60159554 -38.72978284
OS -3.5978973 -38.72793372
OS -3.5932745 -38.72423548
OS -3.58587802 -38.72053724
OS -3.57755698 -38.716839
OS -3.56738682 -38.7122162
OS -3.55721666 -38.70851796
OS -3.54519738 -38.70481972
OS -3.54427282 -38.70481972
OS -3.54057458 -38.70389516
OS -3.53502722 -38.70204604
OS -3.52763074 -38.70112148
OS -3.51838514 -38.69927236
OS -3.50636586 -38.69742324
OS -3.49249746 -38.69464956
OS -3.47585538 -38.69280044
OS -3.47493082 -38.69280044
OS -3.47123258 -38.69187588
OS -3.46660978 -38.69187588
OS -3.46013786 -38.69095132
OS -3.45274138 -38.69002676
OS -3.44349578 -38.68817764
OS -3.43332562 -38.68725308
OS -3.4222309 -38.68540396
OS -3.40004146 -38.68078116
OS -3.3760029 -38.67615836
OS -3.35473802 -38.670611
OS -3.34456786 -38.66783732
OS -3.33532226 -38.66506364
OS -3.33532226 -38.66413908
OS -3.33532226 -38.66228996
OS -3.3343977 -38.6567426
OS -3.3343977 -38.65027068
OS -3.3343977 -38.64657244
OS -3.3343977 -38.64472332
OS -3.3343977 -38.64379876
OS -3.3343977 -38.6428742
OS -3.3343977 -38.63732684
OS -3.33532226 -38.62808124
OS -3.33717138 -38.61791108
OS -3.33994506 -38.60681636
OS -3.34456786 -38.59572164
OS -3.35011522 -38.58555148
OS -3.3575117 -38.57723044
OS -3.35843626 -38.57630588
OS -3.36305906 -38.57260764
OS -3.37045554 -38.5689094
OS -3.37970114 -38.56336204
OS -3.39264498 -38.55873924
OS -3.40743794 -38.55411644
OS -3.42592914 -38.55134276
OS -3.44719402 -38.5504182
OS -3.45643962 -38.5504182
OS -3.46568522 -38.55134276
OS -3.47862906 -38.55319188
OS -3.4915729 -38.555041
OS -3.5054413 -38.55873924
OS -3.51838514 -38.56336204
OS -3.52947986 -38.56983396
OS -3.53040442 -38.57075852
OS -3.53410266 -38.5735322
OS -3.53872546 -38.578155
OS -3.54427282 -38.58555148
OS -3.54982018 -38.59479708
OS -3.5562921 -38.60681636
OS -3.56183946 -38.62160932
OS -3.56738682 -38.6382514
OS -3.6441253 -38.62808124
OS -3.6441253 -38.62715668
OS -3.64320074 -38.62623212
OS -3.64320074 -38.62345844
OS -3.64227618 -38.6197602
OS -3.6395025 -38.61143916
OS -3.63580426 -38.59941988
OS -3.63118146 -38.5874006
OS -3.6256341 -38.57445676
OS -3.61823762 -38.56151292
OS -3.60991658 -38.54949364
OS -3.60899202 -38.54856908
OS -3.60529378 -38.54487084
OS -3.59974642 -38.53932348
OS -3.59234994 -38.531927
OS -3.58217978 -38.52453052
OS -3.5701605 -38.51713404
OS -3.5562921 -38.508813
OS -3.54057458 -38.50234108
OS -3.53965002 -38.50234108
OS -3.53872546 -38.50141652
OS -3.53595178 -38.50049196
OS -3.53225354 -38.4995674
OS -3.52300794 -38.49679372
OS -3.5100641 -38.49402004
OS -3.49527114 -38.49124636
OS -3.47677994 -38.48847268
OS -3.45736418 -38.48662356
OS -3.43517474 -38.485699
OS -3.42500458 -38.485699
OS -3.41483442 -38.48662356
OE
OB -3.90854946 -38.48662356 I
OS -3.90207754 -38.48754812
OS -3.88820914 -38.48939724
OS -3.87156706 -38.49309548
OS -3.85400042 -38.49864284
OS -3.83643378 -38.50696388
OS -3.81886714 -38.51713404
OS -3.81794258 -38.51713404
OS -3.81701802 -38.51898316
OS -3.81147066 -38.5226814
OS -3.80314962 -38.53007788
OS -3.79297946 -38.53932348
OS -3.78188474 -38.55134276
OS -3.77079002 -38.56613572
OS -3.7596953 -38.58370236
OS -3.7504497 -38.60311812
OS -3.7504497 -38.60404268
OS -3.74952514 -38.6058918
OS -3.74860058 -38.60866548
OS -3.74675146 -38.61236372
OS -3.74490234 -38.61791108
OS -3.74305322 -38.624383
OS -3.73843042 -38.63917596
OS -3.73380762 -38.65766716
OS -3.73010938 -38.67800748
OS -3.7273357 -38.70112148
OS -3.72641114 -38.72516004
OS -3.72641114 -38.7260846
OS -3.72641114 -38.72793372
OS -3.72641114 -38.73163196
OS -3.72641114 -38.73717932
OS -3.7273357 -38.74365124
OS -3.7273357 -38.75104772
OS -3.72918482 -38.7676898
OS -3.73288306 -38.78803012
OS -3.73750586 -38.809295
OS -3.74397778 -38.83148444
OS -3.75229882 -38.85367388
OS -3.75229882 -38.85459844
OS -3.75322338 -38.85644756
OS -3.7550725 -38.85922124
OS -3.75692162 -38.86291948
OS -3.76339354 -38.87308964
OS -3.77171458 -38.88603348
OS -3.78188474 -38.89990188
OS -3.79482858 -38.91377028
OS -3.80962154 -38.92763868
OS -3.82718818 -38.94058252
OS -3.82811274 -38.94058252
OS -3.8290373 -38.94150708
OS -3.83181098 -38.9433562
OS -3.83550922 -38.94520532
OS -3.84475482 -38.94982812
OS -3.85769866 -38.95537548
OS -3.87341618 -38.96092284
OS -3.89005826 -38.96554564
OS -3.90947402 -38.96924388
OS -3.92888978 -38.97016844
OS -3.9353617 -38.97016844
OS -3.94275818 -38.96924388
OS -3.95200378 -38.96831932
OS -3.9630985 -38.9664702
OS -3.97511778 -38.96369652
OS -3.98713706 -38.95999828
OS -3.99915634 -38.95445092
OS -4.0000809 -38.95352636
OS -4.0047037 -38.95167724
OS -4.01025106 -38.947979
OS -4.01764754 -38.94243164
OS -4.02504402 -38.93688428
OS -4.03428962 -38.9294878
OS -4.04261066 -38.92116676
OS -4.05000714 -38.91192116
OS -4.05000714 -39.1375138
OS -4.12859474 -39.1375138
OS -4.12859474 -38.49586916
OS -4.05740362 -38.49586916
OS -4.05740362 -38.55689012
OS -4.05647906 -38.555041
OS -4.05278082 -38.55134276
OS -4.04815802 -38.54487084
OS -4.04076154 -38.53747436
OS -4.0324405 -38.52822876
OS -4.0231949 -38.51990772
OS -4.01210018 -38.51158668
OS -4.00100546 -38.5041902
OS -3.99915634 -38.50326564
OS -3.9954581 -38.50141652
OS -3.98806162 -38.49864284
OS -3.97881602 -38.4949446
OS -3.9677213 -38.49124636
OS -3.95477746 -38.48847268
OS -3.9399845 -38.48662356
OS -3.92334242 -38.485699
OS -3.91317226 -38.485699
OS -3.90854946 -38.48662356
OE
OB -1.86989466 -38.42745172 I
OS -1.89115954 -38.54671996
OS -1.94016122 -38.54671996
OS -1.95957698 -38.42745172
OS -1.95957698 -38.32020276
OS -1.86989466 -38.32020276
OS -1.86989466 -38.42745172
OE
OB -2.23232218 -38.48662356 I
OS -2.2249257 -38.48754812
OS -2.2156801 -38.48939724
OS -2.20550994 -38.49124636
OS -2.19349066 -38.49402004
OS -2.18239594 -38.49679372
OS -2.1694521 -38.50141652
OS -2.15743282 -38.50603932
OS -2.14448898 -38.51251124
OS -2.13154514 -38.51990772
OS -2.1186013 -38.52822876
OS -2.10658202 -38.53839892
OS -2.0954873 -38.54949364
OS -2.09456274 -38.5504182
OS -2.09271362 -38.55226732
OS -2.08993994 -38.55596556
OS -2.0862417 -38.56151292
OS -2.0816189 -38.56798484
OS -2.0769961 -38.57538132
OS -2.07144874 -38.58462692
OS -2.06590138 -38.59572164
OS -2.06035402 -38.60774092
OS -2.05480666 -38.62068476
OS -2.05018386 -38.63547772
OS -2.04556106 -38.65119524
OS -2.04186282 -38.66876188
OS -2.03908914 -38.68725308
OS -2.03724002 -38.70666884
OS -2.03631546 -38.72793372
OS -2.03631546 -38.72885828
OS -2.03631546 -38.73255652
OS -2.03631546 -38.73902844
OS -2.03724002 -38.74827404
OS -2.38395002 -38.74827404
OS -2.38395002 -38.7491986
OS -2.38395002 -38.75197228
OS -2.38302546 -38.75567052
OS -2.38302546 -38.76121788
OS -2.3821009 -38.7676898
OS -2.38025178 -38.77508628
OS -2.3774781 -38.79172836
OS -2.37193074 -38.81021956
OS -2.36453426 -38.83055988
OS -2.3543641 -38.84905108
OS -2.34142026 -38.86569316
OS -2.3404957 -38.86569316
OS -2.33957114 -38.86754228
OS -2.33402378 -38.87216508
OS -2.32570274 -38.878637
OS -2.31460802 -38.88510892
OS -2.29981506 -38.8925054
OS -2.28317298 -38.89897732
OS -2.26468178 -38.90360012
OS -2.25451162 -38.90452468
OS -2.2434169 -38.90544924
OS -2.23602042 -38.90544924
OS -2.22769938 -38.90452468
OS -2.21752922 -38.90267556
OS -2.2064345 -38.89990188
OS -2.19349066 -38.89620364
OS -2.18147138 -38.89065628
OS -2.1694521 -38.8832598
OS -2.16852754 -38.88233524
OS -2.16390474 -38.878637
OS -2.15835738 -38.87308964
OS -2.15188546 -38.86569316
OS -2.14448898 -38.855523
OS -2.13616794 -38.84257916
OS -2.1278469 -38.8277862
OS -2.12045042 -38.81021956
OS -2.03908914 -38.82038972
OS -2.03908914 -38.82131428
OS -2.0400137 -38.8231634
OS -2.04093826 -38.82686164
OS -2.04278738 -38.832409
OS -2.04556106 -38.83795636
OS -2.04833474 -38.84535284
OS -2.05573122 -38.86107036
OS -2.06497682 -38.878637
OS -2.07792066 -38.8971282
OS -2.09271362 -38.91469484
OS -2.11120482 -38.93133692
OS -2.11212938 -38.93133692
OS -2.1139785 -38.93318604
OS -2.11675218 -38.93503516
OS -2.12045042 -38.93780884
OS -2.12599778 -38.94058252
OS -2.13154514 -38.9433562
OS -2.13894162 -38.94705444
OS -2.14726266 -38.95075268
OS -2.15650826 -38.95445092
OS -2.16575386 -38.95814916
OS -2.18886786 -38.96369652
OS -2.21475554 -38.96831932
OS -2.2434169 -38.97016844
OS -2.25358706 -38.97016844
OS -2.26005898 -38.96924388
OS -2.26838002 -38.96831932
OS -2.27855018 -38.9664702
OS -2.2896449 -38.96462108
OS -2.30166418 -38.96277196
OS -2.32755186 -38.95537548
OS -2.34142026 -38.94982812
OS -2.3543641 -38.94428076
OS -2.3682325 -38.93688428
OS -2.38117634 -38.92856324
OS -2.39319562 -38.91931764
OS -2.4052149 -38.90822292
OS -2.40613946 -38.90729836
OS -2.40798858 -38.90544924
OS -2.41076226 -38.901751
OS -2.4144605 -38.89620364
OS -2.4190833 -38.88973172
OS -2.4237061 -38.88233524
OS -2.42925346 -38.87308964
OS -2.43480082 -38.86291948
OS -2.44034818 -38.8509002
OS -2.44589554 -38.83795636
OS -2.45051834 -38.8231634
OS -2.45514114 -38.80744588
OS -2.45883938 -38.7908038
OS -2.46161306 -38.7723126
OS -2.46346218 -38.75289684
OS -2.46438674 -38.73255652
OS -2.46438674 -38.73163196
OS -2.46438674 -38.72700916
OS -2.46438674 -38.7214618
OS -2.46346218 -38.71314076
OS -2.46253762 -38.7029706
OS -2.46161306 -38.69187588
OS -2.45976394 -38.67893204
OS -2.45699026 -38.6659882
OS -2.44959378 -38.63640228
OS -2.44497098 -38.62160932
OS -2.43942362 -38.6058918
OS -2.43202714 -38.59109884
OS -2.4237061 -38.57723044
OS -2.4144605 -38.56336204
OS -2.40429034 -38.5504182
OS -2.40336578 -38.54949364
OS -2.40151666 -38.54764452
OS -2.39781842 -38.54487084
OS -2.39319562 -38.54024804
OS -2.38764826 -38.53562524
OS -2.38025178 -38.53007788
OS -2.37193074 -38.52360596
OS -2.36176058 -38.5180586
OS -2.35159042 -38.51158668
OS -2.33957114 -38.50603932
OS -2.3266273 -38.50049196
OS -2.3127589 -38.49586916
OS -2.29796594 -38.49124636
OS -2.28224842 -38.48847268
OS -2.26560634 -38.48662356
OS -2.2480397 -38.485699
OS -2.2387941 -38.485699
OS -2.23232218 -38.48662356
OE
OB -2.5947497 -38.49586916 I
OS -2.51523754 -38.49586916
OS -2.51523754 -38.55689012
OS -2.5947497 -38.55689012
OS -2.5947497 -38.82963532
OS -2.5947497 -38.83148444
OS -2.5947497 -38.83518268
OS -2.5947497 -38.84073004
OS -2.59382514 -38.84720196
OS -2.59290058 -38.86199492
OS -2.59197602 -38.86846684
OS -2.59105146 -38.87308964
OS -2.5901269 -38.87493876
OS -2.58735322 -38.878637
OS -2.58365498 -38.8832598
OS -2.57718306 -38.8878826
OS -2.57533394 -38.88880716
OS -2.57071114 -38.89065628
OS -2.5623901 -38.8925054
OS -2.55037082 -38.89342996
OS -2.54112522 -38.89342996
OS -2.53650242 -38.8925054
OS -2.5300305 -38.8925054
OS -2.52263402 -38.89158084
OS -2.51523754 -38.89065628
OS -2.50506738 -38.95999828
OS -2.5069165 -38.95999828
OS -2.51061474 -38.96092284
OS -2.51708666 -38.9618474
OS -2.5254077 -38.96277196
OS -2.5346533 -38.96462108
OS -2.54482346 -38.96554564
OS -2.56516378 -38.9664702
OS -2.57256026 -38.9664702
OS -2.57995674 -38.96554564
OS -2.58920234 -38.96462108
OS -2.60029706 -38.96369652
OS -2.61139178 -38.96092284
OS -2.62156194 -38.95814916
OS -2.6317321 -38.95352636
OS -2.63265666 -38.9526018
OS -2.63543034 -38.95075268
OS -2.63912858 -38.947979
OS -2.64467594 -38.9433562
OS -2.64929874 -38.9387334
OS -2.6548461 -38.93226148
OS -2.66039346 -38.92578956
OS -2.6640917 -38.91746852
OS -2.6640917 -38.91654396
OS -2.66594082 -38.91284572
OS -2.66686538 -38.9063738
OS -2.6687145 -38.8971282
OS -2.67056362 -38.88510892
OS -2.67148818 -38.87771244
OS -2.67148818 -38.8693914
OS -2.67241274 -38.85922124
OS -2.6733373 -38.84905108
OS -2.6733373 -38.83795636
OS -2.6733373 -38.82501252
OS -2.6733373 -38.55689012
OS -2.73158458 -38.55689012
OS -2.73158458 -38.49586916
OS -2.6733373 -38.49586916
OS -2.6733373 -38.38122372
OS -2.5947497 -38.33407116
OS -2.5947497 -38.49586916
OE
OB -4.17852098 -39.1375138 I
OS -4.69904826 -39.1375138
OS -4.69904826 -39.08111564
OS -4.17852098 -39.08111564
OS -4.17852098 -39.1375138
OE
OB -5.41743138 -38.48662356 I
OS -5.40911034 -38.48754812
OS -5.39986474 -38.48939724
OS -5.38969458 -38.49124636
OS -5.3776753 -38.49309548
OS -5.35271218 -38.50141652
OS -5.33976834 -38.50603932
OS -5.3268245 -38.51251124
OS -5.31388066 -38.51898316
OS -5.30093682 -38.52822876
OS -5.28891754 -38.53747436
OS -5.27689826 -38.54856908
OS -5.2759737 -38.54949364
OS -5.27412458 -38.55134276
OS -5.2713509 -38.555041
OS -5.26765266 -38.5596638
OS -5.26302986 -38.56613572
OS -5.2574825 -38.57445676
OS -5.25193514 -38.58370236
OS -5.24638778 -38.59387252
OS -5.24084042 -38.60496724
OS -5.23529306 -38.61883564
OS -5.2297457 -38.63270404
OS -5.2251229 -38.64842156
OS -5.22142466 -38.66506364
OS -5.21865098 -38.68263028
OS -5.21680186 -38.70112148
OS -5.2158773 -38.7214618
OS -5.2158773 -38.72238636
OS -5.2158773 -38.72516004
OS -5.2158773 -38.72978284
OS -5.2158773 -38.73625476
OS -5.21680186 -38.74365124
OS -5.21772642 -38.75289684
OS -5.21772642 -38.76214244
OS -5.21957554 -38.7723126
OS -5.22234922 -38.7954266
OS -5.22789658 -38.8185406
OS -5.2343685 -38.8416546
OS -5.2436141 -38.86291948
OS -5.2436141 -38.86384404
OS -5.24453866 -38.8647686
OS -5.24638778 -38.86754228
OS -5.2482369 -38.87124052
OS -5.25470882 -38.88048612
OS -5.26302986 -38.89158084
OS -5.27412458 -38.90452468
OS -5.28799298 -38.91746852
OS -5.3037105 -38.93041236
OS -5.3222017 -38.94243164
OS -5.32312626 -38.94243164
OS -5.32405082 -38.9433562
OS -5.3268245 -38.94520532
OS -5.3314473 -38.94705444
OS -5.3360701 -38.94890356
OS -5.34161746 -38.95075268
OS -5.35548586 -38.95630004
OS -5.37120338 -38.96092284
OS -5.39061914 -38.96554564
OS -5.41095946 -38.96924388
OS -5.4331489 -38.97016844
OS -5.4423945 -38.97016844
OS -5.44979098 -38.96924388
OS -5.45811202 -38.96831932
OS -5.46735762 -38.9664702
OS -5.47845234 -38.96462108
OS -5.48954706 -38.96277196
OS -5.51451018 -38.95537548
OS -5.52837858 -38.94982812
OS -5.54132242 -38.94428076
OS -5.55426626 -38.93688428
OS -5.5672101 -38.92856324
OS -5.57922938 -38.91931764
OS -5.59124866 -38.90822292
OS -5.59217322 -38.90729836
OS -5.59402234 -38.90544924
OS -5.59679602 -38.901751
OS -5.60049426 -38.89620364
OS -5.60511706 -38.88973172
OS -5.60973986 -38.88233524
OS -5.61528722 -38.87308964
OS -5.62083458 -38.86199492
OS -5.62638194 -38.84997564
OS -5.6319293 -38.83610724
OS -5.6365521 -38.82131428
OS -5.6411749 -38.80559676
OS -5.64487314 -38.78803012
OS -5.64764682 -38.76953892
OS -5.64949594 -38.7491986
OS -5.6504205 -38.72793372
OS -5.6504205 -38.7260846
OS -5.6504205 -38.72238636
OS -5.64949594 -38.71591444
OS -5.64949594 -38.70666884
OS -5.64857138 -38.69649868
OS -5.64672226 -38.68355484
OS -5.64487314 -38.670611
OS -5.6411749 -38.65581804
OS -5.63747666 -38.64102508
OS -5.63285386 -38.62530756
OS -5.6273065 -38.60866548
OS -5.61991002 -38.59294796
OS -5.61251354 -38.578155
OS -5.60234338 -38.56336204
OS -5.59217322 -38.54949364
OS -5.57922938 -38.53747436
OS -5.57830482 -38.5365498
OS -5.5764557 -38.53562524
OS -5.57275746 -38.53285156
OS -5.56813466 -38.52915332
OS -5.5625873 -38.52545508
OS -5.55519082 -38.52083228
OS -5.54779434 -38.51620948
OS -5.53854874 -38.51158668
OS -5.52837858 -38.50696388
OS -5.51728386 -38.50234108
OS -5.49232074 -38.49402004
OS -5.46365938 -38.48754812
OS -5.44886642 -38.48662356
OS -5.4331489 -38.485699
OS -5.4239033 -38.485699
OS -5.41743138 -38.48662356
OE
OB -5.97031826 -38.42745172 I
OS -5.99158314 -38.54671996
OS -6.04058482 -38.54671996
OS -6.06000058 -38.42745172
OS -6.06000058 -38.32020276
OS -5.97031826 -38.32020276
OS -5.97031826 -38.42745172
OE
OB -5.77800978 -38.49586916 I
OS -5.69849762 -38.49586916
OS -5.69849762 -38.55689012
OS -5.77800978 -38.55689012
OS -5.77800978 -38.82963532
OS -5.77800978 -38.83148444
OS -5.77800978 -38.83518268
OS -5.77800978 -38.84073004
OS -5.77708522 -38.84720196
OS -5.77616066 -38.86199492
OS -5.7752361 -38.86846684
OS -5.77431154 -38.87308964
OS -5.77338698 -38.87493876
OS -5.7706133 -38.878637
OS -5.76691506 -38.8832598
OS -5.76044314 -38.8878826
OS -5.75859402 -38.88880716
OS -5.75397122 -38.89065628
OS -5.74565018 -38.8925054
OS -5.7336309 -38.89342996
OS -5.7243853 -38.89342996
OS -5.7197625 -38.8925054
OS -5.71329058 -38.8925054
OS -5.7058941 -38.89158084
OS -5.69849762 -38.89065628
OS -5.68832746 -38.95999828
OS -5.69017658 -38.95999828
OS -5.69387482 -38.96092284
OS -5.70034674 -38.9618474
OS -5.70866778 -38.96277196
OS -5.71791338 -38.96462108
OS -5.72808354 -38.96554564
OS -5.74842386 -38.9664702
OS -5.75582034 -38.9664702
OS -5.76321682 -38.96554564
OS -5.77246242 -38.96462108
OS -5.78355714 -38.96369652
OS -5.79465186 -38.96092284
OS -5.80482202 -38.95814916
OS -5.81499218 -38.95352636
OS -5.81591674 -38.9526018
OS -5.81869042 -38.95075268
OS -5.82238866 -38.947979
OS -5.82793602 -38.9433562
OS -5.83255882 -38.9387334
OS -5.83810618 -38.93226148
OS -5.84365354 -38.92578956
OS -5.84735178 -38.91746852
OS -5.84735178 -38.91654396
OS -5.8492009 -38.91284572
OS -5.85012546 -38.9063738
OS -5.85197458 -38.8971282
OS -5.8538237 -38.88510892
OS -5.85474826 -38.87771244
OS -5.85474826 -38.8693914
OS -5.85567282 -38.85922124
OS -5.85659738 -38.84905108
OS -5.85659738 -38.83795636
OS -5.85659738 -38.82501252
OS -5.85659738 -38.55689012
OS -5.91484466 -38.55689012
OS -5.91484466 -38.49586916
OS -5.85659738 -38.49586916
OS -5.85659738 -38.38122372
OS -5.77800978 -38.33407116
OS -5.77800978 -38.49586916
OE
OB -4.90337602 -38.48662356 I
OS -4.8969041 -38.48754812
OS -4.8830357 -38.48939724
OS -4.86639362 -38.49309548
OS -4.84882698 -38.49864284
OS -4.83126034 -38.50696388
OS -4.8136937 -38.51713404
OS -4.81276914 -38.51713404
OS -4.81184458 -38.51898316
OS -4.80629722 -38.5226814
OS -4.79797618 -38.53007788
OS -4.78780602 -38.53932348
OS -4.7767113 -38.55134276
OS -4.76561658 -38.56613572
OS -4.75452186 -38.58370236
OS -4.74527626 -38.60311812
OS -4.74527626 -38.60404268
OS -4.7443517 -38.6058918
OS -4.74342714 -38.60866548
OS -4.74157802 -38.61236372
OS -4.7397289 -38.61791108
OS -4.73787978 -38.624383
OS -4.73325698 -38.63917596
OS -4.72863418 -38.65766716
OS -4.72493594 -38.67800748
OS -4.72216226 -38.70112148
OS -4.7212377 -38.72516004
OS -4.7212377 -38.7260846
OS -4.7212377 -38.72793372
OS -4.7212377 -38.73163196
OS -4.7212377 -38.73717932
OS -4.72216226 -38.74365124
OS -4.72216226 -38.75104772
OS -4.72401138 -38.7676898
OS -4.72770962 -38.78803012
OS -4.73233242 -38.809295
OS -4.73880434 -38.83148444
OS -4.74712538 -38.85367388
OS -4.74712538 -38.85459844
OS -4.74804994 -38.85644756
OS -4.74989906 -38.85922124
OS -4.75174818 -38.86291948
OS -4.7582201 -38.87308964
OS -4.76654114 -38.88603348
OS -4.7767113 -38.89990188
OS -4.78965514 -38.91377028
OS -4.8044481 -38.92763868
OS -4.82201474 -38.94058252
OS -4.8229393 -38.94058252
OS -4.82386386 -38.94150708
OS -4.82663754 -38.9433562
OS -4.83033578 -38.94520532
OS -4.83958138 -38.94982812
OS -4.85252522 -38.95537548
OS -4.86824274 -38.96092284
OS -4.88488482 -38.96554564
OS -4.90430058 -38.96924388
OS -4.92371634 -38.97016844
OS -4.93018826 -38.97016844
OS -4.93758474 -38.96924388
OS -4.94683034 -38.96831932
OS -4.95792506 -38.9664702
OS -4.96994434 -38.96369652
OS -4.98196362 -38.95999828
OS -4.9939829 -38.95445092
OS -4.99490746 -38.95352636
OS -4.99953026 -38.95167724
OS -5.00507762 -38.947979
OS -5.0124741 -38.94243164
OS -5.01987058 -38.93688428
OS -5.02911618 -38.9294878
OS -5.03743722 -38.92116676
OS -5.0448337 -38.91192116
OS -5.0448337 -39.1375138
OS -5.1234213 -39.1375138
OS -5.1234213 -38.49586916
OS -5.05223018 -38.49586916
OS -5.05223018 -38.55689012
OS -5.05130562 -38.555041
OS -5.04760738 -38.55134276
OS -5.04298458 -38.54487084
OS -5.0355881 -38.53747436
OS -5.02726706 -38.52822876
OS -5.01802146 -38.51990772
OS -5.00692674 -38.51158668
OS -4.99583202 -38.5041902
OS -4.9939829 -38.50326564
OS -4.99028466 -38.50141652
OS -4.98288818 -38.49864284
OS -4.97364258 -38.4949446
OS -4.96254786 -38.49124636
OS -4.94960402 -38.48847268
OS -4.93481106 -38.48662356
OS -4.91816898 -38.485699
OS -4.90799882 -38.485699
OS -4.90337602 -38.48662356
OE
OB -3.9307389 -38.54764452 H
OS -3.9353617 -38.54764452
OS -3.93905994 -38.54856908
OS -3.94830554 -38.5504182
OS -3.96032482 -38.55319188
OS -3.97419322 -38.55873924
OS -3.98898618 -38.56706028
OS -3.99730722 -38.57260764
OS -4.0047037 -38.57907956
OS -4.01210018 -38.58647604
OS -4.01949666 -38.59479708
OS -4.01949666 -38.59572164
OS -4.02134578 -38.5966462
OS -4.0231949 -38.59941988
OS -4.02504402 -38.60311812
OS -4.0278177 -38.60866548
OS -4.03151594 -38.61421284
OS -4.03521418 -38.62160932
OS -4.03798786 -38.6290058
OS -4.0416861 -38.6382514
OS -4.04538434 -38.64842156
OS -4.04815802 -38.65951628
OS -4.05185626 -38.67153556
OS -4.05370538 -38.68540396
OS -4.0555545 -38.69927236
OS -4.05740362 -38.71406532
OS -4.05740362 -38.7307074
OS -4.05740362 -38.73163196
OS -4.05740362 -38.73440564
OS -4.05740362 -38.73902844
OS -4.05647906 -38.74550036
OS -4.05647906 -38.75289684
OS -4.0555545 -38.76121788
OS -4.05278082 -38.78063364
OS -4.04815802 -38.80282308
OS -4.04261066 -38.82408796
OS -4.03336506 -38.84535284
OS -4.0278177 -38.85459844
OS -4.02134578 -38.86291948
OS -4.01949666 -38.8647686
OS -4.01487386 -38.8693914
OS -4.00747738 -38.87678788
OS -3.99730722 -38.88418436
OS -3.98436338 -38.89158084
OS -3.96957042 -38.89897732
OS -3.95292834 -38.90360012
OS -3.94368274 -38.90452468
OS -3.93443714 -38.90544924
OS -3.92888978 -38.90544924
OS -3.92519154 -38.90452468
OS -3.91594594 -38.90267556
OS -3.9030021 -38.89990188
OS -3.8891337 -38.89435452
OS -3.87434074 -38.88695804
OS -3.85954778 -38.87586332
OS -3.8521513 -38.8693914
OS -3.84475482 -38.86199492
OS -3.84475482 -38.86107036
OS -3.8429057 -38.8601458
OS -3.84105658 -38.85737212
OS -3.83920746 -38.85367388
OS -3.83550922 -38.84905108
OS -3.83273554 -38.84257916
OS -3.8290373 -38.83610724
OS -3.82533906 -38.8277862
OS -3.82256538 -38.81946516
OS -3.81886714 -38.80837044
OS -3.8151689 -38.79727572
OS -3.81239522 -38.78525644
OS -3.8105461 -38.77138804
OS -3.80869698 -38.75659508
OS -3.80684786 -38.74087756
OS -3.80684786 -38.72423548
OS -3.80684786 -38.72331092
OS -3.80684786 -38.72053724
OS -3.80684786 -38.71591444
OS -3.80777242 -38.70944252
OS -3.80777242 -38.70204604
OS -3.80869698 -38.693725
OS -3.81147066 -38.67430924
OS -3.81609346 -38.65304436
OS -3.82256538 -38.63177948
OS -3.83181098 -38.6105146
OS -3.83735834 -38.60034444
OS -3.84383026 -38.5920234
OS -3.84383026 -38.59109884
OS -3.84567938 -38.59017428
OS -3.85030218 -38.58462692
OS -3.85769866 -38.578155
OS -3.86786882 -38.56983396
OS -3.88081266 -38.56151292
OS -3.89560562 -38.55411644
OS -3.9122477 -38.54949364
OS -3.9214933 -38.54856908
OS -3.9307389 -38.54764452
OE
OB -4.92556546 -38.54764452 H
OS -4.93018826 -38.54764452
OS -4.9338865 -38.54856908
OS -4.9431321 -38.5504182
OS -4.95515138 -38.55319188
OS -4.96901978 -38.55873924
OS -4.98381274 -38.56706028
OS -4.99213378 -38.57260764
OS -4.99953026 -38.57907956
OS -5.00692674 -38.58647604
OS -5.01432322 -38.59479708
OS -5.01432322 -38.59572164
OS -5.01617234 -38.5966462
OS -5.01802146 -38.59941988
OS -5.01987058 -38.60311812
OS -5.02264426 -38.60866548
OS -5.0263425 -38.61421284
OS -5.03004074 -38.62160932
OS -5.03281442 -38.6290058
OS -5.03651266 -38.6382514
OS -5.0402109 -38.64842156
OS -5.04298458 -38.65951628
OS -5.04668282 -38.67153556
OS -5.04853194 -38.68540396
OS -5.05038106 -38.69927236
OS -5.05223018 -38.71406532
OS -5.05223018 -38.7307074
OS -5.05223018 -38.73163196
OS -5.05223018 -38.73440564
OS -5.05223018 -38.73902844
OS -5.05130562 -38.74550036
OS -5.05130562 -38.75289684
OS -5.05038106 -38.76121788
OS -5.04760738 -38.78063364
OS -5.04298458 -38.80282308
OS -5.03743722 -38.82408796
OS -5.02819162 -38.84535284
OS -5.02264426 -38.85459844
OS -5.01617234 -38.86291948
OS -5.01432322 -38.8647686
OS -5.00970042 -38.8693914
OS -5.00230394 -38.87678788
OS -4.99213378 -38.88418436
OS -4.97918994 -38.89158084
OS -4.96439698 -38.89897732
OS -4.9477549 -38.90360012
OS -4.9385093 -38.90452468
OS -4.9292637 -38.90544924
OS -4.92371634 -38.90544924
OS -4.9200181 -38.90452468
OS -4.9107725 -38.90267556
OS -4.89782866 -38.89990188
OS -4.88396026 -38.89435452
OS -4.8691673 -38.88695804
OS -4.85437434 -38.87586332
OS -4.84697786 -38.8693914
OS -4.83958138 -38.86199492
OS -4.83958138 -38.86107036
OS -4.83773226 -38.8601458
OS -4.83588314 -38.85737212
OS -4.83403402 -38.85367388
OS -4.83033578 -38.84905108
OS -4.8275621 -38.84257916
OS -4.82386386 -38.83610724
OS -4.82016562 -38.8277862
OS -4.81739194 -38.81946516
OS -4.8136937 -38.80837044
OS -4.80999546 -38.79727572
OS -4.80722178 -38.78525644
OS -4.80537266 -38.77138804
OS -4.80352354 -38.75659508
OS -4.80167442 -38.74087756
OS -4.80167442 -38.72423548
OS -4.80167442 -38.72331092
OS -4.80167442 -38.72053724
OS -4.80167442 -38.71591444
OS -4.80259898 -38.70944252
OS -4.80259898 -38.70204604
OS -4.80352354 -38.693725
OS -4.80629722 -38.67430924
OS -4.81092002 -38.65304436
OS -4.81739194 -38.63177948
OS -4.82663754 -38.6105146
OS -4.8321849 -38.60034444
OS -4.83865682 -38.5920234
OS -4.83865682 -38.59109884
OS -4.84050594 -38.59017428
OS -4.84512874 -38.58462692
OS -4.85252522 -38.578155
OS -4.86269538 -38.56983396
OS -4.87563922 -38.56151292
OS -4.89043218 -38.55411644
OS -4.90707426 -38.54949364
OS -4.91631986 -38.54856908
OS -4.92556546 -38.54764452
OE
OB -2.24711514 -38.5504182 H
OS -2.2526625 -38.5504182
OS -2.25636074 -38.55134276
OS -2.2665309 -38.55226732
OS -2.27855018 -38.555041
OS -2.29334314 -38.5596638
OS -2.30906066 -38.56613572
OS -2.32385362 -38.57538132
OS -2.33864658 -38.5874006
OS -2.3404957 -38.58924972
OS -2.34419394 -38.59387252
OS -2.35066586 -38.60219356
OS -2.35713778 -38.61328828
OS -2.36453426 -38.62623212
OS -2.37100618 -38.6428742
OS -2.37655354 -38.66228996
OS -2.37932722 -38.68355484
OS -2.11952586 -38.68355484
OS -2.11952586 -38.68263028
OS -2.11952586 -38.68078116
OS -2.12045042 -38.67800748
OS -2.12045042 -38.67430924
OS -2.12229954 -38.66321452
OS -2.12507322 -38.65119524
OS -2.12969602 -38.63640228
OS -2.13431882 -38.62253388
OS -2.1417153 -38.60866548
OS -2.15003634 -38.5966462
OS -2.15003634 -38.59572164
OS -2.15188546 -38.59479708
OS -2.15650826 -38.58924972
OS -2.1648293 -38.58185324
OS -2.17592402 -38.5735322
OS -2.18979242 -38.56521116
OS -2.2064345 -38.55781468
OS -2.22585026 -38.55226732
OS -2.23602042 -38.55134276
OS -2.24711514 -38.5504182
OE
OB -3.3343977 -38.72700916 H
OS -3.33532226 -38.72700916
OS -3.33624682 -38.72793372
OS -3.3390205 -38.72885828
OS -3.34271874 -38.72978284
OS -3.34734154 -38.73163196
OS -3.3528889 -38.73348108
OS -3.35936082 -38.7353302
OS -3.3667573 -38.73717932
OS -3.37507834 -38.739953
OS -3.3852485 -38.74180212
OS -3.39541866 -38.7445758
OS -3.40743794 -38.74734948
OS -3.42038178 -38.75012316
OS -3.43332562 -38.75289684
OS -3.44811858 -38.75474596
OS -3.4638361 -38.75751964
OS -3.46568522 -38.75751964
OS -3.47123258 -38.7584442
OS -3.48047818 -38.76029332
OS -3.49064834 -38.76214244
OS -3.50174306 -38.76399156
OS -3.51283778 -38.76676524
OS -3.52300794 -38.76953892
OS -3.53225354 -38.77323716
OS -3.5331781 -38.77323716
OS -3.53595178 -38.77508628
OS -3.53965002 -38.7769354
OS -3.54334826 -38.77970908
OS -3.55444298 -38.78710556
OS -3.56368858 -38.79820028
OS -3.56368858 -38.79912484
OS -3.5655377 -38.80097396
OS -3.56646226 -38.8046722
OS -3.56831138 -38.809295
OS -3.5701605 -38.81484236
OS -3.57200962 -38.82038972
OS -3.57293418 -38.8277862
OS -3.57385874 -38.83518268
OS -3.57385874 -38.83610724
OS -3.57385874 -38.84073004
OS -3.57293418 -38.8462774
OS -3.57108506 -38.85367388
OS -3.56831138 -38.86199492
OS -3.56368858 -38.87031596
OS -3.55814122 -38.87956156
OS -3.55074474 -38.8878826
OS -3.54982018 -38.88880716
OS -3.54612194 -38.89065628
OS -3.54057458 -38.89435452
OS -3.5331781 -38.89805276
OS -3.52300794 -38.901751
OS -3.51098866 -38.90544924
OS -3.49712026 -38.90729836
OS -3.48047818 -38.90822292
OS -3.4730817 -38.90822292
OS -3.4638361 -38.90729836
OS -3.45366594 -38.90544924
OS -3.4407221 -38.90360012
OS -3.42777826 -38.89990188
OS -3.41390986 -38.89527908
OS -3.40004146 -38.88880716
OS -3.39819234 -38.8878826
OS -3.3944941 -38.88510892
OS -3.38802218 -38.88048612
OS -3.3806257 -38.8740142
OS -3.37230466 -38.86661772
OS -3.36305906 -38.85737212
OS -3.35566258 -38.8462774
OS -3.3482661 -38.83425812
OS -3.34734154 -38.83333356
OS -3.34641698 -38.82963532
OS -3.34456786 -38.8231634
OS -3.34179418 -38.81484236
OS -3.3390205 -38.80374764
OS -3.33717138 -38.7908038
OS -3.33624682 -38.77508628
OS -3.33532226 -38.75659508
OS -3.3343977 -38.72700916
OE
OB -5.4331489 -38.5504182 H
OS -5.43869626 -38.5504182
OS -5.44331906 -38.55134276
OS -5.45348922 -38.55226732
OS -5.46735762 -38.55596556
OS -5.48307514 -38.56151292
OS -5.49971722 -38.5689094
OS -5.51543474 -38.58000412
OS -5.52375578 -38.5874006
OS -5.53115226 -38.59479708
OS -5.53115226 -38.59572164
OS -5.53300138 -38.5966462
OS -5.5348505 -38.59941988
OS -5.53762418 -38.60311812
OS -5.54039786 -38.60774092
OS -5.54317154 -38.61328828
OS -5.54686978 -38.62068476
OS -5.55056802 -38.62808124
OS -5.55426626 -38.63732684
OS -5.5579645 -38.64657244
OS -5.56073818 -38.65766716
OS -5.56351186 -38.66968644
OS -5.56628554 -38.68263028
OS -5.56813466 -38.69649868
OS -5.56905922 -38.7122162
OS -5.56998378 -38.72793372
OS -5.56998378 -38.72885828
OS -5.56998378 -38.73163196
OS -5.56998378 -38.73625476
OS -5.56905922 -38.74272668
OS -5.56905922 -38.75012316
OS -5.56813466 -38.7584442
OS -5.56536098 -38.77785996
OS -5.56073818 -38.8000494
OS -5.5533417 -38.82223884
OS -5.5440961 -38.84350372
OS -5.53762418 -38.85274932
OS -5.53115226 -38.86199492
OS -5.5302277 -38.86199492
OS -5.52930314 -38.86384404
OS -5.52375578 -38.86846684
OS -5.51543474 -38.87586332
OS -5.50434002 -38.8832598
OS -5.49047162 -38.89158084
OS -5.47382954 -38.89897732
OS -5.45441378 -38.90360012
OS -5.44424362 -38.90452468
OS -5.4331489 -38.90544924
OS -5.42760154 -38.90544924
OS -5.42297874 -38.90452468
OS -5.41280858 -38.90267556
OS -5.39894018 -38.89990188
OS -5.38414722 -38.89435452
OS -5.36750514 -38.88695804
OS -5.35178762 -38.87586332
OS -5.34346658 -38.86846684
OS -5.3360701 -38.86107036
OS -5.33514554 -38.8601458
OS -5.33422098 -38.85922124
OS -5.33237186 -38.85644756
OS -5.32959818 -38.85274932
OS -5.3268245 -38.84812652
OS -5.32312626 -38.84257916
OS -5.31942802 -38.83518268
OS -5.31572978 -38.8277862
OS -5.31203154 -38.8185406
OS -5.30925786 -38.80837044
OS -5.30555962 -38.79727572
OS -5.30278594 -38.78525644
OS -5.30001226 -38.77138804
OS -5.29816314 -38.75751964
OS -5.29631402 -38.74180212
OS -5.29631402 -38.72516004
OS -5.29631402 -38.72423548
OS -5.29631402 -38.7214618
OS -5.29631402 -38.716839
OS -5.29723858 -38.71129164
OS -5.29723858 -38.70389516
OS -5.29816314 -38.69557412
OS -5.30093682 -38.67615836
OS -5.30555962 -38.65581804
OS -5.3129561 -38.6336286
OS -5.32312626 -38.61328828
OS -5.32867362 -38.60311812
OS -5.3360701 -38.59479708
OS -5.3360701 -38.59387252
OS -5.33791922 -38.59294796
OS -5.34346658 -38.5874006
OS -5.35178762 -38.58092868
OS -5.36288234 -38.57260764
OS -5.37675074 -38.5642866
OS -5.39339282 -38.55689012
OS -5.41188402 -38.55226732
OS -5.42205418 -38.55134276
OS -5.4331489 -38.5504182
OE
SE
S P 0
OB -4.66714078 -36.5016923 I
OS -4.65465922 -36.5016923
OS -4.62553558 -36.50307914
OS -4.5950251 -36.50723966
OS -4.56174094 -36.51140018
OS -4.53123046 -36.51833438
OS -4.51597522 -36.5224949
OS -4.50349366 -36.52665542
OS -4.50210682 -36.52665542
OS -4.50071998 -36.52804226
OS -4.49239894 -36.53220278
OS -4.47991738 -36.53775014
OS -4.46466214 -36.54745802
OS -4.44802006 -36.55993958
OS -4.42999114 -36.57658166
OS -4.41334906 -36.59599742
OS -4.39670698 -36.61818686
OS -4.39670698 -36.6195737
OS -4.39532014 -36.62096054
OS -4.38977278 -36.62928158
OS -4.38422542 -36.64314998
OS -4.37590438 -36.6611789
OS -4.36897018 -36.6819815
OS -4.36203598 -36.70694462
OS -4.35787546 -36.73329458
OS -4.35648862 -36.76241822
OS -4.35648862 -36.76380506
OS -4.35648862 -36.76657874
OS -4.35648862 -36.7721261
OS -4.35787546 -36.7790603
OS -4.35787546 -36.78876818
OS -4.3592623 -36.79847606
OS -4.36480966 -36.82205234
OS -4.3731307 -36.84978914
OS -4.38422542 -36.87891278
OS -4.4008675 -36.90803642
OS -4.41196222 -36.92190482
OS -4.42305694 -36.93577322
OS -4.42444378 -36.93716006
OS -4.42583062 -36.9385469
OS -4.42999114 -36.94270742
OS -4.4355385 -36.94686794
OS -4.4424727 -36.9524153
OS -4.45079374 -36.95796266
OS -4.46188846 -36.96489686
OS -4.47298318 -36.9732179
OS -4.48685158 -36.9801521
OS -4.50210682 -36.9870863
OS -4.5187489 -36.99540734
OS -4.53677782 -37.00234154
OS -4.55758042 -37.0078889
OS -4.57838302 -37.0148231
OS -4.6019593 -37.01898362
OS -4.62692242 -37.02314414
OS -4.62414874 -37.02453098
OS -4.61860138 -37.02730466
OS -4.61028034 -37.03285202
OS -4.59918562 -37.03839938
OS -4.5742225 -37.05365462
OS -4.56174094 -37.0633625
OS -4.55064622 -37.07168354
OS -4.54787254 -37.07445722
OS -4.54093834 -37.08139142
OS -4.52984362 -37.09248614
OS -4.51597522 -37.10635454
OS -4.50071998 -37.1257703
OS -4.48269106 -37.1465729
OS -4.46466214 -37.17153602
OS -4.44524638 -37.19927282
OS -4.28021242 -37.45999874
OS -4.43831218 -37.45999874
OS -4.56451462 -37.26029378
OS -4.56451462 -37.25890694
OS -4.5672883 -37.25613326
OS -4.57006198 -37.25197274
OS -4.5742225 -37.24642538
OS -4.58393038 -37.23117014
OS -4.59641194 -37.21175438
OS -4.61166718 -37.19095178
OS -4.62692242 -37.16876234
OS -4.64217766 -37.14795974
OS -4.65604606 -37.12854398
OS -4.6574329 -37.12715714
OS -4.66159342 -37.12160978
OS -4.66852762 -37.11328874
OS -4.6782355 -37.10358086
OS -4.6990381 -37.08277826
OS -4.71013282 -37.07307038
OS -4.72122754 -37.06474934
OS -4.72261438 -37.0633625
OS -4.72538806 -37.06197566
OS -4.73093542 -37.05920198
OS -4.73925646 -37.05504146
OS -4.7475775 -37.05088094
OS -4.75728538 -37.04672042
OS -4.77947482 -37.03978622
OS -4.78086166 -37.03978622
OS -4.78363534 -37.03839938
OS -4.7891827 -37.03839938
OS -4.7961169 -37.03701254
OS -4.80582478 -37.0356257
OS -4.8169195 -37.0356257
OS -4.83217474 -37.03423886
OS -4.99582186 -37.03423886
OS -4.99582186 -37.45999874
OS -5.12341114 -37.45999874
OS -5.12341114 -36.50030546
OS -4.6782355 -36.50030546
OS -4.66714078 -36.5016923
OE
OB -1.0100437 -37.45999874 I
OS -1.13208562 -37.45999874
OS -1.13208562 -36.65701838
OS -1.4122273 -37.45999874
OS -1.52594818 -37.45999874
OS -1.80331618 -36.64314998
OS -1.80331618 -37.45999874
OS -1.9253581 -37.45999874
OS -1.9253581 -36.50030546
OS -1.73536102 -36.50030546
OS -1.50791926 -37.1812439
OS -1.50791926 -37.18263074
OS -1.50653242 -37.18540442
OS -1.50514558 -37.18956494
OS -1.5023719 -37.19649914
OS -1.49682454 -37.21314122
OS -1.48989034 -37.23394382
OS -1.48295614 -37.2575201
OS -1.4746351 -37.28109638
OS -1.4677009 -37.30328582
OS -1.46215354 -37.32270158
OS -1.4607667 -37.3199279
OS -1.45937986 -37.3129937
OS -1.45521934 -37.30051214
OS -1.44967198 -37.28387006
OS -1.44273778 -37.26168062
OS -1.4330299 -37.23533066
OS -1.42332202 -37.20482018
OS -1.41084046 -37.16876234
OS -1.18062502 -36.50030546
OS -1.0100437 -36.50030546
OS -1.0100437 -37.45999874
OE
OB -2.02382374 -37.45999874 I
OS -2.1680551 -37.45999874
OS -2.28038914 -37.16876234
OS -2.68257274 -37.16876234
OS -2.78658574 -37.45999874
OS -2.92110922 -37.45999874
OS -2.55498346 -36.50030546
OS -2.41629946 -36.50030546
OS -2.02382374 -37.45999874
OE
OB -3.02928274 -37.45999874 I
OS -3.16103254 -37.45999874
OS -3.66306862 -36.70694462
OS -3.66306862 -37.45999874
OS -3.78511054 -37.45999874
OS -3.78511054 -36.50030546
OS -3.65474758 -36.50030546
OS -3.15132466 -37.25474642
OS -3.15132466 -36.50030546
OS -3.02928274 -36.50030546
OS -3.02928274 -37.45999874
OE
OB -5.3231161 -36.61402634 I
OS -5.89033366 -36.61402634
OS -5.89033366 -36.90664958
OS -5.35917394 -36.90664958
OS -5.35917394 -37.02037046
OS -5.89033366 -37.02037046
OS -5.89033366 -37.34627786
OS -5.30092666 -37.34627786
OS -5.30092666 -37.45999874
OS -6.01792294 -37.45999874
OS -6.01792294 -36.50030546
OS -5.3231161 -36.50030546
OS -5.3231161 -36.61402634
OE
OB -0.10721086 -36.61402634 I
OS -0.67442842 -36.61402634
OS -0.67442842 -36.90664958
OS -0.1432687 -36.90664958
OS -0.1432687 -37.02037046
OS -0.67442842 -37.02037046
OS -0.67442842 -37.34627786
OS -0.08502142 -37.34627786
OS -0.08502142 -37.45999874
OS -0.8020177 -37.45999874
OS -0.8020177 -36.50030546
OS -0.10721086 -36.50030546
OS -0.10721086 -36.61402634
OE
OB -8.43241138 -37.34627786 I
OS -7.95949894 -37.34627786
OS -7.95949894 -37.45999874
OS -8.56000066 -37.45999874
OS -8.56000066 -36.50030546
OS -8.43241138 -36.50030546
OS -8.43241138 -37.34627786
OE
OB -6.51718534 -37.05365462 I
OS -6.51718534 -37.45999874
OS -6.64477462 -37.45999874
OS -6.64477462 -37.05365462
OS -7.0150609 -36.50030546
OS -6.86112166 -36.50030546
OS -6.67251142 -36.79154186
OS -6.67251142 -36.7929287
OS -6.66973774 -36.79570238
OS -6.66696406 -36.7998629
OS -6.66419038 -36.80541026
OS -6.65864302 -36.81234446
OS -6.65309566 -36.8206655
OS -6.6406141 -36.8414681
OS -6.62535886 -36.86643122
OS -6.60871678 -36.89416802
OS -6.59068786 -36.92329166
OS -6.57404578 -36.95380214
OS -6.57404578 -36.9524153
OS -6.57265894 -36.94964162
OS -6.56988526 -36.9454811
OS -6.56572474 -36.93993374
OS -6.56156422 -36.93299954
OS -6.55601686 -36.9246785
OS -6.5435353 -36.9038759
OS -6.52828006 -36.87891278
OS -6.51025114 -36.84978914
OS -6.48944854 -36.81789182
OS -6.4672591 -36.78322082
OS -6.28280938 -36.50030546
OS -6.1344175 -36.50030546
OS -6.51718534 -37.05365462
OE
OB -7.01644774 -37.45999874 I
OS -7.1606791 -37.45999874
OS -7.27301314 -37.16876234
OS -7.67519674 -37.16876234
OS -7.77920974 -37.45999874
OS -7.91373322 -37.45999874
OS -7.54760746 -36.50030546
OS -7.40892346 -36.50030546
OS -7.01644774 -37.45999874
OE
OB -7.48103914 -36.60015794 H
OS -7.48103914 -36.60154478
OS -7.48242598 -36.60431846
OS -7.48242598 -36.60986582
OS -7.48519966 -36.61541318
OS -7.4865865 -36.62512106
OS -7.48936018 -36.63482894
OS -7.49490754 -36.65840522
OS -7.50184174 -36.68614202
OS -7.51154962 -36.7166525
OS -7.5212575 -36.74993666
OS -7.53373906 -36.78460766
OS -7.63775206 -37.06474934
OS -7.3132315 -37.06474934
OS -7.41308398 -36.80124974
OS -7.41308398 -36.7998629
OS -7.41447082 -36.79570238
OS -7.4172445 -36.78876818
OS -7.42001818 -36.78044714
OS -7.4241787 -36.77073926
OS -7.42833922 -36.7582577
OS -7.43249974 -36.7443893
OS -7.4380471 -36.7305209
OS -7.44914182 -36.69862358
OS -7.46023654 -36.66533942
OS -7.47133126 -36.63205526
OS -7.48103914 -36.60015794
OE
OB -4.69349074 -36.60709214 H
OS -4.99582186 -36.60709214
OS -4.99582186 -36.9246785
OS -4.71013282 -36.9246785
OS -4.69349074 -36.92329166
OS -4.67407498 -36.92190482
OS -4.65188554 -36.92051798
OS -4.6296961 -36.9177443
OS -4.60750666 -36.91358378
OS -4.5880909 -36.90803642
OS -4.58531722 -36.90664958
OS -4.57976986 -36.9038759
OS -4.57144882 -36.89971538
OS -4.5603541 -36.89416802
OS -4.54787254 -36.88584698
OS -4.53539098 -36.8761391
OS -4.52290942 -36.86365754
OS -4.51320154 -36.84978914
OS -4.5118147 -36.8484023
OS -4.50904102 -36.84285494
OS -4.5048805 -36.8345339
OS -4.49933314 -36.82343918
OS -4.49517262 -36.81095762
OS -4.4910121 -36.79708922
OS -4.48823842 -36.78044714
OS -4.48685158 -36.76380506
OS -4.48685158 -36.76241822
OS -4.48685158 -36.76103138
OS -4.48823842 -36.75271034
OS -4.48962526 -36.74022878
OS -4.49239894 -36.7235867
OS -4.49933314 -36.70694462
OS -4.50765418 -36.68752886
OS -4.52013574 -36.66949994
OS -4.53677782 -36.65147102
OS -4.5395515 -36.65008418
OS -4.5464857 -36.64453682
OS -4.55758042 -36.63760262
OS -4.57560934 -36.62928158
OS -4.59641194 -36.62096054
OS -4.62414874 -36.61402634
OS -4.65604606 -36.60847898
OS -4.69349074 -36.60709214
OE
OB -2.48841514 -36.60015794 H
OS -2.48841514 -36.60154478
OS -2.48980198 -36.60431846
OS -2.48980198 -36.60986582
OS -2.49257566 -36.61541318
OS -2.4939625 -36.62512106
OS -2.49673618 -36.63482894
OS -2.50228354 -36.65840522
OS -2.50921774 -36.68614202
OS -2.51892562 -36.7166525
OS -2.5286335 -36.74993666
OS -2.54111506 -36.78460766
OS -2.64512806 -37.06474934
OS -2.3206075 -37.06474934
OS -2.42045998 -36.80124974
OS -2.42045998 -36.7998629
OS -2.42184682 -36.79570238
OS -2.4246205 -36.78876818
OS -2.42739418 -36.78044714
OS -2.4315547 -36.77073926
OS -2.43571522 -36.7582577
OS -2.43987574 -36.7443893
OS -2.4454231 -36.7305209
OS -2.45651782 -36.69862358
OS -2.46761254 -36.66533942
OS -2.47870726 -36.63205526
OS -2.48841514 -36.60015794
OE
SE
S P 0
OB 35.73690338 -37.45999874 I
OS 35.61486146 -37.45999874
OS 35.61486146 -36.65701838
OS 35.33471978 -37.45999874
OS 35.2209989 -37.45999874
OS 34.9436309 -36.64314998
OS 34.9436309 -37.45999874
OS 34.82158898 -37.45999874
OS 34.82158898 -36.50030546
OS 35.01158606 -36.50030546
OS 35.23902782 -37.1812439
OS 35.23902782 -37.18263074
OS 35.24041466 -37.18540442
OS 35.2418015 -37.18956494
OS 35.24457518 -37.19649914
OS 35.25012254 -37.21314122
OS 35.25705674 -37.23394382
OS 35.26399094 -37.2575201
OS 35.27231198 -37.28109638
OS 35.27924618 -37.30328582
OS 35.28479354 -37.32270158
OS 35.28618038 -37.3199279
OS 35.28756722 -37.3129937
OS 35.29172774 -37.30051214
OS 35.2972751 -37.28387006
OS 35.3042093 -37.26168062
OS 35.31391718 -37.23533066
OS 35.32362506 -37.20482018
OS 35.33610662 -37.16876234
OS 35.56632206 -36.50030546
OS 35.73690338 -36.50030546
OS 35.73690338 -37.45999874
OE
OB 34.61356298 -37.05504146 I
OS 34.61356298 -37.0564283
OS 34.61356298 -37.06197566
OS 34.61356298 -37.06890986
OS 34.61356298 -37.07861774
OS 34.61217614 -37.0910993
OS 34.61217614 -37.1049677
OS 34.6107893 -37.12160978
OS 34.60940246 -37.13825186
OS 34.60524194 -37.17569654
OS 34.59969458 -37.21452806
OS 34.59137354 -37.25197274
OS 34.58582618 -37.27000166
OS 34.58027882 -37.28664374
OS 34.58027882 -37.28803058
OS 34.57889198 -37.29080426
OS 34.5761183 -37.29496478
OS 34.57334462 -37.30051214
OS 34.56502358 -37.31576738
OS 34.55254202 -37.33518314
OS 34.53589994 -37.35737258
OS 34.51648418 -37.37956202
OS 34.49152106 -37.4031383
OS 34.46101058 -37.4239409
OS 34.45962374 -37.4239409
OS 34.45685006 -37.42671458
OS 34.45268954 -37.42810142
OS 34.44575534 -37.43226194
OS 34.4374343 -37.43642246
OS 34.42633958 -37.44058298
OS 34.41524486 -37.4447435
OS 34.40137646 -37.45029086
OS 34.38612122 -37.45583822
OS 34.36947914 -37.45999874
OS 34.35145022 -37.46415926
OS 34.33064762 -37.46831978
OS 34.30984502 -37.47109346
OS 34.28765558 -37.47386714
OS 34.23772934 -37.47664082
OS 34.22524778 -37.47664082
OS 34.2155399 -37.47525398
OS 34.20444518 -37.47525398
OS 34.19057678 -37.47386714
OS 34.17532154 -37.4724803
OS 34.1600663 -37.47109346
OS 34.1253953 -37.4655461
OS 34.08795062 -37.45722506
OS 34.05189278 -37.44613034
OS 34.01722178 -37.4308751
OS 34.01583494 -37.4308751
OS 34.01306126 -37.42810142
OS 34.00890074 -37.42532774
OS 34.00335338 -37.42255406
OS 33.98809814 -37.41145934
OS 33.97006922 -37.3962041
OS 33.94926662 -37.37678834
OS 33.92985086 -37.3545989
OS 33.9104351 -37.3268621
OS 33.89517986 -37.29635162
OS 33.89517986 -37.29496478
OS 33.89379302 -37.2921911
OS 33.89240618 -37.28664374
OS 33.8896325 -37.27970954
OS 33.88685882 -37.2713885
OS 33.88408514 -37.26029378
OS 33.87992462 -37.24781222
OS 33.87715094 -37.23255698
OS 33.87437726 -37.2159149
OS 33.87021674 -37.19788598
OS 33.86744306 -37.17847022
OS 33.86466938 -37.15766762
OS 33.8618957 -37.13409134
OS 33.86050886 -37.10912822
OS 33.85912202 -37.08277826
OS 33.85912202 -37.05504146
OS 33.85912202 -36.50030546
OS 33.9867113 -36.50030546
OS 33.9867113 -37.05504146
OS 33.9867113 -37.0564283
OS 33.9867113 -37.06058882
OS 33.9867113 -37.06752302
OS 33.9867113 -37.07584406
OS 33.98809814 -37.08555194
OS 33.98809814 -37.0980335
OS 33.98948498 -37.12438346
OS 33.99225866 -37.15489394
OS 33.99641918 -37.18540442
OS 34.00196654 -37.21452806
OS 34.00474022 -37.22700962
OS 34.00890074 -37.23949118
OS 34.01028758 -37.24226486
OS 34.01306126 -37.24919906
OS 34.01999546 -37.25890694
OS 34.0283165 -37.27277534
OS 34.03802438 -37.28664374
OS 34.05189278 -37.30189898
OS 34.06853486 -37.31715422
OS 34.08795062 -37.32963578
OS 34.0907243 -37.33102262
OS 34.0976585 -37.33518314
OS 34.11014006 -37.33934366
OS 34.12678214 -37.34489102
OS 34.1461979 -37.35182522
OS 34.17116102 -37.35598574
OS 34.19751098 -37.36014626
OS 34.22663462 -37.3615331
OS 34.24050302 -37.3615331
OS 34.24882406 -37.36014626
OS 34.26130562 -37.36014626
OS 34.27378718 -37.35875942
OS 34.30429766 -37.35321206
OS 34.33758182 -37.34627786
OS 34.36947914 -37.33518314
OS 34.39998962 -37.3199279
OS 34.41385802 -37.31022002
OS 34.42633958 -37.2991253
OS 34.42772642 -37.29773846
OS 34.42911326 -37.29635162
OS 34.43188694 -37.2921911
OS 34.43604746 -37.28664374
OS 34.44020798 -37.2783227
OS 34.44575534 -37.27000166
OS 34.4513027 -37.2575201
OS 34.45685006 -37.24503854
OS 34.46239742 -37.2297833
OS 34.46655794 -37.21175438
OS 34.4721053 -37.19095178
OS 34.47626582 -37.16876234
OS 34.48042634 -37.14379922
OS 34.48320002 -37.11744926
OS 34.4859737 -37.08693878
OS 34.4859737 -37.05504146
OS 34.4859737 -36.50030546
OS 34.61356298 -36.50030546
OS 34.61356298 -37.05504146
OE
OB 33.64416182 -37.45999874 I
OS 33.51241202 -37.45999874
OS 33.01037594 -36.70694462
OS 33.01037594 -37.45999874
OS 32.88833402 -37.45999874
OS 32.88833402 -36.50030546
OS 33.01869698 -36.50030546
OS 33.5221199 -37.25474642
OS 33.5221199 -36.50030546
OS 33.64416182 -36.50030546
OS 33.64416182 -37.45999874
OE
OB 38.19022334 -36.5016923 I
OS 38.2027049 -36.5016923
OS 38.23182854 -36.50307914
OS 38.26233902 -36.50723966
OS 38.29562318 -36.51140018
OS 38.32613366 -36.51833438
OS 38.3413889 -36.5224949
OS 38.35387046 -36.52665542
OS 38.3552573 -36.52665542
OS 38.35664414 -36.52804226
OS 38.36496518 -36.53220278
OS 38.37744674 -36.53775014
OS 38.39270198 -36.54745802
OS 38.40934406 -36.55993958
OS 38.42737298 -36.57658166
OS 38.44401506 -36.59599742
OS 38.46065714 -36.61818686
OS 38.46065714 -36.6195737
OS 38.46204398 -36.62096054
OS 38.46759134 -36.62928158
OS 38.4731387 -36.64314998
OS 38.48145974 -36.6611789
OS 38.48839394 -36.6819815
OS 38.49532814 -36.70694462
OS 38.49948866 -36.73329458
OS 38.5008755 -36.76241822
OS 38.5008755 -36.76380506
OS 38.5008755 -36.76657874
OS 38.5008755 -36.7721261
OS 38.49948866 -36.7790603
OS 38.49948866 -36.78876818
OS 38.49810182 -36.79847606
OS 38.49255446 -36.82205234
OS 38.48423342 -36.84978914
OS 38.4731387 -36.87891278
OS 38.45649662 -36.90803642
OS 38.4454019 -36.92190482
OS 38.43430718 -36.93577322
OS 38.43292034 -36.93716006
OS 38.4315335 -36.9385469
OS 38.42737298 -36.94270742
OS 38.42182562 -36.94686794
OS 38.41489142 -36.9524153
OS 38.40657038 -36.95796266
OS 38.39547566 -36.96489686
OS 38.38438094 -36.9732179
OS 38.37051254 -36.9801521
OS 38.3552573 -36.9870863
OS 38.33861522 -36.99540734
OS 38.3205863 -37.00234154
OS 38.2997837 -37.0078889
OS 38.2789811 -37.0148231
OS 38.25540482 -37.01898362
OS 38.2304417 -37.02314414
OS 38.23321538 -37.02453098
OS 38.23876274 -37.02730466
OS 38.24708378 -37.03285202
OS 38.2581785 -37.03839938
OS 38.28314162 -37.05365462
OS 38.29562318 -37.0633625
OS 38.3067179 -37.07168354
OS 38.30949158 -37.07445722
OS 38.31642578 -37.08139142
OS 38.3275205 -37.09248614
OS 38.3413889 -37.10635454
OS 38.35664414 -37.1257703
OS 38.37467306 -37.1465729
OS 38.39270198 -37.17153602
OS 38.41211774 -37.19927282
OS 38.5771517 -37.45999874
OS 38.41905194 -37.45999874
OS 38.2928495 -37.26029378
OS 38.2928495 -37.25890694
OS 38.29007582 -37.25613326
OS 38.28730214 -37.25197274
OS 38.28314162 -37.24642538
OS 38.27343374 -37.23117014
OS 38.26095218 -37.21175438
OS 38.24569694 -37.19095178
OS 38.2304417 -37.16876234
OS 38.21518646 -37.14795974
OS 38.20131806 -37.12854398
OS 38.19993122 -37.12715714
OS 38.1957707 -37.12160978
OS 38.1888365 -37.11328874
OS 38.17912862 -37.10358086
OS 38.15832602 -37.08277826
OS 38.1472313 -37.07307038
OS 38.13613658 -37.06474934
OS 38.13474974 -37.0633625
OS 38.13197606 -37.06197566
OS 38.1264287 -37.05920198
OS 38.11810766 -37.05504146
OS 38.10978662 -37.05088094
OS 38.10007874 -37.04672042
OS 38.0778893 -37.03978622
OS 38.07650246 -37.03978622
OS 38.07372878 -37.03839938
OS 38.06818142 -37.03839938
OS 38.06124722 -37.03701254
OS 38.05153934 -37.0356257
OS 38.04044462 -37.0356257
OS 38.02518938 -37.03423886
OS 37.86154226 -37.03423886
OS 37.86154226 -37.45999874
OS 37.73395298 -37.45999874
OS 37.73395298 -36.50030546
OS 38.17912862 -36.50030546
OS 38.19022334 -36.5016923
OE
OB 37.53424802 -36.61402634 I
OS 36.96703046 -36.61402634
OS 36.96703046 -36.90664958
OS 37.49819018 -36.90664958
OS 37.49819018 -37.02037046
OS 36.96703046 -37.02037046
OS 36.96703046 -37.34627786
OS 37.55643746 -37.34627786
OS 37.55643746 -37.45999874
OS 36.83944118 -37.45999874
OS 36.83944118 -36.50030546
OS 37.53424802 -36.50030546
OS 37.53424802 -36.61402634
OE
OB 36.32492354 -36.5016923 I
OS 36.33601826 -36.5016923
OS 36.36098138 -36.50446598
OS 36.38871818 -36.50723966
OS 36.41784182 -36.51278702
OS 36.44696546 -36.51972122
OS 36.47331542 -36.5294291
OS 36.47470226 -36.5294291
OS 36.4760891 -36.53081594
OS 36.48441014 -36.53497646
OS 36.4968917 -36.54191066
OS 36.5107601 -36.55161854
OS 36.52740218 -36.5641001
OS 36.5454311 -36.57935534
OS 36.56207318 -36.5987711
OS 36.57732842 -36.6195737
OS 36.57871526 -36.62234738
OS 36.58287578 -36.63066842
OS 36.58980998 -36.64176314
OS 36.59674418 -36.65840522
OS 36.60367838 -36.67782098
OS 36.61061258 -36.69862358
OS 36.6147731 -36.72219986
OS 36.61615994 -36.74577614
OS 36.61615994 -36.74854982
OS 36.61615994 -36.75548402
OS 36.6147731 -36.76796558
OS 36.61199942 -36.78322082
OS 36.6078389 -36.80124974
OS 36.6009047 -36.8206655
OS 36.59258366 -36.84008126
OS 36.58148894 -36.86088386
OS 36.5801021 -36.86365754
OS 36.57594158 -36.8692049
OS 36.56762054 -36.88029962
OS 36.55652582 -36.89139434
OS 36.54265742 -36.90526274
OS 36.52601534 -36.92051798
OS 36.50521274 -36.93438638
OS 36.48163646 -36.94825478
OS 36.4830233 -36.94825478
OS 36.48579698 -36.94964162
OS 36.4899575 -36.95102846
OS 36.49550486 -36.95380214
OS 36.51214694 -36.9593495
OS 36.5315627 -36.96905738
OS 36.5523653 -36.98153894
OS 36.57594158 -36.99679418
OS 36.59674418 -37.0148231
OS 36.61615994 -37.03701254
OS 36.61754678 -37.03978622
OS 36.62309414 -37.04810726
OS 36.63141518 -37.06058882
OS 36.63973622 -37.0772309
OS 36.64805726 -37.09942034
OS 36.6563783 -37.12299662
OS 36.66192566 -37.15073342
OS 36.6633125 -37.1812439
OS 36.6633125 -37.18263074
OS 36.6633125 -37.18401758
OS 36.6633125 -37.19233862
OS 36.66192566 -37.20620702
OS 36.65915198 -37.2228491
OS 36.6563783 -37.24226486
OS 36.65083094 -37.26306746
OS 36.64389674 -37.2852569
OS 36.63418886 -37.30744634
OS 36.63280202 -37.31022002
OS 36.6286415 -37.31715422
OS 36.62309414 -37.3268621
OS 36.6147731 -37.3407305
OS 36.60367838 -37.3545989
OS 36.59258366 -37.36985414
OS 36.57871526 -37.38510938
OS 36.56346002 -37.39759094
OS 36.56207318 -37.39897778
OS 36.55652582 -37.4031383
OS 36.54681794 -37.40868566
OS 36.53433638 -37.41423302
OS 36.51908114 -37.42255406
OS 36.50105222 -37.4308751
OS 36.48163646 -37.4378093
OS 36.45806018 -37.4447435
OS 36.4552865 -37.4447435
OS 36.44696546 -37.44751718
OS 36.43309706 -37.44890402
OS 36.41506814 -37.4516777
OS 36.3928787 -37.45445138
OS 36.36652874 -37.45722506
OS 36.3374051 -37.4586119
OS 36.30412094 -37.45999874
OS 35.93799518 -37.45999874
OS 35.93799518 -36.50030546
OS 36.31521566 -36.50030546
OS 36.32492354 -36.5016923
OE
OB 32.3849111 -36.61402634 I
OS 32.06871158 -36.61402634
OS 32.06871158 -37.45999874
OS 31.9411223 -37.45999874
OS 31.9411223 -36.61402634
OS 31.62492278 -36.61402634
OS 31.62492278 -36.50030546
OS 32.3849111 -36.50030546
OS 32.3849111 -36.61402634
OE
OB 30.62639798 -37.45999874 I
OS 30.48216662 -37.45999874
OS 30.36983258 -37.16876234
OS 29.96764898 -37.16876234
OS 29.86363598 -37.45999874
OS 29.7291125 -37.45999874
OS 30.09523826 -36.50030546
OS 30.23392226 -36.50030546
OS 30.62639798 -37.45999874
OE
OB 29.3546657 -36.5016923 I
OS 29.37824198 -36.50307914
OS 29.4032051 -36.50446598
OS 29.42678138 -36.50723966
OS 29.44758398 -36.51001334
OS 29.45035766 -36.51001334
OS 29.46006554 -36.51278702
OS 29.4725471 -36.5155607
OS 29.48918918 -36.51972122
OS 29.5072181 -36.52665542
OS 29.52663386 -36.53497646
OS 29.54743646 -36.54468434
OS 29.56546538 -36.55577906
OS 29.56823906 -36.5571659
OS 29.57378642 -36.56132642
OS 29.58210746 -36.56964746
OS 29.59320218 -36.57935534
OS 29.60568374 -36.5918369
OS 29.6181653 -36.60847898
OS 29.6320337 -36.6265079
OS 29.64312842 -36.6473105
OS 29.64451526 -36.65008418
OS 29.64728894 -36.65701838
OS 29.6528363 -36.66949994
OS 29.65838366 -36.68614202
OS 29.66254418 -36.70555778
OS 29.66809154 -36.72774722
OS 29.67086522 -36.75271034
OS 29.67225206 -36.7790603
OS 29.67225206 -36.78044714
OS 29.67225206 -36.78460766
OS 29.67225206 -36.79015502
OS 29.67086522 -36.7998629
OS 29.66947838 -36.80957078
OS 29.66809154 -36.82205234
OS 29.66531786 -36.83592074
OS 29.66254418 -36.85117598
OS 29.6528363 -36.8830733
OS 29.64728894 -36.89971538
OS 29.6389679 -36.9177443
OS 29.62926002 -36.93577322
OS 29.61955214 -36.9524153
OS 29.60707058 -36.96905738
OS 29.59320218 -36.98569946
OS 29.59181534 -36.9870863
OS 29.58904166 -36.98985998
OS 29.58488114 -36.9940205
OS 29.57794694 -36.99818102
OS 29.5696259 -37.00511522
OS 29.55853118 -37.01204942
OS 29.54466278 -37.02037046
OS 29.52940754 -37.02730466
OS 29.51137862 -37.0356257
OS 29.49057602 -37.04394674
OS 29.46838658 -37.05088094
OS 29.44203662 -37.0564283
OS 29.41429982 -37.06197566
OS 29.38378934 -37.06613618
OS 29.34911834 -37.06890986
OS 29.3130605 -37.0702967
OS 29.06758982 -37.0702967
OS 29.06758982 -37.45999874
OS 28.94000054 -37.45999874
OS 28.94000054 -36.50030546
OS 29.3338631 -36.50030546
OS 29.3546657 -36.5016923
OE
OB 31.18668134 -36.5016923 I
OS 31.1991629 -36.5016923
OS 31.22828654 -36.50307914
OS 31.25879702 -36.50723966
OS 31.29208118 -36.51140018
OS 31.32259166 -36.51833438
OS 31.3378469 -36.5224949
OS 31.35032846 -36.52665542
OS 31.3517153 -36.52665542
OS 31.35310214 -36.52804226
OS 31.36142318 -36.53220278
OS 31.37390474 -36.53775014
OS 31.38915998 -36.54745802
OS 31.40580206 -36.55993958
OS 31.42383098 -36.57658166
OS 31.44047306 -36.59599742
OS 31.45711514 -36.61818686
OS 31.45711514 -36.6195737
OS 31.45850198 -36.62096054
OS 31.46404934 -36.62928158
OS 31.4695967 -36.64314998
OS 31.47791774 -36.6611789
OS 31.48485194 -36.6819815
OS 31.49178614 -36.70694462
OS 31.49594666 -36.73329458
OS 31.4973335 -36.76241822
OS 31.4973335 -36.76380506
OS 31.4973335 -36.76657874
OS 31.4973335 -36.7721261
OS 31.49594666 -36.7790603
OS 31.49594666 -36.78876818
OS 31.49455982 -36.79847606
OS 31.48901246 -36.82205234
OS 31.48069142 -36.84978914
OS 31.4695967 -36.87891278
OS 31.45295462 -36.90803642
OS 31.4418599 -36.92190482
OS 31.43076518 -36.93577322
OS 31.42937834 -36.93716006
OS 31.4279915 -36.9385469
OS 31.42383098 -36.94270742
OS 31.41828362 -36.94686794
OS 31.41134942 -36.9524153
OS 31.40302838 -36.95796266
OS 31.39193366 -36.96489686
OS 31.38083894 -36.9732179
OS 31.36697054 -36.9801521
OS 31.3517153 -36.9870863
OS 31.33507322 -36.99540734
OS 31.3170443 -37.00234154
OS 31.2962417 -37.0078889
OS 31.2754391 -37.0148231
OS 31.25186282 -37.01898362
OS 31.2268997 -37.02314414
OS 31.22967338 -37.02453098
OS 31.23522074 -37.02730466
OS 31.24354178 -37.03285202
OS 31.2546365 -37.03839938
OS 31.27959962 -37.05365462
OS 31.29208118 -37.0633625
OS 31.3031759 -37.07168354
OS 31.30594958 -37.07445722
OS 31.31288378 -37.08139142
OS 31.3239785 -37.09248614
OS 31.3378469 -37.10635454
OS 31.35310214 -37.1257703
OS 31.37113106 -37.1465729
OS 31.38915998 -37.17153602
OS 31.40857574 -37.19927282
OS 31.5736097 -37.45999874
OS 31.41550994 -37.45999874
OS 31.2893075 -37.26029378
OS 31.2893075 -37.25890694
OS 31.28653382 -37.25613326
OS 31.28376014 -37.25197274
OS 31.27959962 -37.24642538
OS 31.26989174 -37.23117014
OS 31.25741018 -37.21175438
OS 31.24215494 -37.19095178
OS 31.2268997 -37.16876234
OS 31.21164446 -37.14795974
OS 31.19777606 -37.12854398
OS 31.19638922 -37.12715714
OS 31.1922287 -37.12160978
OS 31.1852945 -37.11328874
OS 31.17558662 -37.10358086
OS 31.15478402 -37.08277826
OS 31.1436893 -37.07307038
OS 31.13259458 -37.06474934
OS 31.13120774 -37.0633625
OS 31.12843406 -37.06197566
OS 31.1228867 -37.05920198
OS 31.11456566 -37.05504146
OS 31.10624462 -37.05088094
OS 31.09653674 -37.04672042
OS 31.0743473 -37.03978622
OS 31.07296046 -37.03978622
OS 31.07018678 -37.03839938
OS 31.06463942 -37.03839938
OS 31.05770522 -37.03701254
OS 31.04799734 -37.0356257
OS 31.03690262 -37.0356257
OS 31.02164738 -37.03423886
OS 30.85800026 -37.03423886
OS 30.85800026 -37.45999874
OS 30.73041098 -37.45999874
OS 30.73041098 -36.50030546
OS 31.17558662 -36.50030546
OS 31.18668134 -36.5016923
OE
OB 38.16387338 -36.60709214 H
OS 37.86154226 -36.60709214
OS 37.86154226 -36.9246785
OS 38.1472313 -36.9246785
OS 38.16387338 -36.92329166
OS 38.18328914 -36.92190482
OS 38.20547858 -36.92051798
OS 38.22766802 -36.9177443
OS 38.24985746 -36.91358378
OS 38.26927322 -36.90803642
OS 38.2720469 -36.90664958
OS 38.27759426 -36.9038759
OS 38.2859153 -36.89971538
OS 38.29701002 -36.89416802
OS 38.30949158 -36.88584698
OS 38.32197314 -36.8761391
OS 38.3344547 -36.86365754
OS 38.34416258 -36.84978914
OS 38.34554942 -36.8484023
OS 38.3483231 -36.84285494
OS 38.35248362 -36.8345339
OS 38.35803098 -36.82343918
OS 38.3621915 -36.81095762
OS 38.36635202 -36.79708922
OS 38.3691257 -36.78044714
OS 38.37051254 -36.76380506
OS 38.37051254 -36.76241822
OS 38.37051254 -36.76103138
OS 38.3691257 -36.75271034
OS 38.36773886 -36.74022878
OS 38.36496518 -36.7235867
OS 38.35803098 -36.70694462
OS 38.34970994 -36.68752886
OS 38.33722838 -36.66949994
OS 38.3205863 -36.65147102
OS 38.31781262 -36.65008418
OS 38.31087842 -36.64453682
OS 38.2997837 -36.63760262
OS 38.28175478 -36.62928158
OS 38.26095218 -36.62096054
OS 38.23321538 -36.61402634
OS 38.20131806 -36.60847898
OS 38.16387338 -36.60709214
OE
OB 29.34218414 -36.61402634 H
OS 29.06758982 -36.61402634
OS 29.06758982 -36.95657582
OS 29.32554206 -36.95657582
OS 29.33524994 -36.95518898
OS 29.34495782 -36.95518898
OS 29.35605254 -36.95380214
OS 29.3824025 -36.95102846
OS 29.41152614 -36.9454811
OS 29.44064978 -36.93716006
OS 29.46699974 -36.92606534
OS 29.4794813 -36.91913114
OS 29.48918918 -36.9108101
OS 29.49196286 -36.90803642
OS 29.49751022 -36.90248906
OS 29.50583126 -36.89139434
OS 29.51553914 -36.87752594
OS 29.52524702 -36.85949702
OS 29.53356806 -36.83730758
OS 29.53911542 -36.81234446
OS 29.5418891 -36.78322082
OS 29.5418891 -36.78183398
OS 29.5418891 -36.78044714
OS 29.5418891 -36.77351294
OS 29.54050226 -36.76103138
OS 29.53772858 -36.74716298
OS 29.5349549 -36.73190774
OS 29.52940754 -36.71387882
OS 29.5210865 -36.69723674
OS 29.51137862 -36.68059466
OS 29.50999178 -36.67920782
OS 29.50583126 -36.67366046
OS 29.49889706 -36.66672626
OS 29.49057602 -36.65701838
OS 29.47809446 -36.6473105
OS 29.46422606 -36.63898946
OS 29.44897082 -36.63066842
OS 29.4309419 -36.62373422
OS 29.42955506 -36.62373422
OS 29.4240077 -36.62234738
OS 29.41568666 -36.62096054
OS 29.40459194 -36.61818686
OS 29.38794986 -36.61680002
OS 29.36714726 -36.61541318
OS 29.34218414 -36.61402634
OE
OB 30.16180658 -36.60015794 H
OS 30.16180658 -36.60154478
OS 30.16041974 -36.60431846
OS 30.16041974 -36.60986582
OS 30.15764606 -36.61541318
OS 30.15625922 -36.62512106
OS 30.15348554 -36.63482894
OS 30.14793818 -36.65840522
OS 30.14100398 -36.68614202
OS 30.1312961 -36.7166525
OS 30.12158822 -36.74993666
OS 30.10910666 -36.78460766
OS 30.00509366 -37.06474934
OS 30.32961422 -37.06474934
OS 30.22976174 -36.80124974
OS 30.22976174 -36.7998629
OS 30.2283749 -36.79570238
OS 30.22560122 -36.78876818
OS 30.22282754 -36.78044714
OS 30.21866702 -36.77073926
OS 30.2145065 -36.7582577
OS 30.21034598 -36.7443893
OS 30.20479862 -36.7305209
OS 30.1937039 -36.69862358
OS 30.18260918 -36.66533942
OS 30.17151446 -36.63205526
OS 30.16180658 -36.60015794
OE
OB 31.16033138 -36.60709214 H
OS 30.85800026 -36.60709214
OS 30.85800026 -36.9246785
OS 31.1436893 -36.9246785
OS 31.16033138 -36.92329166
OS 31.17974714 -36.92190482
OS 31.20193658 -36.92051798
OS 31.22412602 -36.9177443
OS 31.24631546 -36.91358378
OS 31.26573122 -36.90803642
OS 31.2685049 -36.90664958
OS 31.27405226 -36.9038759
OS 31.2823733 -36.89971538
OS 31.29346802 -36.89416802
OS 31.30594958 -36.88584698
OS 31.31843114 -36.8761391
OS 31.3309127 -36.86365754
OS 31.34062058 -36.84978914
OS 31.34200742 -36.8484023
OS 31.3447811 -36.84285494
OS 31.34894162 -36.8345339
OS 31.35448898 -36.82343918
OS 31.3586495 -36.81095762
OS 31.36281002 -36.79708922
OS 31.3655837 -36.78044714
OS 31.36697054 -36.76380506
OS 31.36697054 -36.76241822
OS 31.36697054 -36.76103138
OS 31.3655837 -36.75271034
OS 31.36419686 -36.74022878
OS 31.36142318 -36.7235867
OS 31.35448898 -36.70694462
OS 31.34616794 -36.68752886
OS 31.33368638 -36.66949994
OS 31.3170443 -36.65147102
OS 31.31427062 -36.65008418
OS 31.30733642 -36.64453682
OS 31.2962417 -36.63760262
OS 31.27821278 -36.62928158
OS 31.25741018 -36.62096054
OS 31.22967338 -36.61402634
OS 31.19777606 -36.60847898
OS 31.16033138 -36.60709214
OE
OB 36.29302622 -36.61402634 H
OS 36.06558446 -36.61402634
OS 36.06558446 -36.90248906
OS 36.30134726 -36.90248906
OS 36.31937618 -36.90110222
OS 36.33879194 -36.89971538
OS 36.3582077 -36.89832854
OS 36.37762346 -36.89555486
OS 36.3928787 -36.89278118
OS 36.39565238 -36.89139434
OS 36.40119974 -36.8900075
OS 36.40952078 -36.88584698
OS 36.4206155 -36.88029962
OS 36.43171022 -36.87475226
OS 36.44419178 -36.86643122
OS 36.45667334 -36.8553365
OS 36.46638122 -36.84424178
OS 36.46776806 -36.84285494
OS 36.47054174 -36.83869442
OS 36.47470226 -36.83037338
OS 36.47886278 -36.8206655
OS 36.4830233 -36.80957078
OS 36.48718382 -36.79570238
OS 36.4899575 -36.7790603
OS 36.49134434 -36.76103138
OS 36.49134434 -36.7582577
OS 36.49134434 -36.75271034
OS 36.4899575 -36.7443893
OS 36.48857066 -36.73329458
OS 36.48579698 -36.71942618
OS 36.48163646 -36.70555778
OS 36.4760891 -36.69168938
OS 36.46776806 -36.67782098
OS 36.46638122 -36.67643414
OS 36.46360754 -36.67227362
OS 36.45806018 -36.66533942
OS 36.45112598 -36.65840522
OS 36.4414181 -36.65008418
OS 36.43032338 -36.64176314
OS 36.41645498 -36.6334421
OS 36.40119974 -36.62789474
OS 36.3998129 -36.62789474
OS 36.3928787 -36.62512106
OS 36.38317082 -36.62373422
OS 36.36791558 -36.62096054
OS 36.34711298 -36.61818686
OS 36.3235367 -36.61680002
OS 36.29302622 -36.61402634
OE
OB 36.31798934 -37.01620994 H
OS 36.06558446 -37.01620994
OS 36.06558446 -37.34627786
OS 36.33879194 -37.34627786
OS 36.36791558 -37.34489102
OS 36.38039714 -37.34350418
OS 36.39149186 -37.34211734
OS 36.3928787 -37.34211734
OS 36.39842606 -37.3407305
OS 36.4067471 -37.33934366
OS 36.41645498 -37.33656998
OS 36.44003126 -37.32824894
OS 36.46360754 -37.31715422
OS 36.46499438 -37.31576738
OS 36.4691549 -37.3129937
OS 36.47470226 -37.30883318
OS 36.48163646 -37.30328582
OS 36.48857066 -37.29496478
OS 36.49827854 -37.28664374
OS 36.50521274 -37.27554902
OS 36.51353378 -37.26306746
OS 36.51492062 -37.26168062
OS 36.51630746 -37.2575201
OS 36.51908114 -37.24919906
OS 36.52324166 -37.23949118
OS 36.52740218 -37.22839646
OS 36.53017586 -37.21452806
OS 36.5315627 -37.19788598
OS 36.53294954 -37.1812439
OS 36.53294954 -37.17847022
OS 36.53294954 -37.17292286
OS 36.5315627 -37.16182814
OS 36.52878902 -37.14934658
OS 36.52601534 -37.13547818
OS 36.52046798 -37.12022294
OS 36.51353378 -37.1049677
OS 36.5038259 -37.08971246
OS 36.50243906 -37.08832562
OS 36.49827854 -37.08277826
OS 36.49273118 -37.07584406
OS 36.48441014 -37.06752302
OS 36.47331542 -37.05781514
OS 36.45944702 -37.04810726
OS 36.44419178 -37.03978622
OS 36.42616286 -37.03285202
OS 36.42338918 -37.03146518
OS 36.41784182 -37.03007834
OS 36.40536026 -37.02730466
OS 36.39010502 -37.02453098
OS 36.37068926 -37.0217573
OS 36.34711298 -37.01898362
OS 36.31798934 -37.01620994
OE
SE
S P 0
OB 40.9056459 -38.32112732 I
OS 40.92136342 -38.32205188
OS 40.9380055 -38.32297644
OS 40.95372302 -38.32482556
OS 40.96759142 -38.32667468
OS 40.96944054 -38.32667468
OS 40.97591246 -38.3285238
OS 40.9842335 -38.33037292
OS 40.99532822 -38.3331466
OS 41.0073475 -38.3377694
OS 41.02029134 -38.34331676
OS 41.03415974 -38.34978868
OS 41.04617902 -38.35718516
OS 41.04802814 -38.35810972
OS 41.05172638 -38.3608834
OS 41.05727374 -38.36643076
OS 41.06467022 -38.37290268
OS 41.07299126 -38.38122372
OS 41.0813123 -38.39231844
OS 41.0905579 -38.40433772
OS 41.09795438 -38.41820612
OS 41.09887894 -38.42005524
OS 41.10072806 -38.42467804
OS 41.1044263 -38.43299908
OS 41.10812454 -38.4440938
OS 41.11089822 -38.45703764
OS 41.11459646 -38.4718306
OS 41.11644558 -38.48847268
OS 41.11737014 -38.50603932
OS 41.11737014 -38.50696388
OS 41.11737014 -38.50973756
OS 41.11737014 -38.5134358
OS 41.11644558 -38.51990772
OS 41.11552102 -38.52637964
OS 41.11459646 -38.53470068
OS 41.11274734 -38.54394628
OS 41.11089822 -38.55411644
OS 41.1044263 -38.57538132
OS 41.10072806 -38.58647604
OS 41.0951807 -38.59849532
OS 41.08870878 -38.6105146
OS 41.08223686 -38.62160932
OS 41.07391582 -38.63270404
OS 41.06467022 -38.64379876
OS 41.06374566 -38.64472332
OS 41.06189654 -38.64657244
OS 41.05912286 -38.64934612
OS 41.05450006 -38.6521198
OS 41.0489527 -38.6567426
OS 41.04155622 -38.6613654
OS 41.03231062 -38.66691276
OS 41.02214046 -38.67153556
OS 41.01012118 -38.67708292
OS 40.99625278 -38.68263028
OS 40.98145982 -38.68725308
OS 40.96389318 -38.69095132
OS 40.94540198 -38.69464956
OS 40.92506166 -38.69742324
OS 40.90194766 -38.69927236
OS 40.8779091 -38.70019692
OS 40.71426198 -38.70019692
OS 40.71426198 -38.95999828
OS 40.62920246 -38.95999828
OS 40.62920246 -38.32020276
OS 40.8917775 -38.32020276
OS 40.9056459 -38.32112732
OE
OB 40.49791494 -38.98403684 I
OS 40.49791494 -38.9849614
OS 40.49791494 -38.98773508
OS 40.49791494 -38.99235788
OS 40.49791494 -38.99790524
OS 40.49699038 -39.00530172
OS 40.49699038 -39.0126982
OS 40.49514126 -39.0311894
OS 40.49236758 -39.05060516
OS 40.48866934 -39.07094548
OS 40.48312198 -39.08851212
OS 40.47942374 -39.09683316
OS 40.4757255 -39.10330508
OS 40.4757255 -39.10422964
OS 40.47480094 -39.1051542
OS 40.47017814 -39.109777
OS 40.46278166 -39.11717348
OS 40.45353606 -39.12549452
OS 40.44059222 -39.13381556
OS 40.42395014 -39.14028748
OS 40.40453438 -39.14583484
OS 40.39343966 -39.1467594
OS 40.38142038 -39.14768396
OS 40.37587302 -39.14768396
OS 40.37032566 -39.1467594
OS 40.36200462 -39.1467594
OS 40.35275902 -39.14583484
OS 40.34258886 -39.14398572
OS 40.32039942 -39.13843836
OS 40.33519238 -39.07187004
OS 40.33611694 -39.07187004
OS 40.33889062 -39.0727946
OS 40.34351342 -39.07371916
OS 40.34813622 -39.07464372
OS 40.3601555 -39.0774174
OS 40.36570286 -39.07834196
OS 40.37494846 -39.07834196
OS 40.37957126 -39.0774174
OS 40.38511862 -39.07649284
OS 40.39066598 -39.07464372
OS 40.39621334 -39.07094548
OS 40.40268526 -39.06724724
OS 40.40730806 -39.06169988
OS 40.40823262 -39.06077532
OS 40.40915718 -39.05800164
OS 40.4110063 -39.05337884
OS 40.41377998 -39.04598236
OS 40.4156291 -39.0358122
OS 40.41655366 -39.02841572
OS 40.41747822 -39.0219438
OS 40.41840278 -39.01362276
OS 40.41840278 -39.0034526
OS 40.41932734 -38.99328244
OS 40.41932734 -38.98218772
OS 40.41932734 -38.49586916
OS 40.49791494 -38.49586916
OS 40.49791494 -38.98403684
OE
OB 41.51770462 -38.3100326 I
OS 41.52602566 -38.31095716
OS 41.53619582 -38.31188172
OS 41.54636598 -38.31280628
OS 41.55838526 -38.31557996
OS 41.58334838 -38.32112732
OS 41.61108518 -38.32944836
OS 41.62495358 -38.33499572
OS 41.63789742 -38.34146764
OS 41.65084126 -38.34978868
OS 41.6637851 -38.35810972
OS 41.66470966 -38.35903428
OS 41.66655878 -38.35995884
OS 41.67025702 -38.36273252
OS 41.67487982 -38.36735532
OS 41.67950262 -38.37197812
OS 41.68597454 -38.37845004
OS 41.69244646 -38.38584652
OS 41.69984294 -38.393243
OS 41.70723942 -38.4024886
OS 41.7146359 -38.41358332
OS 41.72295694 -38.42467804
OS 41.73035342 -38.43669732
OS 41.73682534 -38.45056572
OS 41.74422182 -38.46443412
OS 41.74976918 -38.47922708
OS 41.75531654 -38.49586916
OS 41.67210614 -38.51528492
OS 41.67210614 -38.51436036
OS 41.67118158 -38.51251124
OS 41.66933246 -38.508813
OS 41.66748334 -38.5041902
OS 41.66563422 -38.49864284
OS 41.66286054 -38.49124636
OS 41.65546406 -38.4764534
OS 41.64621846 -38.45981132
OS 41.63512374 -38.44316924
OS 41.62125534 -38.42745172
OS 41.60646238 -38.41358332
OS 41.60461326 -38.4117342
OS 41.5990659 -38.40803596
OS 41.5898203 -38.40341316
OS 41.57780102 -38.39694124
OS 41.5620835 -38.39139388
OS 41.54451686 -38.38584652
OS 41.52325198 -38.38214828
OS 41.50013798 -38.38122372
OS 41.4927415 -38.38122372
OS 41.4881187 -38.38214828
OS 41.48164678 -38.38214828
OS 41.4742503 -38.38307284
OS 41.45668366 -38.38584652
OS 41.4372679 -38.38954476
OS 41.41692758 -38.39601668
OS 41.3956627 -38.40526228
OS 41.37624694 -38.41728156
OS 41.37532238 -38.41728156
OS 41.37439782 -38.41913068
OS 41.3679259 -38.42375348
OS 41.35960486 -38.43114996
OS 41.3494347 -38.44224468
OS 41.33741542 -38.45611308
OS 41.3263207 -38.4718306
OS 41.31615054 -38.49124636
OS 41.30690494 -38.51251124
OS 41.30690494 -38.5134358
OS 41.30598038 -38.51528492
OS 41.30505582 -38.5180586
OS 41.30413126 -38.5226814
OS 41.30228214 -38.52822876
OS 41.30043302 -38.53470068
OS 41.29765934 -38.5504182
OS 41.2939611 -38.5689094
OS 41.29026286 -38.58924972
OS 41.28841374 -38.61143916
OS 41.28748918 -38.63547772
OS 41.28748918 -38.63640228
OS 41.28748918 -38.63917596
OS 41.28748918 -38.64379876
OS 41.28748918 -38.64934612
OS 41.28841374 -38.65581804
OS 41.28841374 -38.66413908
OS 41.2893383 -38.67338468
OS 41.29026286 -38.68355484
OS 41.29303654 -38.70574428
OS 41.29765934 -38.72978284
OS 41.3032067 -38.7538214
OS 41.31060318 -38.77785996
OS 41.31060318 -38.77878452
OS 41.31152774 -38.78063364
OS 41.31337686 -38.78340732
OS 41.31522598 -38.78803012
OS 41.32077334 -38.79912484
OS 41.32909438 -38.81206868
OS 41.33926454 -38.82686164
OS 41.35220838 -38.84257916
OS 41.36700134 -38.85644756
OS 41.38456798 -38.8693914
OS 41.38549254 -38.8693914
OS 41.38734166 -38.87031596
OS 41.39011534 -38.87216508
OS 41.39381358 -38.8740142
OS 41.39843638 -38.87586332
OS 41.40398374 -38.878637
OS 41.41692758 -38.88418436
OS 41.43356966 -38.88973172
OS 41.45206086 -38.89435452
OS 41.47240118 -38.89805276
OS 41.49366606 -38.89897732
OS 41.50013798 -38.89897732
OS 41.50568534 -38.89805276
OS 41.51215726 -38.89805276
OS 41.51862918 -38.8971282
OS 41.53527126 -38.89342996
OS 41.55468702 -38.88880716
OS 41.57410278 -38.88141068
OS 41.5944431 -38.87124052
OS 41.60461326 -38.86569316
OS 41.61385886 -38.85829668
OS 41.61478342 -38.85737212
OS 41.61570798 -38.85644756
OS 41.61848166 -38.85367388
OS 41.6221799 -38.8509002
OS 41.62587814 -38.8462774
OS 41.63050094 -38.84073004
OS 41.6360483 -38.83518268
OS 41.6406711 -38.8277862
OS 41.64621846 -38.81946516
OS 41.65269038 -38.81021956
OS 41.65823774 -38.80097396
OS 41.6637851 -38.78987924
OS 41.6684079 -38.77785996
OS 41.6730307 -38.76491612
OS 41.6776535 -38.75104772
OS 41.68135174 -38.73625476
OS 41.76641126 -38.75751964
OS 41.76641126 -38.7584442
OS 41.7654867 -38.76214244
OS 41.76363758 -38.7676898
OS 41.7608639 -38.77508628
OS 41.75809022 -38.78340732
OS 41.75439198 -38.79357748
OS 41.74976918 -38.8046722
OS 41.74422182 -38.81669148
OS 41.73127798 -38.84257916
OS 41.7146359 -38.86846684
OS 41.70446574 -38.88141068
OS 41.69429558 -38.89435452
OS 41.68320086 -38.90544924
OS 41.67025702 -38.91654396
OS 41.66933246 -38.91746852
OS 41.66748334 -38.91931764
OS 41.66286054 -38.92116676
OS 41.65823774 -38.924865
OS 41.65084126 -38.9294878
OS 41.64344478 -38.9341106
OS 41.63327462 -38.9387334
OS 41.62310446 -38.9433562
OS 41.61108518 -38.94890356
OS 41.59814134 -38.95352636
OS 41.58427294 -38.95814916
OS 41.56947998 -38.96277196
OS 41.55376246 -38.9664702
OS 41.53712038 -38.96831932
OS 41.51955374 -38.97016844
OS 41.50106254 -38.971093
OS 41.49089238 -38.971093
OS 41.4834959 -38.97016844
OS 41.47517486 -38.97016844
OS 41.4650047 -38.96924388
OS 41.45390998 -38.96739476
OS 41.44096614 -38.96554564
OS 41.4141539 -38.96092284
OS 41.3864171 -38.95352636
OS 41.3586803 -38.9433562
OS 41.34573646 -38.93688428
OS 41.33279262 -38.9294878
OS 41.33186806 -38.92856324
OS 41.33001894 -38.92763868
OS 41.3263207 -38.924865
OS 41.32262246 -38.92116676
OS 41.3170751 -38.91746852
OS 41.31060318 -38.91192116
OS 41.3032067 -38.90544924
OS 41.29581022 -38.89805276
OS 41.28841374 -38.88973172
OS 41.2800927 -38.88141068
OS 41.26345062 -38.8601458
OS 41.2477331 -38.83518268
OS 41.2338647 -38.80744588
OS 41.2338647 -38.80652132
OS 41.23201558 -38.80374764
OS 41.23109102 -38.79912484
OS 41.22831734 -38.79357748
OS 41.22646822 -38.786181
OS 41.22369454 -38.7769354
OS 41.2199963 -38.76676524
OS 41.21722262 -38.75567052
OS 41.21444894 -38.74365124
OS 41.2107507 -38.72978284
OS 41.2061279 -38.70112148
OS 41.20242966 -38.66876188
OS 41.20058054 -38.63547772
OS 41.20058054 -38.63455316
OS 41.20058054 -38.63085492
OS 41.20058054 -38.62530756
OS 41.2015051 -38.61883564
OS 41.2015051 -38.60959004
OS 41.20242966 -38.60034444
OS 41.20335422 -38.58832516
OS 41.20520334 -38.57630588
OS 41.20982614 -38.54949364
OS 41.21629806 -38.51990772
OS 41.22554366 -38.4903218
OS 41.2384875 -38.46166044
OS 41.23941206 -38.46073588
OS 41.24033662 -38.4579622
OS 41.24218574 -38.45426396
OS 41.24588398 -38.44964116
OS 41.24958222 -38.44316924
OS 41.25420502 -38.43577276
OS 41.2662243 -38.41913068
OS 41.28194182 -38.40063948
OS 41.30043302 -38.38214828
OS 41.3216979 -38.36365708
OS 41.34666102 -38.34793956
OS 41.34758558 -38.347015
OS 41.35035926 -38.34609044
OS 41.3540575 -38.34424132
OS 41.3586803 -38.34146764
OS 41.36607678 -38.33869396
OS 41.37347326 -38.33592028
OS 41.38271886 -38.33222204
OS 41.39288902 -38.3285238
OS 41.40398374 -38.32482556
OS 41.41600302 -38.32112732
OS 41.4418907 -38.31557996
OS 41.47147662 -38.31095716
OS 41.5019871 -38.30910804
OS 41.5112327 -38.30910804
OS 41.51770462 -38.3100326
OE
OB 42.90454462 -39.1375138 I
OS 42.38401734 -39.1375138
OS 42.38401734 -39.08111564
OS 42.90454462 -39.08111564
OS 42.90454462 -39.1375138
OE
OB 42.12514054 -38.32112732 I
OS 42.13253702 -38.32112732
OS 42.1491791 -38.32297644
OS 42.1676703 -38.32482556
OS 42.18708606 -38.3285238
OS 42.20650182 -38.3331466
OS 42.22406846 -38.33961852
OS 42.22499302 -38.33961852
OS 42.22591758 -38.34054308
OS 42.23146494 -38.34331676
OS 42.23978598 -38.34793956
OS 42.24903158 -38.35441148
OS 42.2601263 -38.36273252
OS 42.27214558 -38.37290268
OS 42.2832403 -38.38584652
OS 42.29341046 -38.39971492
OS 42.29433502 -38.40156404
OS 42.2971087 -38.4071114
OS 42.3017315 -38.41450788
OS 42.3063543 -38.4256026
OS 42.3109771 -38.43854644
OS 42.3155999 -38.45241484
OS 42.31837358 -38.46813236
OS 42.31929814 -38.48384988
OS 42.31929814 -38.485699
OS 42.31929814 -38.4903218
OS 42.31837358 -38.49864284
OS 42.31652446 -38.508813
OS 42.31375078 -38.52083228
OS 42.30912798 -38.53377612
OS 42.30358062 -38.54671996
OS 42.29618414 -38.56058836
OS 42.29525958 -38.56243748
OS 42.2924859 -38.56613572
OS 42.28693854 -38.5735322
OS 42.27954206 -38.58092868
OS 42.27029646 -38.59017428
OS 42.25920174 -38.60034444
OS 42.24533334 -38.60959004
OS 42.22961582 -38.61883564
OS 42.23054038 -38.61883564
OS 42.2323895 -38.6197602
OS 42.23516318 -38.62068476
OS 42.23886142 -38.62253388
OS 42.24995614 -38.62623212
OS 42.26289998 -38.63270404
OS 42.27676838 -38.64102508
OS 42.2924859 -38.65119524
OS 42.3063543 -38.66321452
OS 42.31929814 -38.67800748
OS 42.3202227 -38.6798566
OS 42.32392094 -38.68540396
OS 42.3294683 -38.693725
OS 42.33501566 -38.70481972
OS 42.34056302 -38.71961268
OS 42.34611038 -38.7353302
OS 42.34980862 -38.7538214
OS 42.35073318 -38.77416172
OS 42.35073318 -38.77508628
OS 42.35073318 -38.77601084
OS 42.35073318 -38.7815582
OS 42.34980862 -38.7908038
OS 42.3479595 -38.80189852
OS 42.34611038 -38.81484236
OS 42.34241214 -38.82871076
OS 42.33778934 -38.84350372
OS 42.33131742 -38.85829668
OS 42.33039286 -38.8601458
OS 42.32761918 -38.8647686
OS 42.32392094 -38.87124052
OS 42.31837358 -38.88048612
OS 42.3109771 -38.88973172
OS 42.30358062 -38.89990188
OS 42.29433502 -38.91007204
OS 42.28416486 -38.91839308
OS 42.2832403 -38.91931764
OS 42.27954206 -38.92209132
OS 42.27307014 -38.92578956
OS 42.2647491 -38.9294878
OS 42.25457894 -38.93503516
OS 42.24255966 -38.94058252
OS 42.22961582 -38.94520532
OS 42.2138983 -38.94982812
OS 42.21204918 -38.94982812
OS 42.20650182 -38.95167724
OS 42.19725622 -38.9526018
OS 42.18523694 -38.95445092
OS 42.17044398 -38.95630004
OS 42.15287734 -38.95814916
OS 42.13346158 -38.95907372
OS 42.11127214 -38.95999828
OS 41.8671883 -38.95999828
OS 41.8671883 -38.32020276
OS 42.11866862 -38.32020276
OS 42.12514054 -38.32112732
OE
OB 40.30745558 -38.48662356 I
OS 40.31762574 -38.48847268
OS 40.32964502 -38.49217092
OS 40.34258886 -38.49679372
OS 40.35738182 -38.50326564
OS 40.37309934 -38.51158668
OS 40.34443798 -38.58370236
OS 40.34351342 -38.5827778
OS 40.33981518 -38.58092868
OS 40.33426782 -38.578155
OS 40.32687134 -38.57538132
OS 40.3185503 -38.57260764
OS 40.30838014 -38.56983396
OS 40.29820998 -38.56798484
OS 40.28803982 -38.56706028
OS 40.28341702 -38.56706028
OS 40.27879422 -38.56798484
OS 40.2723223 -38.5689094
OS 40.26585038 -38.57075852
OS 40.25752934 -38.5735322
OS 40.2492083 -38.57723044
OS 40.24181182 -38.5827778
OS 40.24088726 -38.58370236
OS 40.23811358 -38.58555148
OS 40.2353399 -38.58924972
OS 40.2307171 -38.59387252
OS 40.2260943 -38.60034444
OS 40.2214715 -38.60774092
OS 40.2168487 -38.61606196
OS 40.21315046 -38.62623212
OS 40.2122259 -38.62808124
OS 40.21130134 -38.6336286
OS 40.20945222 -38.64194964
OS 40.20667854 -38.65304436
OS 40.20390486 -38.66691276
OS 40.20205574 -38.68263028
OS 40.20113118 -38.69927236
OS 40.20020662 -38.71776356
OS 40.20020662 -38.95999828
OS 40.12161902 -38.95999828
OS 40.12161902 -38.49586916
OS 40.19281014 -38.49586916
OS 40.19281014 -38.56613572
OS 40.1937347 -38.56521116
OS 40.19743294 -38.55873924
OS 40.20205574 -38.5504182
OS 40.20945222 -38.54024804
OS 40.2168487 -38.53007788
OS 40.22516974 -38.51898316
OS 40.23349078 -38.50973756
OS 40.24181182 -38.50234108
OS 40.24273638 -38.50141652
OS 40.24551006 -38.4995674
OS 40.25105742 -38.49679372
OS 40.25660478 -38.49402004
OS 40.26400126 -38.49124636
OS 40.27324686 -38.48847268
OS 40.28249246 -38.48662356
OS 40.29266262 -38.485699
OS 40.29913454 -38.485699
OS 40.30745558 -38.48662356
OE
OB 39.48829542 -38.95999828 I
OS 39.3986131 -38.95999828
OS 39.3986131 -38.87031596
OS 39.48829542 -38.87031596
OS 39.48829542 -38.95999828
OE
OB 38.6404739 -38.95999828 I
OS 38.55171614 -38.95999828
OS 38.30393406 -38.32020276
OS 38.39639006 -38.32020276
OS 38.56281086 -38.78525644
OS 38.56281086 -38.786181
OS 38.56373542 -38.78803012
OS 38.56465998 -38.7908038
OS 38.5665091 -38.79450204
OS 38.56743366 -38.8000494
OS 38.56928278 -38.80559676
OS 38.57390558 -38.81946516
OS 38.57945294 -38.83518268
OS 38.5850003 -38.85274932
OS 38.59609502 -38.88973172
OS 38.59609502 -38.88880716
OS 38.59701958 -38.88695804
OS 38.59794414 -38.88418436
OS 38.5988687 -38.88048612
OS 38.60164238 -38.87031596
OS 38.60626518 -38.85644756
OS 38.61088798 -38.84073004
OS 38.61643534 -38.8231634
OS 38.62290726 -38.8046722
OS 38.63030374 -38.78525644
OS 38.80412102 -38.32020276
OS 38.8901051 -38.32020276
OS 38.6404739 -38.95999828
OE
OB 39.27564662 -38.42745172 I
OS 39.25438174 -38.54671996
OS 39.20538006 -38.54671996
OS 39.1859643 -38.42745172
OS 39.1859643 -38.32020276
OS 39.27564662 -38.32020276
OS 39.27564662 -38.42745172
OE
OB 40.49791494 -38.4117342 I
OS 40.41932734 -38.4117342
OS 40.41932734 -38.32020276
OS 40.49791494 -38.32020276
OS 40.49791494 -38.4117342
OE
OB 39.84517558 -38.48662356 I
OS 39.8516475 -38.48754812
OS 39.8655159 -38.48939724
OS 39.88215798 -38.49309548
OS 39.89972462 -38.49864284
OS 39.91729126 -38.50696388
OS 39.9348579 -38.51713404
OS 39.93578246 -38.51713404
OS 39.93670702 -38.51898316
OS 39.94225438 -38.5226814
OS 39.95057542 -38.53007788
OS 39.96074558 -38.53932348
OS 39.9718403 -38.55134276
OS 39.98293502 -38.56613572
OS 39.99402974 -38.58370236
OS 40.00327534 -38.60311812
OS 40.00327534 -38.60404268
OS 40.0041999 -38.6058918
OS 40.00512446 -38.60866548
OS 40.00697358 -38.61236372
OS 40.0088227 -38.61791108
OS 40.01067182 -38.624383
OS 40.01529462 -38.63917596
OS 40.01991742 -38.65766716
OS 40.02361566 -38.67800748
OS 40.02638934 -38.70112148
OS 40.0273139 -38.72516004
OS 40.0273139 -38.7260846
OS 40.0273139 -38.72793372
OS 40.0273139 -38.73163196
OS 40.0273139 -38.73717932
OS 40.02638934 -38.74365124
OS 40.02638934 -38.75104772
OS 40.02454022 -38.7676898
OS 40.02084198 -38.78803012
OS 40.01621918 -38.809295
OS 40.00974726 -38.83148444
OS 40.00142622 -38.85367388
OS 40.00142622 -38.85459844
OS 40.00050166 -38.85644756
OS 39.99865254 -38.85922124
OS 39.99680342 -38.86291948
OS 39.9903315 -38.87308964
OS 39.98201046 -38.88603348
OS 39.9718403 -38.89990188
OS 39.95889646 -38.91377028
OS 39.9441035 -38.92763868
OS 39.92653686 -38.94058252
OS 39.9256123 -38.94058252
OS 39.92468774 -38.94150708
OS 39.92191406 -38.9433562
OS 39.91821582 -38.94520532
OS 39.90897022 -38.94982812
OS 39.89602638 -38.95537548
OS 39.88030886 -38.96092284
OS 39.86366678 -38.96554564
OS 39.84425102 -38.96924388
OS 39.82483526 -38.97016844
OS 39.81836334 -38.97016844
OS 39.81096686 -38.96924388
OS 39.80172126 -38.96831932
OS 39.79062654 -38.9664702
OS 39.77860726 -38.96369652
OS 39.76658798 -38.95999828
OS 39.7545687 -38.95445092
OS 39.75364414 -38.95352636
OS 39.74902134 -38.95167724
OS 39.74347398 -38.947979
OS 39.7360775 -38.94243164
OS 39.72868102 -38.93688428
OS 39.71943542 -38.9294878
OS 39.71111438 -38.92116676
OS 39.7037179 -38.91192116
OS 39.7037179 -39.1375138
OS 39.6251303 -39.1375138
OS 39.6251303 -38.49586916
OS 39.69632142 -38.49586916
OS 39.69632142 -38.55689012
OS 39.69724598 -38.555041
OS 39.70094422 -38.55134276
OS 39.70556702 -38.54487084
OS 39.7129635 -38.53747436
OS 39.72128454 -38.52822876
OS 39.73053014 -38.51990772
OS 39.74162486 -38.51158668
OS 39.75271958 -38.5041902
OS 39.7545687 -38.50326564
OS 39.75826694 -38.50141652
OS 39.76566342 -38.49864284
OS 39.77490902 -38.4949446
OS 39.78600374 -38.49124636
OS 39.79894758 -38.48847268
OS 39.81374054 -38.48662356
OS 39.83038262 -38.485699
OS 39.84055278 -38.485699
OS 39.84517558 -38.48662356
OE
OB 44.92193454 -38.40988508 I
OS 44.84334694 -38.40988508
OS 44.84334694 -38.32020276
OS 44.92193454 -38.32020276
OS 44.92193454 -38.40988508
OE
OB 45.24553054 -38.48662356 I
OS 45.25385158 -38.48754812
OS 45.26309718 -38.48939724
OS 45.27326734 -38.49124636
OS 45.28528662 -38.49309548
OS 45.31024974 -38.50141652
OS 45.32319358 -38.50603932
OS 45.33613742 -38.51251124
OS 45.34908126 -38.51898316
OS 45.3620251 -38.52822876
OS 45.37404438 -38.53747436
OS 45.38606366 -38.54856908
OS 45.38698822 -38.54949364
OS 45.38883734 -38.55134276
OS 45.39161102 -38.555041
OS 45.39530926 -38.5596638
OS 45.39993206 -38.56613572
OS 45.40547942 -38.57445676
OS 45.41102678 -38.58370236
OS 45.41657414 -38.59387252
OS 45.4221215 -38.60496724
OS 45.42766886 -38.61883564
OS 45.43321622 -38.63270404
OS 45.43783902 -38.64842156
OS 45.44153726 -38.66506364
OS 45.44431094 -38.68263028
OS 45.44616006 -38.70112148
OS 45.44708462 -38.7214618
OS 45.44708462 -38.72238636
OS 45.44708462 -38.72516004
OS 45.44708462 -38.72978284
OS 45.44708462 -38.73625476
OS 45.44616006 -38.74365124
OS 45.4452355 -38.75289684
OS 45.4452355 -38.76214244
OS 45.44338638 -38.7723126
OS 45.4406127 -38.7954266
OS 45.43506534 -38.8185406
OS 45.42859342 -38.8416546
OS 45.41934782 -38.86291948
OS 45.41934782 -38.86384404
OS 45.41842326 -38.8647686
OS 45.41657414 -38.86754228
OS 45.41472502 -38.87124052
OS 45.4082531 -38.88048612
OS 45.39993206 -38.89158084
OS 45.38883734 -38.90452468
OS 45.37496894 -38.91746852
OS 45.35925142 -38.93041236
OS 45.34076022 -38.94243164
OS 45.33983566 -38.94243164
OS 45.3389111 -38.9433562
OS 45.33613742 -38.94520532
OS 45.33151462 -38.94705444
OS 45.32689182 -38.94890356
OS 45.32134446 -38.95075268
OS 45.30747606 -38.95630004
OS 45.29175854 -38.96092284
OS 45.27234278 -38.96554564
OS 45.25200246 -38.96924388
OS 45.22981302 -38.97016844
OS 45.22056742 -38.97016844
OS 45.21317094 -38.96924388
OS 45.2048499 -38.96831932
OS 45.1956043 -38.9664702
OS 45.18450958 -38.96462108
OS 45.17341486 -38.96277196
OS 45.14845174 -38.95537548
OS 45.13458334 -38.94982812
OS 45.1216395 -38.94428076
OS 45.10869566 -38.93688428
OS 45.09575182 -38.92856324
OS 45.08373254 -38.91931764
OS 45.07171326 -38.90822292
OS 45.0707887 -38.90729836
OS 45.06893958 -38.90544924
OS 45.0661659 -38.901751
OS 45.06246766 -38.89620364
OS 45.05784486 -38.88973172
OS 45.05322206 -38.88233524
OS 45.0476747 -38.87308964
OS 45.04212734 -38.86199492
OS 45.03657998 -38.84997564
OS 45.03103262 -38.83610724
OS 45.02640982 -38.82131428
OS 45.02178702 -38.80559676
OS 45.01808878 -38.78803012
OS 45.0153151 -38.76953892
OS 45.01346598 -38.7491986
OS 45.01254142 -38.72793372
OS 45.01254142 -38.7260846
OS 45.01254142 -38.72238636
OS 45.01346598 -38.71591444
OS 45.01346598 -38.70666884
OS 45.01439054 -38.69649868
OS 45.01623966 -38.68355484
OS 45.01808878 -38.670611
OS 45.02178702 -38.65581804
OS 45.02548526 -38.64102508
OS 45.03010806 -38.62530756
OS 45.03565542 -38.60866548
OS 45.0430519 -38.59294796
OS 45.05044838 -38.578155
OS 45.06061854 -38.56336204
OS 45.0707887 -38.54949364
OS 45.08373254 -38.53747436
OS 45.0846571 -38.5365498
OS 45.08650622 -38.53562524
OS 45.09020446 -38.53285156
OS 45.09482726 -38.52915332
OS 45.10037462 -38.52545508
OS 45.1077711 -38.52083228
OS 45.11516758 -38.51620948
OS 45.12441318 -38.51158668
OS 45.13458334 -38.50696388
OS 45.14567806 -38.50234108
OS 45.17064118 -38.49402004
OS 45.19930254 -38.48754812
OS 45.2140955 -38.48662356
OS 45.22981302 -38.485699
OS 45.23905862 -38.485699
OS 45.24553054 -38.48662356
OE
OB 44.92193454 -38.95999828 I
OS 44.84334694 -38.95999828
OS 44.84334694 -38.49586916
OS 44.92193454 -38.49586916
OS 44.92193454 -38.95999828
OE
OB 46.10722046 -38.42745172 I
OS 46.08595558 -38.54671996
OS 46.0369539 -38.54671996
OS 46.01753814 -38.42745172
OS 46.01753814 -38.32020276
OS 46.10722046 -38.32020276
OS 46.10722046 -38.42745172
OE
OB 45.77160518 -38.48662356 I
OS 45.78177534 -38.48754812
OS 45.79379462 -38.48939724
OS 45.80673846 -38.49217092
OS 45.82060686 -38.49586916
OS 45.8335507 -38.50141652
OS 45.83539982 -38.50234108
OS 45.83909806 -38.5041902
OS 45.84556998 -38.50696388
OS 45.85296646 -38.51158668
OS 45.86221206 -38.51713404
OS 45.8705331 -38.52453052
OS 45.87885414 -38.531927
OS 45.88625062 -38.5411726
OS 45.88717518 -38.54209716
OS 45.8890243 -38.5457954
OS 45.89179798 -38.5504182
OS 45.89642078 -38.55689012
OS 45.90011902 -38.56613572
OS 45.90381726 -38.57538132
OS 45.90844006 -38.58647604
OS 45.91121374 -38.59849532
OS 45.91121374 -38.59941988
OS 45.9121383 -38.60311812
OS 45.91306286 -38.60866548
OS 45.91398742 -38.61606196
OS 45.91398742 -38.62715668
OS 45.91491198 -38.64010052
OS 45.91583654 -38.65581804
OS 45.91583654 -38.6752338
OS 45.91583654 -38.95999828
OS 45.83724894 -38.95999828
OS 45.83724894 -38.67893204
OS 45.83724894 -38.67800748
OS 45.83724894 -38.67708292
OS 45.83724894 -38.670611
OS 45.83724894 -38.66228996
OS 45.83632438 -38.6521198
OS 45.83539982 -38.64010052
OS 45.8335507 -38.62808124
OS 45.83077702 -38.61698652
OS 45.82800334 -38.60681636
OS 45.82800334 -38.6058918
OS 45.82615422 -38.60311812
OS 45.82338054 -38.59849532
OS 45.82060686 -38.59294796
OS 45.81598406 -38.5874006
OS 45.8104367 -38.58092868
OS 45.80304022 -38.57445676
OS 45.79471918 -38.5689094
OS 45.79379462 -38.56798484
OS 45.79102094 -38.56613572
OS 45.78547358 -38.5642866
OS 45.77900166 -38.56151292
OS 45.77160518 -38.55873924
OS 45.76235958 -38.55596556
OS 45.75126486 -38.555041
OS 45.74017014 -38.55411644
OS 45.73554734 -38.55411644
OS 45.7318491 -38.555041
OS 45.7226035 -38.55596556
OS 45.71058422 -38.55781468
OS 45.69764038 -38.56243748
OS 45.68284742 -38.56798484
OS 45.66805446 -38.57538132
OS 45.65418606 -38.58647604
OS 45.65233694 -38.58832516
OS 45.6486387 -38.59294796
OS 45.64586502 -38.5966462
OS 45.64309134 -38.601269
OS 45.6393931 -38.60681636
OS 45.63661942 -38.61328828
OS 45.63292118 -38.62068476
OS 45.62922294 -38.62993036
OS 45.62644926 -38.64010052
OS 45.62367558 -38.65119524
OS 45.62182646 -38.66321452
OS 45.61997734 -38.67615836
OS 45.61812822 -38.69187588
OS 45.61812822 -38.7075934
OS 45.61812822 -38.95999828
OS 45.53954062 -38.95999828
OS 45.53954062 -38.49586916
OS 45.60980718 -38.49586916
OS 45.60980718 -38.56243748
OS 45.61073174 -38.56151292
OS 45.61258086 -38.55873924
OS 45.61535454 -38.555041
OS 45.61905278 -38.5504182
OS 45.62460014 -38.54487084
OS 45.63107206 -38.53839892
OS 45.63846854 -38.53100244
OS 45.64771414 -38.52360596
OS 45.65695974 -38.51713404
OS 45.66805446 -38.50973756
OS 45.68007374 -38.50326564
OS 45.69301758 -38.49771828
OS 45.70781054 -38.49309548
OS 45.7226035 -38.48939724
OS 45.73924558 -38.48662356
OS 45.75681222 -38.485699
OS 45.7642087 -38.485699
OS 45.77160518 -38.48662356
OE
OB 44.2756671 -38.95999828 I
OS 44.1970795 -38.95999828
OS 44.1970795 -38.49586916
OS 44.2756671 -38.49586916
OS 44.2756671 -38.95999828
OE
OB 43.4574315 -38.48662356 I
OS 43.46482798 -38.48754812
OS 43.47407358 -38.48939724
OS 43.48424374 -38.49124636
OS 43.49626302 -38.49402004
OS 43.50735774 -38.49679372
OS 43.52030158 -38.50141652
OS 43.53232086 -38.50603932
OS 43.5452647 -38.51251124
OS 43.55820854 -38.51990772
OS 43.57115238 -38.52822876
OS 43.58317166 -38.53839892
OS 43.59426638 -38.54949364
OS 43.59519094 -38.5504182
OS 43.59704006 -38.55226732
OS 43.59981374 -38.55596556
OS 43.60351198 -38.56151292
OS 43.60813478 -38.56798484
OS 43.61275758 -38.57538132
OS 43.61830494 -38.58462692
OS 43.6238523 -38.59572164
OS 43.62939966 -38.60774092
OS 43.63494702 -38.62068476
OS 43.63956982 -38.63547772
OS 43.64419262 -38.65119524
OS 43.64789086 -38.66876188
OS 43.65066454 -38.68725308
OS 43.65251366 -38.70666884
OS 43.65343822 -38.72793372
OS 43.65343822 -38.72885828
OS 43.65343822 -38.73255652
OS 43.65343822 -38.73902844
OS 43.65251366 -38.74827404
OS 43.30580366 -38.74827404
OS 43.30580366 -38.7491986
OS 43.30580366 -38.75197228
OS 43.30672822 -38.75567052
OS 43.30672822 -38.76121788
OS 43.30765278 -38.7676898
OS 43.3095019 -38.77508628
OS 43.31227558 -38.79172836
OS 43.31782294 -38.81021956
OS 43.32521942 -38.83055988
OS 43.33538958 -38.84905108
OS 43.34833342 -38.86569316
OS 43.34925798 -38.86569316
OS 43.35018254 -38.86754228
OS 43.3557299 -38.87216508
OS 43.36405094 -38.878637
OS 43.37514566 -38.88510892
OS 43.38993862 -38.8925054
OS 43.4065807 -38.89897732
OS 43.4250719 -38.90360012
OS 43.43524206 -38.90452468
OS 43.44633678 -38.90544924
OS 43.45373326 -38.90544924
OS 43.4620543 -38.90452468
OS 43.47222446 -38.90267556
OS 43.48331918 -38.89990188
OS 43.49626302 -38.89620364
OS 43.5082823 -38.89065628
OS 43.52030158 -38.8832598
OS 43.52122614 -38.88233524
OS 43.52584894 -38.878637
OS 43.5313963 -38.87308964
OS 43.53786822 -38.86569316
OS 43.5452647 -38.855523
OS 43.55358574 -38.84257916
OS 43.56190678 -38.8277862
OS 43.56930326 -38.81021956
OS 43.65066454 -38.82038972
OS 43.65066454 -38.82131428
OS 43.64973998 -38.8231634
OS 43.64881542 -38.82686164
OS 43.6469663 -38.832409
OS 43.64419262 -38.83795636
OS 43.64141894 -38.84535284
OS 43.63402246 -38.86107036
OS 43.62477686 -38.878637
OS 43.61183302 -38.8971282
OS 43.59704006 -38.91469484
OS 43.57854886 -38.93133692
OS 43.5776243 -38.93133692
OS 43.57577518 -38.93318604
OS 43.5730015 -38.93503516
OS 43.56930326 -38.93780884
OS 43.5637559 -38.94058252
OS 43.55820854 -38.9433562
OS 43.55081206 -38.94705444
OS 43.54249102 -38.95075268
OS 43.53324542 -38.95445092
OS 43.52399982 -38.95814916
OS 43.50088582 -38.96369652
OS 43.47499814 -38.96831932
OS 43.44633678 -38.97016844
OS 43.43616662 -38.97016844
OS 43.4296947 -38.96924388
OS 43.42137366 -38.96831932
OS 43.4112035 -38.9664702
OS 43.40010878 -38.96462108
OS 43.3880895 -38.96277196
OS 43.36220182 -38.95537548
OS 43.34833342 -38.94982812
OS 43.33538958 -38.94428076
OS 43.32152118 -38.93688428
OS 43.30857734 -38.92856324
OS 43.29655806 -38.91931764
OS 43.28453878 -38.90822292
OS 43.28361422 -38.90729836
OS 43.2817651 -38.90544924
OS 43.27899142 -38.901751
OS 43.27529318 -38.89620364
OS 43.27067038 -38.88973172
OS 43.26604758 -38.88233524
OS 43.26050022 -38.87308964
OS 43.25495286 -38.86291948
OS 43.2494055 -38.8509002
OS 43.24385814 -38.83795636
OS 43.23923534 -38.8231634
OS 43.23461254 -38.80744588
OS 43.2309143 -38.7908038
OS 43.22814062 -38.7723126
OS 43.2262915 -38.75289684
OS 43.22536694 -38.73255652
OS 43.22536694 -38.73163196
OS 43.22536694 -38.72700916
OS 43.22536694 -38.7214618
OS 43.2262915 -38.71314076
OS 43.22721606 -38.7029706
OS 43.22814062 -38.69187588
OS 43.22998974 -38.67893204
OS 43.23276342 -38.6659882
OS 43.2401599 -38.63640228
OS 43.2447827 -38.62160932
OS 43.25033006 -38.6058918
OS 43.25772654 -38.59109884
OS 43.26604758 -38.57723044
OS 43.27529318 -38.56336204
OS 43.28546334 -38.5504182
OS 43.2863879 -38.54949364
OS 43.28823702 -38.54764452
OS 43.29193526 -38.54487084
OS 43.29655806 -38.54024804
OS 43.30210542 -38.53562524
OS 43.3095019 -38.53007788
OS 43.31782294 -38.52360596
OS 43.3279931 -38.5180586
OS 43.33816326 -38.51158668
OS 43.35018254 -38.50603932
OS 43.36312638 -38.50049196
OS 43.37699478 -38.49586916
OS 43.39178774 -38.49124636
OS 43.40750526 -38.48847268
OS 43.42414734 -38.48662356
OS 43.44171398 -38.485699
OS 43.45095958 -38.485699
OS 43.4574315 -38.48662356
OE
OB 43.13938286 -38.48662356 I
OS 43.14955302 -38.48847268
OS 43.1615723 -38.49217092
OS 43.17451614 -38.49679372
OS 43.1893091 -38.50326564
OS 43.20502662 -38.51158668
OS 43.17636526 -38.58370236
OS 43.1754407 -38.5827778
OS 43.17174246 -38.58092868
OS 43.1661951 -38.578155
OS 43.15879862 -38.57538132
OS 43.15047758 -38.57260764
OS 43.14030742 -38.56983396
OS 43.13013726 -38.56798484
OS 43.1199671 -38.56706028
OS 43.1153443 -38.56706028
OS 43.1107215 -38.56798484
OS 43.10424958 -38.5689094
OS 43.09777766 -38.57075852
OS 43.08945662 -38.5735322
OS 43.08113558 -38.57723044
OS 43.0737391 -38.5827778
OS 43.07281454 -38.58370236
OS 43.07004086 -38.58555148
OS 43.06726718 -38.58924972
OS 43.06264438 -38.59387252
OS 43.05802158 -38.60034444
OS 43.05339878 -38.60774092
OS 43.04877598 -38.61606196
OS 43.04507774 -38.62623212
OS 43.04415318 -38.62808124
OS 43.04322862 -38.6336286
OS 43.0413795 -38.64194964
OS 43.03860582 -38.65304436
OS 43.03583214 -38.66691276
OS 43.03398302 -38.68263028
OS 43.03305846 -38.69927236
OS 43.0321339 -38.71776356
OS 43.0321339 -38.95999828
OS 42.9535463 -38.95999828
OS 42.9535463 -38.49586916
OS 43.02473742 -38.49586916
OS 43.02473742 -38.56613572
OS 43.02566198 -38.56521116
OS 43.02936022 -38.55873924
OS 43.03398302 -38.5504182
OS 43.0413795 -38.54024804
OS 43.04877598 -38.53007788
OS 43.05709702 -38.51898316
OS 43.06541806 -38.50973756
OS 43.0737391 -38.50234108
OS 43.07466366 -38.50141652
OS 43.07743734 -38.4995674
OS 43.0829847 -38.49679372
OS 43.08853206 -38.49402004
OS 43.09592854 -38.49124636
OS 43.10517414 -38.48847268
OS 43.11441974 -38.48662356
OS 43.1245899 -38.485699
OS 43.13106182 -38.485699
OS 43.13938286 -38.48662356
OE
OB 43.95022198 -38.95999828 I
OS 43.87533262 -38.95999828
OS 43.70059078 -38.49586916
OS 43.78380118 -38.49586916
OS 43.88365366 -38.77416172
OS 43.88365366 -38.77508628
OS 43.88457822 -38.77601084
OS 43.88550278 -38.77878452
OS 43.88642734 -38.7815582
OS 43.88920102 -38.7908038
OS 43.89289926 -38.80282308
OS 43.89752206 -38.81669148
OS 43.90306942 -38.832409
OS 43.90769222 -38.84997564
OS 43.91323958 -38.86754228
OS 43.91416414 -38.86569316
OS 43.9150887 -38.86107036
OS 43.91786238 -38.85367388
OS 43.92063606 -38.84257916
OS 43.92525886 -38.83055988
OS 43.92988166 -38.81484236
OS 43.93635358 -38.79820028
OS 43.9428255 -38.77970908
OS 44.04545166 -38.49586916
OS 44.12681294 -38.49586916
OS 43.95022198 -38.95999828
OE
OB 44.2756671 -38.40988508 I
OS 44.1970795 -38.40988508
OS 44.1970795 -38.32020276
OS 44.2756671 -38.32020276
OS 44.2756671 -38.40988508
OE
OB 44.5669035 -38.48662356 I
OS 44.5807719 -38.48754812
OS 44.59556486 -38.48939724
OS 44.61128238 -38.49309548
OS 44.62792446 -38.49679372
OS 44.64364198 -38.50234108
OS 44.64456654 -38.50234108
OS 44.6454911 -38.50326564
OS 44.6501139 -38.50511476
OS 44.65751038 -38.508813
OS 44.66675598 -38.5134358
OS 44.67692614 -38.51990772
OS 44.6870963 -38.5273042
OS 44.6963419 -38.53562524
OS 44.70466294 -38.54487084
OS 44.7055875 -38.5457954
OS 44.70743662 -38.54949364
OS 44.71113486 -38.55596556
OS 44.71575766 -38.56336204
OS 44.72038046 -38.57445676
OS 44.72500326 -38.58647604
OS 44.7287015 -38.60034444
OS 44.73239974 -38.61606196
OS 44.65566126 -38.62623212
OS 44.65566126 -38.624383
OS 44.6547367 -38.62068476
OS 44.65288758 -38.61421284
OS 44.6501139 -38.6058918
OS 44.6454911 -38.59757076
OS 44.63994374 -38.58832516
OS 44.63347182 -38.57907956
OS 44.62422622 -38.57075852
OS 44.62330166 -38.56983396
OS 44.61960342 -38.56798484
OS 44.61405606 -38.5642866
OS 44.60573502 -38.56058836
OS 44.59648942 -38.55689012
OS 44.58447014 -38.55319188
OS 44.56967718 -38.55134276
OS 44.55395966 -38.5504182
OS 44.54471406 -38.5504182
OS 44.53546846 -38.55134276
OS 44.52344918 -38.55226732
OS 44.5114299 -38.555041
OS 44.49848606 -38.55781468
OS 44.48646678 -38.56243748
OS 44.47629662 -38.5689094
OS 44.47537206 -38.56983396
OS 44.47259838 -38.57168308
OS 44.46890014 -38.57538132
OS 44.4652019 -38.58092868
OS 44.4605791 -38.58647604
OS 44.45688086 -38.59387252
OS 44.45410718 -38.60219356
OS 44.45318262 -38.6105146
OS 44.45318262 -38.61143916
OS 44.45318262 -38.61328828
OS 44.45410718 -38.61606196
OS 44.45410718 -38.6197602
OS 44.45688086 -38.6290058
OS 44.46242822 -38.6382514
OS 44.46335278 -38.63917596
OS 44.46427734 -38.64010052
OS 44.46612646 -38.6428742
OS 44.4698247 -38.64564788
OS 44.47352294 -38.64842156
OS 44.4790703 -38.6521198
OS 44.48554222 -38.65489348
OS 44.4929387 -38.65859172
OS 44.49386326 -38.65859172
OS 44.49571238 -38.65951628
OS 44.49941062 -38.66044084
OS 44.50588254 -38.66321452
OS 44.51512814 -38.6659882
OS 44.52714742 -38.66876188
OS 44.5345439 -38.67153556
OS 44.54286494 -38.67338468
OS 44.55211054 -38.67615836
OS 44.5622807 -38.67893204
OS 44.56320526 -38.67893204
OS 44.56597894 -38.6798566
OS 44.57060174 -38.68078116
OS 44.5761491 -38.68263028
OS 44.58262102 -38.6844794
OS 44.59094206 -38.68632852
OS 44.6085087 -38.69187588
OS 44.62792446 -38.69742324
OS 44.64734022 -38.70389516
OS 44.66490686 -38.71036708
OS 44.67230334 -38.71314076
OS 44.67877526 -38.71591444
OS 44.68062438 -38.716839
OS 44.68432262 -38.71868812
OS 44.68986998 -38.7214618
OS 44.69819102 -38.7260846
OS 44.70651206 -38.73163196
OS 44.7148331 -38.73902844
OS 44.72315414 -38.74734948
OS 44.73055062 -38.75659508
OS 44.73147518 -38.75751964
OS 44.7333243 -38.76121788
OS 44.73702254 -38.76676524
OS 44.74072078 -38.77508628
OS 44.74349446 -38.78525644
OS 44.7471927 -38.79635116
OS 44.74904182 -38.809295
OS 44.74996638 -38.82408796
OS 44.74996638 -38.82593708
OS 44.74996638 -38.83055988
OS 44.74904182 -38.83795636
OS 44.7471927 -38.84812652
OS 44.74441902 -38.85922124
OS 44.73979622 -38.87124052
OS 44.73424886 -38.88510892
OS 44.72685238 -38.89805276
OS 44.72592782 -38.89990188
OS 44.72222958 -38.90360012
OS 44.71760678 -38.91007204
OS 44.7102103 -38.91746852
OS 44.70004014 -38.92578956
OS 44.68894542 -38.93503516
OS 44.67600158 -38.9433562
OS 44.66028406 -38.95167724
OS 44.6593595 -38.95167724
OS 44.65843494 -38.9526018
OS 44.65288758 -38.95445092
OS 44.64364198 -38.9572246
OS 44.6316227 -38.96092284
OS 44.61682974 -38.96462108
OS 44.60018766 -38.96739476
OS 44.58262102 -38.96924388
OS 44.5622807 -38.97016844
OS 44.55395966 -38.97016844
OS 44.54748774 -38.96924388
OS 44.54009126 -38.96924388
OS 44.53084566 -38.96831932
OS 44.52160006 -38.96739476
OS 44.5114299 -38.96554564
OS 44.48924046 -38.96092284
OS 44.46612646 -38.95445092
OS 44.44393702 -38.94520532
OS 44.43376686 -38.93965796
OS 44.42452126 -38.93318604
OS 44.4235967 -38.93226148
OS 44.42267214 -38.93133692
OS 44.41712478 -38.92578956
OS 44.40880374 -38.91746852
OS 44.39955814 -38.90452468
OS 44.38938798 -38.88880716
OS 44.37921782 -38.87031596
OS 44.37089678 -38.84720196
OS 44.36442486 -38.82131428
OS 44.4420879 -38.809295
OS 44.4420879 -38.81021956
OS 44.4420879 -38.81114412
OS 44.44393702 -38.81669148
OS 44.44578614 -38.82593708
OS 44.44948438 -38.83610724
OS 44.45410718 -38.84720196
OS 44.45965454 -38.85922124
OS 44.46797558 -38.87124052
OS 44.47814574 -38.88141068
OS 44.47999486 -38.88233524
OS 44.4836931 -38.88510892
OS 44.49108958 -38.88880716
OS 44.50033518 -38.89342996
OS 44.51235446 -38.89805276
OS 44.52622286 -38.901751
OS 44.54286494 -38.90452468
OS 44.5622807 -38.90544924
OS 44.5715263 -38.90544924
OS 44.5807719 -38.90452468
OS 44.59279118 -38.90267556
OS 44.60573502 -38.89990188
OS 44.61960342 -38.89620364
OS 44.6316227 -38.89158084
OS 44.64271742 -38.88418436
OS 44.64364198 -38.8832598
OS 44.64734022 -38.88048612
OS 44.65103846 -38.87586332
OS 44.65658582 -38.8693914
OS 44.66120862 -38.86199492
OS 44.66583142 -38.85274932
OS 44.6686051 -38.84350372
OS 44.66952966 -38.832409
OS 44.66952966 -38.83148444
OS 44.66952966 -38.8277862
OS 44.6686051 -38.8231634
OS 44.66675598 -38.81669148
OS 44.6639823 -38.81021956
OS 44.6593595 -38.80374764
OS 44.65381214 -38.79635116
OS 44.6454911 -38.7908038
OS 44.64456654 -38.78987924
OS 44.64179286 -38.78895468
OS 44.63717006 -38.786181
OS 44.62977358 -38.78340732
OS 44.61867886 -38.77970908
OS 44.61220694 -38.7769354
OS 44.60481046 -38.77508628
OS 44.59648942 -38.7723126
OS 44.58724382 -38.76953892
OS 44.57707366 -38.76676524
OS 44.56505438 -38.76399156
OS 44.56412982 -38.76399156
OS 44.56135614 -38.763067
OS 44.55673334 -38.76214244
OS 44.55118598 -38.76029332
OS 44.5437895 -38.7584442
OS 44.53546846 -38.75567052
OS 44.51790182 -38.75104772
OS 44.4975615 -38.7445758
OS 44.47814574 -38.73902844
OS 44.45965454 -38.73255652
OS 44.4513335 -38.72885828
OS 44.44486158 -38.7260846
OS 44.44301246 -38.72516004
OS 44.43931422 -38.72331092
OS 44.43376686 -38.71961268
OS 44.42637038 -38.71498988
OS 44.41804934 -38.70851796
OS 44.4097283 -38.70112148
OS 44.40140726 -38.69280044
OS 44.39401078 -38.68263028
OS 44.39308622 -38.68170572
OS 44.3912371 -38.67800748
OS 44.38846342 -38.67153556
OS 44.38568974 -38.66413908
OS 44.38291606 -38.65489348
OS 44.38014238 -38.64379876
OS 44.37829326 -38.63270404
OS 44.3773687 -38.6197602
OS 44.3773687 -38.61791108
OS 44.3773687 -38.61421284
OS 44.37829326 -38.60866548
OS 44.37921782 -38.60034444
OS 44.38106694 -38.5920234
OS 44.38291606 -38.58185324
OS 44.3866143 -38.57260764
OS 44.3912371 -38.56243748
OS 44.39216166 -38.56151292
OS 44.39401078 -38.55781468
OS 44.39678446 -38.55319188
OS 44.40140726 -38.54671996
OS 44.40695462 -38.54024804
OS 44.41342654 -38.531927
OS 44.42082302 -38.52453052
OS 44.43006862 -38.5180586
OS 44.43099318 -38.51713404
OS 44.43376686 -38.51620948
OS 44.4374651 -38.5134358
OS 44.44301246 -38.51066212
OS 44.45040894 -38.50696388
OS 44.45872998 -38.50326564
OS 44.46890014 -38.4995674
OS 44.47999486 -38.49586916
OS 44.48184398 -38.4949446
OS 44.48554222 -38.49402004
OS 44.49201414 -38.49217092
OS 44.50033518 -38.4903218
OS 44.51050534 -38.48847268
OS 44.52160006 -38.48754812
OS 44.5345439 -38.485699
OS 44.55673334 -38.485699
OS 44.5669035 -38.48662356
OE
OB 33.15968222 -38.32112732 I
OS 33.17539974 -38.32205188
OS 33.19204182 -38.32297644
OS 33.20775934 -38.32482556
OS 33.22162774 -38.32667468
OS 33.22347686 -38.32667468
OS 33.22994878 -38.3285238
OS 33.23826982 -38.33037292
OS 33.24936454 -38.3331466
OS 33.26138382 -38.3377694
OS 33.27432766 -38.34331676
OS 33.28819606 -38.34978868
OS 33.30021534 -38.35718516
OS 33.30206446 -38.35810972
OS 33.3057627 -38.3608834
OS 33.31131006 -38.36643076
OS 33.31870654 -38.37290268
OS 33.32702758 -38.38122372
OS 33.33534862 -38.39231844
OS 33.34459422 -38.40433772
OS 33.3519907 -38.41820612
OS 33.35291526 -38.42005524
OS 33.35476438 -38.42467804
OS 33.35846262 -38.43299908
OS 33.36216086 -38.4440938
OS 33.36493454 -38.45703764
OS 33.36863278 -38.4718306
OS 33.3704819 -38.48847268
OS 33.37140646 -38.50603932
OS 33.37140646 -38.50696388
OS 33.37140646 -38.50973756
OS 33.37140646 -38.5134358
OS 33.3704819 -38.51990772
OS 33.36955734 -38.52637964
OS 33.36863278 -38.53470068
OS 33.36678366 -38.54394628
OS 33.36493454 -38.55411644
OS 33.35846262 -38.57538132
OS 33.35476438 -38.58647604
OS 33.34921702 -38.59849532
OS 33.3427451 -38.6105146
OS 33.33627318 -38.62160932
OS 33.32795214 -38.63270404
OS 33.31870654 -38.64379876
OS 33.31778198 -38.64472332
OS 33.31593286 -38.64657244
OS 33.31315918 -38.64934612
OS 33.30853638 -38.6521198
OS 33.30298902 -38.6567426
OS 33.29559254 -38.6613654
OS 33.28634694 -38.66691276
OS 33.27617678 -38.67153556
OS 33.2641575 -38.67708292
OS 33.2502891 -38.68263028
OS 33.23549614 -38.68725308
OS 33.2179295 -38.69095132
OS 33.1994383 -38.69464956
OS 33.17909798 -38.69742324
OS 33.15598398 -38.69927236
OS 33.13194542 -38.70019692
OS 32.9682983 -38.70019692
OS 32.9682983 -38.95999828
OS 32.88323878 -38.95999828
OS 32.88323878 -38.32020276
OS 33.14581382 -38.32020276
OS 33.15968222 -38.32112732
OE
OB 32.75195126 -38.98403684 I
OS 32.75195126 -38.9849614
OS 32.75195126 -38.98773508
OS 32.75195126 -38.99235788
OS 32.75195126 -38.99790524
OS 32.7510267 -39.00530172
OS 32.7510267 -39.0126982
OS 32.74917758 -39.0311894
OS 32.7464039 -39.05060516
OS 32.74270566 -39.07094548
OS 32.7371583 -39.08851212
OS 32.73346006 -39.09683316
OS 32.72976182 -39.10330508
OS 32.72976182 -39.10422964
OS 32.72883726 -39.1051542
OS 32.72421446 -39.109777
OS 32.71681798 -39.11717348
OS 32.70757238 -39.12549452
OS 32.69462854 -39.13381556
OS 32.67798646 -39.14028748
OS 32.6585707 -39.14583484
OS 32.64747598 -39.1467594
OS 32.6354567 -39.14768396
OS 32.62990934 -39.14768396
OS 32.62436198 -39.1467594
OS 32.61604094 -39.1467594
OS 32.60679534 -39.14583484
OS 32.59662518 -39.14398572
OS 32.57443574 -39.13843836
OS 32.5892287 -39.07187004
OS 32.59015326 -39.07187004
OS 32.59292694 -39.0727946
OS 32.59754974 -39.07371916
OS 32.60217254 -39.07464372
OS 32.61419182 -39.0774174
OS 32.61973918 -39.07834196
OS 32.62898478 -39.07834196
OS 32.63360758 -39.0774174
OS 32.63915494 -39.07649284
OS 32.6447023 -39.07464372
OS 32.65024966 -39.07094548
OS 32.65672158 -39.06724724
OS 32.66134438 -39.06169988
OS 32.66226894 -39.06077532
OS 32.6631935 -39.05800164
OS 32.66504262 -39.05337884
OS 32.6678163 -39.04598236
OS 32.66966542 -39.0358122
OS 32.67058998 -39.02841572
OS 32.67151454 -39.0219438
OS 32.6724391 -39.01362276
OS 32.6724391 -39.0034526
OS 32.67336366 -38.99328244
OS 32.67336366 -38.98218772
OS 32.67336366 -38.49586916
OS 32.75195126 -38.49586916
OS 32.75195126 -38.98403684
OE
OB 33.77174094 -38.3100326 I
OS 33.78006198 -38.31095716
OS 33.79023214 -38.31188172
OS 33.8004023 -38.31280628
OS 33.81242158 -38.31557996
OS 33.8373847 -38.32112732
OS 33.8651215 -38.32944836
OS 33.8789899 -38.33499572
OS 33.89193374 -38.34146764
OS 33.90487758 -38.34978868
OS 33.91782142 -38.35810972
OS 33.91874598 -38.35903428
OS 33.9205951 -38.35995884
OS 33.92429334 -38.36273252
OS 33.92891614 -38.36735532
OS 33.93353894 -38.37197812
OS 33.94001086 -38.37845004
OS 33.94648278 -38.38584652
OS 33.95387926 -38.393243
OS 33.96127574 -38.4024886
OS 33.96867222 -38.41358332
OS 33.97699326 -38.42467804
OS 33.98438974 -38.43669732
OS 33.99086166 -38.45056572
OS 33.99825814 -38.46443412
OS 34.0038055 -38.47922708
OS 34.00935286 -38.49586916
OS 33.92614246 -38.51528492
OS 33.92614246 -38.51436036
OS 33.9252179 -38.51251124
OS 33.92336878 -38.508813
OS 33.92151966 -38.5041902
OS 33.91967054 -38.49864284
OS 33.91689686 -38.49124636
OS 33.90950038 -38.4764534
OS 33.90025478 -38.45981132
OS 33.88916006 -38.44316924
OS 33.87529166 -38.42745172
OS 33.8604987 -38.41358332
OS 33.85864958 -38.4117342
OS 33.85310222 -38.40803596
OS 33.84385662 -38.40341316
OS 33.83183734 -38.39694124
OS 33.81611982 -38.39139388
OS 33.79855318 -38.38584652
OS 33.7772883 -38.38214828
OS 33.7541743 -38.38122372
OS 33.74677782 -38.38122372
OS 33.74215502 -38.38214828
OS 33.7356831 -38.38214828
OS 33.72828662 -38.38307284
OS 33.71071998 -38.38584652
OS 33.69130422 -38.38954476
OS 33.6709639 -38.39601668
OS 33.64969902 -38.40526228
OS 33.63028326 -38.41728156
OS 33.6293587 -38.41728156
OS 33.62843414 -38.41913068
OS 33.62196222 -38.42375348
OS 33.61364118 -38.43114996
OS 33.60347102 -38.44224468
OS 33.59145174 -38.45611308
OS 33.58035702 -38.4718306
OS 33.57018686 -38.49124636
OS 33.56094126 -38.51251124
OS 33.56094126 -38.5134358
OS 33.5600167 -38.51528492
OS 33.55909214 -38.5180586
OS 33.55816758 -38.5226814
OS 33.55631846 -38.52822876
OS 33.55446934 -38.53470068
OS 33.55169566 -38.5504182
OS 33.54799742 -38.5689094
OS 33.54429918 -38.58924972
OS 33.54245006 -38.61143916
OS 33.5415255 -38.63547772
OS 33.5415255 -38.63640228
OS 33.5415255 -38.63917596
OS 33.5415255 -38.64379876
OS 33.5415255 -38.64934612
OS 33.54245006 -38.65581804
OS 33.54245006 -38.66413908
OS 33.54337462 -38.67338468
OS 33.54429918 -38.68355484
OS 33.54707286 -38.70574428
OS 33.55169566 -38.72978284
OS 33.55724302 -38.7538214
OS 33.5646395 -38.77785996
OS 33.5646395 -38.77878452
OS 33.56556406 -38.78063364
OS 33.56741318 -38.78340732
OS 33.5692623 -38.78803012
OS 33.57480966 -38.79912484
OS 33.5831307 -38.81206868
OS 33.59330086 -38.82686164
OS 33.6062447 -38.84257916
OS 33.62103766 -38.85644756
OS 33.6386043 -38.8693914
OS 33.63952886 -38.8693914
OS 33.64137798 -38.87031596
OS 33.64415166 -38.87216508
OS 33.6478499 -38.8740142
OS 33.6524727 -38.87586332
OS 33.65802006 -38.878637
OS 33.6709639 -38.88418436
OS 33.68760598 -38.88973172
OS 33.70609718 -38.89435452
OS 33.7264375 -38.89805276
OS 33.74770238 -38.89897732
OS 33.7541743 -38.89897732
OS 33.75972166 -38.89805276
OS 33.76619358 -38.89805276
OS 33.7726655 -38.8971282
OS 33.78930758 -38.89342996
OS 33.80872334 -38.88880716
OS 33.8281391 -38.88141068
OS 33.84847942 -38.87124052
OS 33.85864958 -38.86569316
OS 33.86789518 -38.85829668
OS 33.86881974 -38.85737212
OS 33.8697443 -38.85644756
OS 33.87251798 -38.85367388
OS 33.87621622 -38.8509002
OS 33.87991446 -38.8462774
OS 33.88453726 -38.84073004
OS 33.89008462 -38.83518268
OS 33.89470742 -38.8277862
OS 33.90025478 -38.81946516
OS 33.9067267 -38.81021956
OS 33.91227406 -38.80097396
OS 33.91782142 -38.78987924
OS 33.92244422 -38.77785996
OS 33.92706702 -38.76491612
OS 33.93168982 -38.75104772
OS 33.93538806 -38.73625476
OS 34.02044758 -38.75751964
OS 34.02044758 -38.7584442
OS 34.01952302 -38.76214244
OS 34.0176739 -38.7676898
OS 34.01490022 -38.77508628
OS 34.01212654 -38.78340732
OS 34.0084283 -38.79357748
OS 34.0038055 -38.8046722
OS 33.99825814 -38.81669148
OS 33.9853143 -38.84257916
OS 33.96867222 -38.86846684
OS 33.95850206 -38.88141068
OS 33.9483319 -38.89435452
OS 33.93723718 -38.90544924
OS 33.92429334 -38.91654396
OS 33.92336878 -38.91746852
OS 33.92151966 -38.91931764
OS 33.91689686 -38.92116676
OS 33.91227406 -38.924865
OS 33.90487758 -38.9294878
OS 33.8974811 -38.9341106
OS 33.88731094 -38.9387334
OS 33.87714078 -38.9433562
OS 33.8651215 -38.94890356
OS 33.85217766 -38.95352636
OS 33.83830926 -38.95814916
OS 33.8235163 -38.96277196
OS 33.80779878 -38.9664702
OS 33.7911567 -38.96831932
OS 33.77359006 -38.97016844
OS 33.75509886 -38.971093
OS 33.7449287 -38.971093
OS 33.73753222 -38.97016844
OS 33.72921118 -38.97016844
OS 33.71904102 -38.96924388
OS 33.7079463 -38.96739476
OS 33.69500246 -38.96554564
OS 33.66819022 -38.96092284
OS 33.64045342 -38.95352636
OS 33.61271662 -38.9433562
OS 33.59977278 -38.93688428
OS 33.58682894 -38.9294878
OS 33.58590438 -38.92856324
OS 33.58405526 -38.92763868
OS 33.58035702 -38.924865
OS 33.57665878 -38.92116676
OS 33.57111142 -38.91746852
OS 33.5646395 -38.91192116
OS 33.55724302 -38.90544924
OS 33.54984654 -38.89805276
OS 33.54245006 -38.88973172
OS 33.53412902 -38.88141068
OS 33.51748694 -38.8601458
OS 33.50176942 -38.83518268
OS 33.48790102 -38.80744588
OS 33.48790102 -38.80652132
OS 33.4860519 -38.80374764
OS 33.48512734 -38.79912484
OS 33.48235366 -38.79357748
OS 33.48050454 -38.786181
OS 33.47773086 -38.7769354
OS 33.47403262 -38.76676524
OS 33.47125894 -38.75567052
OS 33.46848526 -38.74365124
OS 33.46478702 -38.72978284
OS 33.46016422 -38.70112148
OS 33.45646598 -38.66876188
OS 33.45461686 -38.63547772
OS 33.45461686 -38.63455316
OS 33.45461686 -38.63085492
OS 33.45461686 -38.62530756
OS 33.45554142 -38.61883564
OS 33.45554142 -38.60959004
OS 33.45646598 -38.60034444
OS 33.45739054 -38.58832516
OS 33.45923966 -38.57630588
OS 33.46386246 -38.54949364
OS 33.47033438 -38.51990772
OS 33.47957998 -38.4903218
OS 33.49252382 -38.46166044
OS 33.49344838 -38.46073588
OS 33.49437294 -38.4579622
OS 33.49622206 -38.45426396
OS 33.4999203 -38.44964116
OS 33.50361854 -38.44316924
OS 33.50824134 -38.43577276
OS 33.52026062 -38.41913068
OS 33.53597814 -38.40063948
OS 33.55446934 -38.38214828
OS 33.57573422 -38.36365708
OS 33.60069734 -38.34793956
OS 33.6016219 -38.347015
OS 33.60439558 -38.34609044
OS 33.60809382 -38.34424132
OS 33.61271662 -38.34146764
OS 33.6201131 -38.33869396
OS 33.62750958 -38.33592028
OS 33.63675518 -38.33222204
OS 33.64692534 -38.3285238
OS 33.65802006 -38.32482556
OS 33.67003934 -38.32112732
OS 33.69592702 -38.31557996
OS 33.72551294 -38.31095716
OS 33.75602342 -38.30910804
OS 33.76526902 -38.30910804
OS 33.77174094 -38.3100326
OE
OB 35.15858094 -39.1375138 I
OS 34.63805366 -39.1375138
OS 34.63805366 -39.08111564
OS 35.15858094 -39.08111564
OS 35.15858094 -39.1375138
OE
OB 34.37917686 -38.32112732 I
OS 34.38657334 -38.32112732
OS 34.40321542 -38.32297644
OS 34.42170662 -38.32482556
OS 34.44112238 -38.3285238
OS 34.46053814 -38.3331466
OS 34.47810478 -38.33961852
OS 34.47902934 -38.33961852
OS 34.4799539 -38.34054308
OS 34.48550126 -38.34331676
OS 34.4938223 -38.34793956
OS 34.5030679 -38.35441148
OS 34.51416262 -38.36273252
OS 34.5261819 -38.37290268
OS 34.53727662 -38.38584652
OS 34.54744678 -38.39971492
OS 34.54837134 -38.40156404
OS 34.55114502 -38.4071114
OS 34.55576782 -38.41450788
OS 34.56039062 -38.4256026
OS 34.56501342 -38.43854644
OS 34.56963622 -38.45241484
OS 34.5724099 -38.46813236
OS 34.57333446 -38.48384988
OS 34.57333446 -38.485699
OS 34.57333446 -38.4903218
OS 34.5724099 -38.49864284
OS 34.57056078 -38.508813
OS 34.5677871 -38.52083228
OS 34.5631643 -38.53377612
OS 34.55761694 -38.54671996
OS 34.55022046 -38.56058836
OS 34.5492959 -38.56243748
OS 34.54652222 -38.56613572
OS 34.54097486 -38.5735322
OS 34.53357838 -38.58092868
OS 34.52433278 -38.59017428
OS 34.51323806 -38.60034444
OS 34.49936966 -38.60959004
OS 34.48365214 -38.61883564
OS 34.4845767 -38.61883564
OS 34.48642582 -38.6197602
OS 34.4891995 -38.62068476
OS 34.49289774 -38.62253388
OS 34.50399246 -38.62623212
OS 34.5169363 -38.63270404
OS 34.5308047 -38.64102508
OS 34.54652222 -38.65119524
OS 34.56039062 -38.66321452
OS 34.57333446 -38.67800748
OS 34.57425902 -38.6798566
OS 34.57795726 -38.68540396
OS 34.58350462 -38.693725
OS 34.58905198 -38.70481972
OS 34.59459934 -38.71961268
OS 34.6001467 -38.7353302
OS 34.60384494 -38.7538214
OS 34.6047695 -38.77416172
OS 34.6047695 -38.77508628
OS 34.6047695 -38.77601084
OS 34.6047695 -38.7815582
OS 34.60384494 -38.7908038
OS 34.60199582 -38.80189852
OS 34.6001467 -38.81484236
OS 34.59644846 -38.82871076
OS 34.59182566 -38.84350372
OS 34.58535374 -38.85829668
OS 34.58442918 -38.8601458
OS 34.5816555 -38.8647686
OS 34.57795726 -38.87124052
OS 34.5724099 -38.88048612
OS 34.56501342 -38.88973172
OS 34.55761694 -38.89990188
OS 34.54837134 -38.91007204
OS 34.53820118 -38.91839308
OS 34.53727662 -38.91931764
OS 34.53357838 -38.92209132
OS 34.52710646 -38.92578956
OS 34.51878542 -38.9294878
OS 34.50861526 -38.93503516
OS 34.49659598 -38.94058252
OS 34.48365214 -38.94520532
OS 34.46793462 -38.94982812
OS 34.4660855 -38.94982812
OS 34.46053814 -38.95167724
OS 34.45129254 -38.9526018
OS 34.43927326 -38.95445092
OS 34.4244803 -38.95630004
OS 34.40691366 -38.95814916
OS 34.3874979 -38.95907372
OS 34.36530846 -38.95999828
OS 34.12122462 -38.95999828
OS 34.12122462 -38.32020276
OS 34.37270494 -38.32020276
OS 34.37917686 -38.32112732
OE
OB 31.74233174 -38.95999828 I
OS 31.65264942 -38.95999828
OS 31.65264942 -38.87031596
OS 31.74233174 -38.87031596
OS 31.74233174 -38.95999828
OE
OB 31.52968294 -38.42745172 I
OS 31.50841806 -38.54671996
OS 31.45941638 -38.54671996
OS 31.44000062 -38.42745172
OS 31.44000062 -38.32020276
OS 31.52968294 -38.32020276
OS 31.52968294 -38.42745172
OE
OB 32.0992119 -38.48662356 I
OS 32.10568382 -38.48754812
OS 32.11955222 -38.48939724
OS 32.1361943 -38.49309548
OS 32.15376094 -38.49864284
OS 32.17132758 -38.50696388
OS 32.18889422 -38.51713404
OS 32.18981878 -38.51713404
OS 32.19074334 -38.51898316
OS 32.1962907 -38.5226814
OS 32.20461174 -38.53007788
OS 32.2147819 -38.53932348
OS 32.22587662 -38.55134276
OS 32.23697134 -38.56613572
OS 32.24806606 -38.58370236
OS 32.25731166 -38.60311812
OS 32.25731166 -38.60404268
OS 32.25823622 -38.6058918
OS 32.25916078 -38.60866548
OS 32.2610099 -38.61236372
OS 32.26285902 -38.61791108
OS 32.26470814 -38.624383
OS 32.26933094 -38.63917596
OS 32.27395374 -38.65766716
OS 32.27765198 -38.67800748
OS 32.28042566 -38.70112148
OS 32.28135022 -38.72516004
OS 32.28135022 -38.7260846
OS 32.28135022 -38.72793372
OS 32.28135022 -38.73163196
OS 32.28135022 -38.73717932
OS 32.28042566 -38.74365124
OS 32.28042566 -38.75104772
OS 32.27857654 -38.7676898
OS 32.2748783 -38.78803012
OS 32.2702555 -38.809295
OS 32.26378358 -38.83148444
OS 32.25546254 -38.85367388
OS 32.25546254 -38.85459844
OS 32.25453798 -38.85644756
OS 32.25268886 -38.85922124
OS 32.25083974 -38.86291948
OS 32.24436782 -38.87308964
OS 32.23604678 -38.88603348
OS 32.22587662 -38.89990188
OS 32.21293278 -38.91377028
OS 32.19813982 -38.92763868
OS 32.18057318 -38.94058252
OS 32.17964862 -38.94058252
OS 32.17872406 -38.94150708
OS 32.17595038 -38.9433562
OS 32.17225214 -38.94520532
OS 32.16300654 -38.94982812
OS 32.1500627 -38.95537548
OS 32.13434518 -38.96092284
OS 32.1177031 -38.96554564
OS 32.09828734 -38.96924388
OS 32.07887158 -38.97016844
OS 32.07239966 -38.97016844
OS 32.06500318 -38.96924388
OS 32.05575758 -38.96831932
OS 32.04466286 -38.9664702
OS 32.03264358 -38.96369652
OS 32.0206243 -38.95999828
OS 32.00860502 -38.95445092
OS 32.00768046 -38.95352636
OS 32.00305766 -38.95167724
OS 31.9975103 -38.947979
OS 31.99011382 -38.94243164
OS 31.98271734 -38.93688428
OS 31.97347174 -38.9294878
OS 31.9651507 -38.92116676
OS 31.95775422 -38.91192116
OS 31.95775422 -39.1375138
OS 31.87916662 -39.1375138
OS 31.87916662 -38.49586916
OS 31.95035774 -38.49586916
OS 31.95035774 -38.55689012
OS 31.9512823 -38.555041
OS 31.95498054 -38.55134276
OS 31.95960334 -38.54487084
OS 31.96699982 -38.53747436
OS 31.97532086 -38.52822876
OS 31.98456646 -38.51990772
OS 31.99566118 -38.51158668
OS 32.0067559 -38.5041902
OS 32.00860502 -38.50326564
OS 32.01230326 -38.50141652
OS 32.01969974 -38.49864284
OS 32.02894534 -38.4949446
OS 32.04004006 -38.49124636
OS 32.0529839 -38.48847268
OS 32.06777686 -38.48662356
OS 32.08441894 -38.485699
OS 32.0945891 -38.485699
OS 32.0992119 -38.48662356
OE
OB 32.5614919 -38.48662356 I
OS 32.57166206 -38.48847268
OS 32.58368134 -38.49217092
OS 32.59662518 -38.49679372
OS 32.61141814 -38.50326564
OS 32.62713566 -38.51158668
OS 32.5984743 -38.58370236
OS 32.59754974 -38.5827778
OS 32.5938515 -38.58092868
OS 32.58830414 -38.578155
OS 32.58090766 -38.57538132
OS 32.57258662 -38.57260764
OS 32.56241646 -38.56983396
OS 32.5522463 -38.56798484
OS 32.54207614 -38.56706028
OS 32.53745334 -38.56706028
OS 32.53283054 -38.56798484
OS 32.52635862 -38.5689094
OS 32.5198867 -38.57075852
OS 32.51156566 -38.5735322
OS 32.50324462 -38.57723044
OS 32.49584814 -38.5827778
OS 32.49492358 -38.58370236
OS 32.4921499 -38.58555148
OS 32.48937622 -38.58924972
OS 32.48475342 -38.59387252
OS 32.48013062 -38.60034444
OS 32.47550782 -38.60774092
OS 32.47088502 -38.61606196
OS 32.46718678 -38.62623212
OS 32.46626222 -38.62808124
OS 32.46533766 -38.6336286
OS 32.46348854 -38.64194964
OS 32.46071486 -38.65304436
OS 32.45794118 -38.66691276
OS 32.45609206 -38.68263028
OS 32.4551675 -38.69927236
OS 32.45424294 -38.71776356
OS 32.45424294 -38.95999828
OS 32.37565534 -38.95999828
OS 32.37565534 -38.49586916
OS 32.44684646 -38.49586916
OS 32.44684646 -38.56613572
OS 32.44777102 -38.56521116
OS 32.45146926 -38.55873924
OS 32.45609206 -38.5504182
OS 32.46348854 -38.54024804
OS 32.47088502 -38.53007788
OS 32.47920606 -38.51898316
OS 32.4875271 -38.50973756
OS 32.49584814 -38.50234108
OS 32.4967727 -38.50141652
OS 32.49954638 -38.4995674
OS 32.50509374 -38.49679372
OS 32.5106411 -38.49402004
OS 32.51803758 -38.49124636
OS 32.52728318 -38.48847268
OS 32.53652878 -38.48662356
OS 32.54669894 -38.485699
OS 32.55317086 -38.485699
OS 32.5614919 -38.48662356
OE
OB 32.75195126 -38.4117342 I
OS 32.67336366 -38.4117342
OS 32.67336366 -38.32020276
OS 32.75195126 -38.32020276
OS 32.75195126 -38.4117342
OE
OB 36.56668582 -38.95999828 I
OS 36.47885262 -38.95999828
OS 36.1441619 -38.4579622
OS 36.1441619 -38.95999828
OS 36.06280062 -38.95999828
OS 36.06280062 -38.32020276
OS 36.14970926 -38.32020276
OS 36.48532454 -38.8231634
OS 36.48532454 -38.32020276
OS 36.56668582 -38.32020276
OS 36.56668582 -38.95999828
OE
OB 35.74382742 -38.32112732 I
OS 35.75954494 -38.32205188
OS 35.77618702 -38.32297644
OS 35.79190454 -38.32482556
OS 35.80577294 -38.32667468
OS 35.80762206 -38.32667468
OS 35.81409398 -38.3285238
OS 35.82241502 -38.33037292
OS 35.83350974 -38.3331466
OS 35.84552902 -38.3377694
OS 35.85847286 -38.34331676
OS 35.87234126 -38.34978868
OS 35.88436054 -38.35718516
OS 35.88620966 -38.35810972
OS 35.8899079 -38.3608834
OS 35.89545526 -38.36643076
OS 35.90285174 -38.37290268
OS 35.91117278 -38.38122372
OS 35.91949382 -38.39231844
OS 35.92873942 -38.40433772
OS 35.9361359 -38.41820612
OS 35.93706046 -38.42005524
OS 35.93890958 -38.42467804
OS 35.94260782 -38.43299908
OS 35.94630606 -38.4440938
OS 35.94907974 -38.45703764
OS 35.95277798 -38.4718306
OS 35.9546271 -38.48847268
OS 35.95555166 -38.50603932
OS 35.95555166 -38.50696388
OS 35.95555166 -38.50973756
OS 35.95555166 -38.5134358
OS 35.9546271 -38.51990772
OS 35.95370254 -38.52637964
OS 35.95277798 -38.53470068
OS 35.95092886 -38.54394628
OS 35.94907974 -38.55411644
OS 35.94260782 -38.57538132
OS 35.93890958 -38.58647604
OS 35.93336222 -38.59849532
OS 35.9268903 -38.6105146
OS 35.92041838 -38.62160932
OS 35.91209734 -38.63270404
OS 35.90285174 -38.64379876
OS 35.90192718 -38.64472332
OS 35.90007806 -38.64657244
OS 35.89730438 -38.64934612
OS 35.89268158 -38.6521198
OS 35.88713422 -38.6567426
OS 35.87973774 -38.6613654
OS 35.87049214 -38.66691276
OS 35.86032198 -38.67153556
OS 35.8483027 -38.67708292
OS 35.8344343 -38.68263028
OS 35.81964134 -38.68725308
OS 35.8020747 -38.69095132
OS 35.7835835 -38.69464956
OS 35.76324318 -38.69742324
OS 35.74012918 -38.69927236
OS 35.71609062 -38.70019692
OS 35.5524435 -38.70019692
OS 35.5524435 -38.95999828
OS 35.46738398 -38.95999828
OS 35.46738398 -38.32020276
OS 35.72995902 -38.32020276
OS 35.74382742 -38.32112732
OE
OB 36.76916446 -38.42745172 I
OS 36.74789958 -38.54671996
OS 36.6988979 -38.54671996
OS 36.67948214 -38.42745172
OS 36.67948214 -38.32020276
OS 36.76916446 -38.32020276
OS 36.76916446 -38.42745172
OE
OB 38.2382903 -38.39601668 I
OS 37.86014526 -38.39601668
OS 37.86014526 -38.59109884
OS 38.21425174 -38.59109884
OS 38.21425174 -38.66691276
OS 37.86014526 -38.66691276
OS 37.86014526 -38.88418436
OS 38.25308326 -38.88418436
OS 38.25308326 -38.95999828
OS 37.77508574 -38.95999828
OS 37.77508574 -38.32020276
OS 38.2382903 -38.32020276
OS 38.2382903 -38.39601668
OE
OB 37.4339231 -38.32112732 I
OS 37.44224414 -38.32112732
OS 37.4616599 -38.32205188
OS 37.48200022 -38.32482556
OS 37.50418966 -38.32759924
OS 37.52452998 -38.33222204
OS 37.53470014 -38.33499572
OS 37.54302118 -38.3377694
OS 37.54394574 -38.3377694
OS 37.5448703 -38.33869396
OS 37.55041766 -38.34146764
OS 37.5587387 -38.34516588
OS 37.56890886 -38.3516378
OS 37.58000358 -38.35995884
OS 37.59202286 -38.37105356
OS 37.60311758 -38.3839974
OS 37.6142123 -38.39879036
OS 37.6142123 -38.39971492
OS 37.61513686 -38.40063948
OS 37.6188351 -38.40618684
OS 37.62253334 -38.41543244
OS 37.6280807 -38.42745172
OS 37.6327035 -38.44132012
OS 37.6373263 -38.4579622
OS 37.64009998 -38.47552884
OS 37.64102454 -38.4949446
OS 37.64102454 -38.49586916
OS 37.64102454 -38.49771828
OS 37.64102454 -38.50141652
OS 37.64009998 -38.50603932
OS 37.64009998 -38.51251124
OS 37.63917542 -38.51898316
OS 37.63547718 -38.53470068
OS 37.62992982 -38.55319188
OS 37.62253334 -38.57260764
OS 37.61143862 -38.5920234
OS 37.60404214 -38.601269
OS 37.59664566 -38.6105146
OS 37.5957211 -38.61143916
OS 37.59479654 -38.61236372
OS 37.59202286 -38.6151374
OS 37.58832462 -38.61791108
OS 37.58370182 -38.62160932
OS 37.57815446 -38.62530756
OS 37.57075798 -38.62993036
OS 37.5633615 -38.63547772
OS 37.5541159 -38.64010052
OS 37.54394574 -38.64472332
OS 37.53285102 -38.65027068
OS 37.52083174 -38.65489348
OS 37.50696334 -38.65859172
OS 37.49309494 -38.66321452
OS 37.47737742 -38.6659882
OS 37.46073534 -38.66876188
OS 37.46258446 -38.66968644
OS 37.4662827 -38.67153556
OS 37.47183006 -38.6752338
OS 37.47922654 -38.67893204
OS 37.49586862 -38.6891022
OS 37.50418966 -38.69557412
OS 37.51158614 -38.70112148
OS 37.51343526 -38.7029706
OS 37.51805806 -38.7075934
OS 37.52545454 -38.71498988
OS 37.53470014 -38.72423548
OS 37.5448703 -38.73717932
OS 37.55688958 -38.75104772
OS 37.56890886 -38.7676898
OS 37.5818527 -38.786181
OS 37.69187534 -38.95999828
OS 37.5864755 -38.95999828
OS 37.50234054 -38.82686164
OS 37.50234054 -38.82593708
OS 37.50049142 -38.82408796
OS 37.4986423 -38.82131428
OS 37.49586862 -38.81761604
OS 37.4893967 -38.80744588
OS 37.48107566 -38.79450204
OS 37.4709055 -38.78063364
OS 37.46073534 -38.76584068
OS 37.45056518 -38.75197228
OS 37.44131958 -38.73902844
OS 37.44039502 -38.73810388
OS 37.43762134 -38.73440564
OS 37.43299854 -38.72885828
OS 37.42652662 -38.72238636
OS 37.41265822 -38.70851796
OS 37.40526174 -38.70204604
OS 37.39786526 -38.69649868
OS 37.3969407 -38.69557412
OS 37.39509158 -38.69464956
OS 37.39139334 -38.69280044
OS 37.38584598 -38.69002676
OS 37.38029862 -38.68725308
OS 37.3738267 -38.6844794
OS 37.35903374 -38.6798566
OS 37.35810918 -38.6798566
OS 37.35626006 -38.67893204
OS 37.35256182 -38.67893204
OS 37.34793902 -38.67800748
OS 37.3414671 -38.67708292
OS 37.33407062 -38.67708292
OS 37.32390046 -38.67615836
OS 37.21480238 -38.67615836
OS 37.21480238 -38.95999828
OS 37.12974286 -38.95999828
OS 37.12974286 -38.32020276
OS 37.42652662 -38.32020276
OS 37.4339231 -38.32112732
OE
OB 35.31760526 -38.95999828 I
OS 35.23254574 -38.95999828
OS 35.23254574 -38.32020276
OS 35.31760526 -38.32020276
OS 35.31760526 -38.95999828
OE
OB 42.12051774 -38.66413908 H
OS 41.95224782 -38.66413908
OS 41.95224782 -38.88418436
OS 42.13438614 -38.88418436
OS 42.1538019 -38.8832598
OS 42.16212294 -38.88233524
OS 42.16951942 -38.88141068
OS 42.17044398 -38.88141068
OS 42.17414222 -38.88048612
OS 42.17968958 -38.87956156
OS 42.1861615 -38.87771244
OS 42.20187902 -38.87216508
OS 42.21759654 -38.8647686
OS 42.2185211 -38.86384404
OS 42.22129478 -38.86199492
OS 42.22499302 -38.85922124
OS 42.22961582 -38.855523
OS 42.23423862 -38.84997564
OS 42.24071054 -38.84442828
OS 42.24533334 -38.8370318
OS 42.2508807 -38.82871076
OS 42.25180526 -38.8277862
OS 42.25272982 -38.82501252
OS 42.25457894 -38.81946516
OS 42.25735262 -38.81299324
OS 42.2601263 -38.80559676
OS 42.26197542 -38.79635116
OS 42.26289998 -38.78525644
OS 42.26382454 -38.77416172
OS 42.26382454 -38.7723126
OS 42.26382454 -38.76861436
OS 42.26289998 -38.76121788
OS 42.26105086 -38.75289684
OS 42.25920174 -38.74365124
OS 42.2555035 -38.73348108
OS 42.2508807 -38.72331092
OS 42.24440878 -38.71314076
OS 42.24348422 -38.7122162
OS 42.24071054 -38.70851796
OS 42.2370123 -38.70389516
OS 42.23146494 -38.6983478
OS 42.22406846 -38.69187588
OS 42.21482286 -38.68540396
OS 42.2046527 -38.6798566
OS 42.19263342 -38.6752338
OS 42.1907843 -38.67430924
OS 42.18708606 -38.67338468
OS 42.17876502 -38.67153556
OS 42.16859486 -38.66968644
OS 42.15565102 -38.66783732
OS 42.1399335 -38.6659882
OS 42.12051774 -38.66413908
OE
OB 45.22981302 -38.5504182 H
OS 45.22426566 -38.5504182
OS 45.21964286 -38.55134276
OS 45.2094727 -38.55226732
OS 45.1956043 -38.55596556
OS 45.17988678 -38.56151292
OS 45.1632447 -38.5689094
OS 45.14752718 -38.58000412
OS 45.13920614 -38.5874006
OS 45.13180966 -38.59479708
OS 45.13180966 -38.59572164
OS 45.12996054 -38.5966462
OS 45.12811142 -38.59941988
OS 45.12533774 -38.60311812
OS 45.12256406 -38.60774092
OS 45.11979038 -38.61328828
OS 45.11609214 -38.62068476
OS 45.1123939 -38.62808124
OS 45.10869566 -38.63732684
OS 45.10499742 -38.64657244
OS 45.10222374 -38.65766716
OS 45.09945006 -38.66968644
OS 45.09667638 -38.68263028
OS 45.09482726 -38.69649868
OS 45.0939027 -38.7122162
OS 45.09297814 -38.72793372
OS 45.09297814 -38.72885828
OS 45.09297814 -38.73163196
OS 45.09297814 -38.73625476
OS 45.0939027 -38.74272668
OS 45.0939027 -38.75012316
OS 45.09482726 -38.7584442
OS 45.09760094 -38.77785996
OS 45.10222374 -38.8000494
OS 45.10962022 -38.82223884
OS 45.11886582 -38.84350372
OS 45.12533774 -38.85274932
OS 45.13180966 -38.86199492
OS 45.13273422 -38.86199492
OS 45.13365878 -38.86384404
OS 45.13920614 -38.86846684
OS 45.14752718 -38.87586332
OS 45.1586219 -38.8832598
OS 45.1724903 -38.89158084
OS 45.18913238 -38.89897732
OS 45.20854814 -38.90360012
OS 45.2187183 -38.90452468
OS 45.22981302 -38.90544924
OS 45.23536038 -38.90544924
OS 45.23998318 -38.90452468
OS 45.25015334 -38.90267556
OS 45.26402174 -38.89990188
OS 45.2788147 -38.89435452
OS 45.29545678 -38.88695804
OS 45.3111743 -38.87586332
OS 45.31949534 -38.86846684
OS 45.32689182 -38.86107036
OS 45.32781638 -38.8601458
OS 45.32874094 -38.85922124
OS 45.33059006 -38.85644756
OS 45.33336374 -38.85274932
OS 45.33613742 -38.84812652
OS 45.33983566 -38.84257916
OS 45.3435339 -38.83518268
OS 45.34723214 -38.8277862
OS 45.35093038 -38.8185406
OS 45.35370406 -38.80837044
OS 45.3574023 -38.79727572
OS 45.36017598 -38.78525644
OS 45.36294966 -38.77138804
OS 45.36479878 -38.75751964
OS 45.3666479 -38.74180212
OS 45.3666479 -38.72516004
OS 45.3666479 -38.72423548
OS 45.3666479 -38.7214618
OS 45.3666479 -38.716839
OS 45.36572334 -38.71129164
OS 45.36572334 -38.70389516
OS 45.36479878 -38.69557412
OS 45.3620251 -38.67615836
OS 45.3574023 -38.65581804
OS 45.35000582 -38.6336286
OS 45.33983566 -38.61328828
OS 45.3342883 -38.60311812
OS 45.32689182 -38.59479708
OS 45.32689182 -38.59387252
OS 45.3250427 -38.59294796
OS 45.31949534 -38.5874006
OS 45.3111743 -38.58092868
OS 45.30007958 -38.57260764
OS 45.28621118 -38.5642866
OS 45.2695691 -38.55689012
OS 45.2510779 -38.55226732
OS 45.24090774 -38.55134276
OS 45.22981302 -38.5504182
OE
OB 32.07702246 -38.54764452 H
OS 32.07239966 -38.54764452
OS 32.06870142 -38.54856908
OS 32.05945582 -38.5504182
OS 32.04743654 -38.55319188
OS 32.03356814 -38.55873924
OS 32.01877518 -38.56706028
OS 32.01045414 -38.57260764
OS 32.00305766 -38.57907956
OS 31.99566118 -38.58647604
OS 31.9882647 -38.59479708
OS 31.9882647 -38.59572164
OS 31.98641558 -38.5966462
OS 31.98456646 -38.59941988
OS 31.98271734 -38.60311812
OS 31.97994366 -38.60866548
OS 31.97624542 -38.61421284
OS 31.97254718 -38.62160932
OS 31.9697735 -38.6290058
OS 31.96607526 -38.6382514
OS 31.96237702 -38.64842156
OS 31.95960334 -38.65951628
OS 31.9559051 -38.67153556
OS 31.95405598 -38.68540396
OS 31.95220686 -38.69927236
OS 31.95035774 -38.71406532
OS 31.95035774 -38.7307074
OS 31.95035774 -38.73163196
OS 31.95035774 -38.73440564
OS 31.95035774 -38.73902844
OS 31.9512823 -38.74550036
OS 31.9512823 -38.75289684
OS 31.95220686 -38.76121788
OS 31.95498054 -38.78063364
OS 31.95960334 -38.80282308
OS 31.9651507 -38.82408796
OS 31.9743963 -38.84535284
OS 31.97994366 -38.85459844
OS 31.98641558 -38.86291948
OS 31.9882647 -38.8647686
OS 31.9928875 -38.8693914
OS 32.00028398 -38.87678788
OS 32.01045414 -38.88418436
OS 32.02339798 -38.89158084
OS 32.03819094 -38.89897732
OS 32.05483302 -38.90360012
OS 32.06407862 -38.90452468
OS 32.07332422 -38.90544924
OS 32.07887158 -38.90544924
OS 32.08256982 -38.90452468
OS 32.09181542 -38.90267556
OS 32.10475926 -38.89990188
OS 32.11862766 -38.89435452
OS 32.13342062 -38.88695804
OS 32.14821358 -38.87586332
OS 32.15561006 -38.8693914
OS 32.16300654 -38.86199492
OS 32.16300654 -38.86107036
OS 32.16485566 -38.8601458
OS 32.16670478 -38.85737212
OS 32.1685539 -38.85367388
OS 32.17225214 -38.84905108
OS 32.17502582 -38.84257916
OS 32.17872406 -38.83610724
OS 32.1824223 -38.8277862
OS 32.18519598 -38.81946516
OS 32.18889422 -38.80837044
OS 32.19259246 -38.79727572
OS 32.19536614 -38.78525644
OS 32.19721526 -38.77138804
OS 32.19906438 -38.75659508
OS 32.2009135 -38.74087756
OS 32.2009135 -38.72423548
OS 32.2009135 -38.72331092
OS 32.2009135 -38.72053724
OS 32.2009135 -38.71591444
OS 32.19998894 -38.70944252
OS 32.19998894 -38.70204604
OS 32.19906438 -38.693725
OS 32.1962907 -38.67430924
OS 32.1916679 -38.65304436
OS 32.18519598 -38.63177948
OS 32.17595038 -38.6105146
OS 32.17040302 -38.60034444
OS 32.1639311 -38.5920234
OS 32.1639311 -38.59109884
OS 32.16208198 -38.59017428
OS 32.15745918 -38.58462692
OS 32.1500627 -38.578155
OS 32.13989254 -38.56983396
OS 32.1269487 -38.56151292
OS 32.11215574 -38.55411644
OS 32.09551366 -38.54949364
OS 32.08626806 -38.54856908
OS 32.07702246 -38.54764452
OE
OB 42.10387566 -38.39601668 H
OS 41.95224782 -38.39601668
OS 41.95224782 -38.58832516
OS 42.10942302 -38.58832516
OS 42.1214423 -38.5874006
OS 42.13438614 -38.58647604
OS 42.14732998 -38.58555148
OS 42.16027382 -38.58370236
OS 42.17044398 -38.58185324
OS 42.1722931 -38.58092868
OS 42.17599134 -38.58000412
OS 42.1815387 -38.57723044
OS 42.18893518 -38.5735322
OS 42.19633166 -38.56983396
OS 42.2046527 -38.5642866
OS 42.21297374 -38.55689012
OS 42.21944566 -38.54949364
OS 42.22037022 -38.54856908
OS 42.22221934 -38.5457954
OS 42.22499302 -38.54024804
OS 42.2277667 -38.53377612
OS 42.23054038 -38.52637964
OS 42.23331406 -38.51713404
OS 42.23516318 -38.50603932
OS 42.23608774 -38.49402004
OS 42.23608774 -38.49217092
OS 42.23608774 -38.48847268
OS 42.23516318 -38.48292532
OS 42.23423862 -38.47552884
OS 42.2323895 -38.46628324
OS 42.22961582 -38.45703764
OS 42.22591758 -38.44779204
OS 42.22037022 -38.43854644
OS 42.21944566 -38.43762188
OS 42.21759654 -38.4348482
OS 42.2138983 -38.4302254
OS 42.2092755 -38.4256026
OS 42.20280358 -38.42005524
OS 42.1954071 -38.41450788
OS 42.1861615 -38.40896052
OS 42.17599134 -38.40526228
OS 42.17506678 -38.40526228
OS 42.17044398 -38.40341316
OS 42.16397206 -38.4024886
OS 42.1538019 -38.40063948
OS 42.1399335 -38.39879036
OS 42.12421598 -38.3978658
OS 42.10387566 -38.39601668
OE
OB 37.41635646 -38.39139388 H
OS 37.21480238 -38.39139388
OS 37.21480238 -38.60311812
OS 37.40526174 -38.60311812
OS 37.41635646 -38.60219356
OS 37.4293003 -38.601269
OS 37.44409326 -38.60034444
OS 37.45888622 -38.59849532
OS 37.47367918 -38.59572164
OS 37.48662302 -38.5920234
OS 37.48847214 -38.59109884
OS 37.49217038 -38.58924972
OS 37.49771774 -38.58647604
OS 37.50511422 -38.5827778
OS 37.51343526 -38.57723044
OS 37.5217563 -38.57075852
OS 37.53007734 -38.56243748
OS 37.53654926 -38.55319188
OS 37.53747382 -38.55226732
OS 37.53932294 -38.54856908
OS 37.54209662 -38.54302172
OS 37.54579486 -38.53562524
OS 37.54856854 -38.5273042
OS 37.55134222 -38.5180586
OS 37.55319134 -38.50696388
OS 37.5541159 -38.49586916
OS 37.5541159 -38.4949446
OS 37.5541159 -38.49402004
OS 37.55319134 -38.48847268
OS 37.55226678 -38.48015164
OS 37.55041766 -38.46905692
OS 37.54579486 -38.4579622
OS 37.5402475 -38.44501836
OS 37.53192646 -38.43299908
OS 37.52083174 -38.4209798
OS 37.51898262 -38.42005524
OS 37.51435982 -38.416357
OS 37.50696334 -38.4117342
OS 37.49494406 -38.40618684
OS 37.48107566 -38.40063948
OS 37.46258446 -38.39601668
OS 37.44131958 -38.39231844
OS 37.41635646 -38.39139388
OE
OB 39.82298614 -38.54764452 H
OS 39.81836334 -38.54764452
OS 39.8146651 -38.54856908
OS 39.8054195 -38.5504182
OS 39.79340022 -38.55319188
OS 39.77953182 -38.55873924
OS 39.76473886 -38.56706028
OS 39.75641782 -38.57260764
OS 39.74902134 -38.57907956
OS 39.74162486 -38.58647604
OS 39.73422838 -38.59479708
OS 39.73422838 -38.59572164
OS 39.73237926 -38.5966462
OS 39.73053014 -38.59941988
OS 39.72868102 -38.60311812
OS 39.72590734 -38.60866548
OS 39.7222091 -38.61421284
OS 39.71851086 -38.62160932
OS 39.71573718 -38.6290058
OS 39.71203894 -38.6382514
OS 39.7083407 -38.64842156
OS 39.70556702 -38.65951628
OS 39.70186878 -38.67153556
OS 39.70001966 -38.68540396
OS 39.69817054 -38.69927236
OS 39.69632142 -38.71406532
OS 39.69632142 -38.7307074
OS 39.69632142 -38.73163196
OS 39.69632142 -38.73440564
OS 39.69632142 -38.73902844
OS 39.69724598 -38.74550036
OS 39.69724598 -38.75289684
OS 39.69817054 -38.76121788
OS 39.70094422 -38.78063364
OS 39.70556702 -38.80282308
OS 39.71111438 -38.82408796
OS 39.72035998 -38.84535284
OS 39.72590734 -38.85459844
OS 39.73237926 -38.86291948
OS 39.73422838 -38.8647686
OS 39.73885118 -38.8693914
OS 39.74624766 -38.87678788
OS 39.75641782 -38.88418436
OS 39.76936166 -38.89158084
OS 39.78415462 -38.89897732
OS 39.8007967 -38.90360012
OS 39.8100423 -38.90452468
OS 39.8192879 -38.90544924
OS 39.82483526 -38.90544924
OS 39.8285335 -38.90452468
OS 39.8377791 -38.90267556
OS 39.85072294 -38.89990188
OS 39.86459134 -38.89435452
OS 39.8793843 -38.88695804
OS 39.89417726 -38.87586332
OS 39.90157374 -38.8693914
OS 39.90897022 -38.86199492
OS 39.90897022 -38.86107036
OS 39.91081934 -38.8601458
OS 39.91266846 -38.85737212
OS 39.91451758 -38.85367388
OS 39.91821582 -38.84905108
OS 39.9209895 -38.84257916
OS 39.92468774 -38.83610724
OS 39.92838598 -38.8277862
OS 39.93115966 -38.81946516
OS 39.9348579 -38.80837044
OS 39.93855614 -38.79727572
OS 39.94132982 -38.78525644
OS 39.94317894 -38.77138804
OS 39.94502806 -38.75659508
OS 39.94687718 -38.74087756
OS 39.94687718 -38.72423548
OS 39.94687718 -38.72331092
OS 39.94687718 -38.72053724
OS 39.94687718 -38.71591444
OS 39.94595262 -38.70944252
OS 39.94595262 -38.70204604
OS 39.94502806 -38.693725
OS 39.94225438 -38.67430924
OS 39.93763158 -38.65304436
OS 39.93115966 -38.63177948
OS 39.92191406 -38.6105146
OS 39.9163667 -38.60034444
OS 39.90989478 -38.5920234
OS 39.90989478 -38.59109884
OS 39.90804566 -38.59017428
OS 39.90342286 -38.58462692
OS 39.89602638 -38.578155
OS 39.88585622 -38.56983396
OS 39.87291238 -38.56151292
OS 39.85811942 -38.55411644
OS 39.84147734 -38.54949364
OS 39.83223174 -38.54856908
OS 39.82298614 -38.54764452
OE
OB 35.73550638 -38.39601668 H
OS 35.5524435 -38.39601668
OS 35.5524435 -38.624383
OS 35.72441166 -38.624383
OS 35.73088358 -38.62345844
OS 35.7373555 -38.62345844
OS 35.74475198 -38.62253388
OS 35.76231862 -38.62068476
OS 35.78173438 -38.61698652
OS 35.80115014 -38.61143916
OS 35.81871678 -38.60404268
OS 35.82703782 -38.59941988
OS 35.83350974 -38.59387252
OS 35.83535886 -38.5920234
OS 35.8390571 -38.58832516
OS 35.84460446 -38.58092868
OS 35.85107638 -38.57168308
OS 35.8575483 -38.5596638
OS 35.86309566 -38.54487084
OS 35.8667939 -38.52822876
OS 35.86864302 -38.508813
OS 35.86864302 -38.50788844
OS 35.86864302 -38.50696388
OS 35.86864302 -38.50234108
OS 35.86771846 -38.49402004
OS 35.86586934 -38.48477444
OS 35.86402022 -38.47460428
OS 35.86032198 -38.462585
OS 35.85477462 -38.45149028
OS 35.8483027 -38.44039556
OS 35.84737814 -38.439471
OS 35.84460446 -38.43577276
OS 35.83998166 -38.43114996
OS 35.8344343 -38.42467804
OS 35.82611326 -38.41820612
OS 35.81686766 -38.41265876
OS 35.8066975 -38.4071114
OS 35.79467822 -38.4024886
OS 35.79375366 -38.4024886
OS 35.79005542 -38.40156404
OS 35.78450806 -38.40063948
OS 35.77711158 -38.39879036
OS 35.76601686 -38.3978658
OS 35.75214846 -38.39694124
OS 35.73550638 -38.39601668
OE
OB 43.44263854 -38.5504182 H
OS 43.43709118 -38.5504182
OS 43.43339294 -38.55134276
OS 43.42322278 -38.55226732
OS 43.4112035 -38.555041
OS 43.39641054 -38.5596638
OS 43.38069302 -38.56613572
OS 43.36590006 -38.57538132
OS 43.3511071 -38.5874006
OS 43.34925798 -38.58924972
OS 43.34555974 -38.59387252
OS 43.33908782 -38.60219356
OS 43.3326159 -38.61328828
OS 43.32521942 -38.62623212
OS 43.3187475 -38.6428742
OS 43.31320014 -38.66228996
OS 43.31042646 -38.68355484
OS 43.57022782 -38.68355484
OS 43.57022782 -38.68263028
OS 43.57022782 -38.68078116
OS 43.56930326 -38.67800748
OS 43.56930326 -38.67430924
OS 43.56745414 -38.66321452
OS 43.56468046 -38.65119524
OS 43.56005766 -38.63640228
OS 43.55543486 -38.62253388
OS 43.54803838 -38.60866548
OS 43.53971734 -38.5966462
OS 43.53971734 -38.59572164
OS 43.53786822 -38.59479708
OS 43.53324542 -38.58924972
OS 43.52492438 -38.58185324
OS 43.51382966 -38.5735322
OS 43.49996126 -38.56521116
OS 43.48331918 -38.55781468
OS 43.46390342 -38.55226732
OS 43.45373326 -38.55134276
OS 43.44263854 -38.5504182
OE
OB 34.35791198 -38.39601668 H
OS 34.20628414 -38.39601668
OS 34.20628414 -38.58832516
OS 34.36345934 -38.58832516
OS 34.37547862 -38.5874006
OS 34.38842246 -38.58647604
OS 34.4013663 -38.58555148
OS 34.41431014 -38.58370236
OS 34.4244803 -38.58185324
OS 34.42632942 -38.58092868
OS 34.43002766 -38.58000412
OS 34.43557502 -38.57723044
OS 34.4429715 -38.5735322
OS 34.45036798 -38.56983396
OS 34.45868902 -38.5642866
OS 34.46701006 -38.55689012
OS 34.47348198 -38.54949364
OS 34.47440654 -38.54856908
OS 34.47625566 -38.5457954
OS 34.47902934 -38.54024804
OS 34.48180302 -38.53377612
OS 34.4845767 -38.52637964
OS 34.48735038 -38.51713404
OS 34.4891995 -38.50603932
OS 34.49012406 -38.49402004
OS 34.49012406 -38.49217092
OS 34.49012406 -38.48847268
OS 34.4891995 -38.48292532
OS 34.48827494 -38.47552884
OS 34.48642582 -38.46628324
OS 34.48365214 -38.45703764
OS 34.4799539 -38.44779204
OS 34.47440654 -38.43854644
OS 34.47348198 -38.43762188
OS 34.47163286 -38.4348482
OS 34.46793462 -38.4302254
OS 34.46331182 -38.4256026
OS 34.4568399 -38.42005524
OS 34.44944342 -38.41450788
OS 34.44019782 -38.40896052
OS 34.43002766 -38.40526228
OS 34.4291031 -38.40526228
OS 34.4244803 -38.40341316
OS 34.41800838 -38.4024886
OS 34.40783822 -38.40063948
OS 34.39396982 -38.39879036
OS 34.3782523 -38.3978658
OS 34.35791198 -38.39601668
OE
OB 40.89732486 -38.39601668 H
OS 40.71426198 -38.39601668
OS 40.71426198 -38.624383
OS 40.88623014 -38.624383
OS 40.89270206 -38.62345844
OS 40.89917398 -38.62345844
OS 40.90657046 -38.62253388
OS 40.9241371 -38.62068476
OS 40.94355286 -38.61698652
OS 40.96296862 -38.61143916
OS 40.98053526 -38.60404268
OS 40.9888563 -38.59941988
OS 40.99532822 -38.59387252
OS 40.99717734 -38.5920234
OS 41.00087558 -38.58832516
OS 41.00642294 -38.58092868
OS 41.01289486 -38.57168308
OS 41.01936678 -38.5596638
OS 41.02491414 -38.54487084
OS 41.02861238 -38.52822876
OS 41.0304615 -38.508813
OS 41.0304615 -38.50788844
OS 41.0304615 -38.50696388
OS 41.0304615 -38.50234108
OS 41.02953694 -38.49402004
OS 41.02768782 -38.48477444
OS 41.0258387 -38.47460428
OS 41.02214046 -38.462585
OS 41.0165931 -38.45149028
OS 41.01012118 -38.44039556
OS 41.00919662 -38.439471
OS 41.00642294 -38.43577276
OS 41.00180014 -38.43114996
OS 40.99625278 -38.42467804
OS 40.98793174 -38.41820612
OS 40.97868614 -38.41265876
OS 40.96851598 -38.4071114
OS 40.9564967 -38.4024886
OS 40.95557214 -38.4024886
OS 40.9518739 -38.40156404
OS 40.94632654 -38.40063948
OS 40.93893006 -38.39879036
OS 40.92783534 -38.3978658
OS 40.91396694 -38.39694124
OS 40.89732486 -38.39601668
OE
OB 33.15136118 -38.39601668 H
OS 32.9682983 -38.39601668
OS 32.9682983 -38.624383
OS 33.14026646 -38.624383
OS 33.14673838 -38.62345844
OS 33.1532103 -38.62345844
OS 33.16060678 -38.62253388
OS 33.17817342 -38.62068476
OS 33.19758918 -38.61698652
OS 33.21700494 -38.61143916
OS 33.23457158 -38.60404268
OS 33.24289262 -38.59941988
OS 33.24936454 -38.59387252
OS 33.25121366 -38.5920234
OS 33.2549119 -38.58832516
OS 33.26045926 -38.58092868
OS 33.26693118 -38.57168308
OS 33.2734031 -38.5596638
OS 33.27895046 -38.54487084
OS 33.2826487 -38.52822876
OS 33.28449782 -38.508813
OS 33.28449782 -38.50788844
OS 33.28449782 -38.50696388
OS 33.28449782 -38.50234108
OS 33.28357326 -38.49402004
OS 33.28172414 -38.48477444
OS 33.27987502 -38.47460428
OS 33.27617678 -38.462585
OS 33.27062942 -38.45149028
OS 33.2641575 -38.44039556
OS 33.26323294 -38.439471
OS 33.26045926 -38.43577276
OS 33.25583646 -38.43114996
OS 33.2502891 -38.42467804
OS 33.24196806 -38.41820612
OS 33.23272246 -38.41265876
OS 33.2225523 -38.4071114
OS 33.21053302 -38.4024886
OS 33.20960846 -38.4024886
OS 33.20591022 -38.40156404
OS 33.20036286 -38.40063948
OS 33.19296638 -38.39879036
OS 33.18187166 -38.3978658
OS 33.16800326 -38.39694124
OS 33.15136118 -38.39601668
OE
OB 34.37455406 -38.66413908 H
OS 34.20628414 -38.66413908
OS 34.20628414 -38.88418436
OS 34.38842246 -38.88418436
OS 34.40783822 -38.8832598
OS 34.41615926 -38.88233524
OS 34.42355574 -38.88141068
OS 34.4244803 -38.88141068
OS 34.42817854 -38.88048612
OS 34.4337259 -38.87956156
OS 34.44019782 -38.87771244
OS 34.45591534 -38.87216508
OS 34.47163286 -38.8647686
OS 34.47255742 -38.86384404
OS 34.4753311 -38.86199492
OS 34.47902934 -38.85922124
OS 34.48365214 -38.855523
OS 34.48827494 -38.84997564
OS 34.49474686 -38.84442828
OS 34.49936966 -38.8370318
OS 34.50491702 -38.82871076
OS 34.50584158 -38.8277862
OS 34.50676614 -38.82501252
OS 34.50861526 -38.81946516
OS 34.51138894 -38.81299324
OS 34.51416262 -38.80559676
OS 34.51601174 -38.79635116
OS 34.5169363 -38.78525644
OS 34.51786086 -38.77416172
OS 34.51786086 -38.7723126
OS 34.51786086 -38.76861436
OS 34.5169363 -38.76121788
OS 34.51508718 -38.75289684
OS 34.51323806 -38.74365124
OS 34.50953982 -38.73348108
OS 34.50491702 -38.72331092
OS 34.4984451 -38.71314076
OS 34.49752054 -38.7122162
OS 34.49474686 -38.70851796
OS 34.49104862 -38.70389516
OS 34.48550126 -38.6983478
OS 34.47810478 -38.69187588
OS 34.46885918 -38.68540396
OS 34.45868902 -38.6798566
OS 34.44666974 -38.6752338
OS 34.44482062 -38.67430924
OS 34.44112238 -38.67338468
OS 34.43280134 -38.67153556
OS 34.42263118 -38.66968644
OS 34.40968734 -38.66783732
OS 34.39396982 -38.6659882
OS 34.37455406 -38.66413908
OE
SE
S P 0
OB 48.49040086 -36.61402634 I
OS 48.17420134 -36.61402634
OS 48.17420134 -37.45999874
OS 48.04661206 -37.45999874
OS 48.04661206 -36.61402634
OS 47.73041254 -36.61402634
OS 47.73041254 -36.50030546
OS 48.49040086 -36.50030546
OS 48.49040086 -36.61402634
OE
OB 47.69990206 -37.45999874 I
OS 47.5556707 -37.45999874
OS 47.44333666 -37.16876234
OS 47.04115306 -37.16876234
OS 46.93714006 -37.45999874
OS 46.80261658 -37.45999874
OS 47.16874234 -36.50030546
OS 47.30742634 -36.50030546
OS 47.69990206 -37.45999874
OE
OB 49.31834434 -36.61402634 I
OS 48.75112678 -36.61402634
OS 48.75112678 -36.90664958
OS 49.2822865 -36.90664958
OS 49.2822865 -37.02037046
OS 48.75112678 -37.02037046
OS 48.75112678 -37.34627786
OS 49.34053378 -37.34627786
OS 49.34053378 -37.45999874
OS 48.6235375 -37.45999874
OS 48.6235375 -36.50030546
OS 49.31834434 -36.50030546
OS 49.31834434 -36.61402634
OE
OB 46.33386466 -36.5016923 I
OS 46.36160146 -36.50307914
OS 46.38933826 -36.50585282
OS 46.41707506 -36.51001334
OS 46.44065134 -36.51417386
OS 46.44203818 -36.51417386
OS 46.44481186 -36.5155607
OS 46.44897238 -36.5155607
OS 46.45451974 -36.51833438
OS 46.46977498 -36.5224949
OS 46.48919074 -36.5294291
OS 46.51138018 -36.53913698
OS 46.53495646 -36.55161854
OS 46.55853274 -36.56548694
OS 46.58072218 -36.58351586
OS 46.58210902 -36.5849027
OS 46.58349586 -36.58628954
OS 46.58765638 -36.59045006
OS 46.59320374 -36.59461058
OS 46.60707214 -36.60847898
OS 46.62371422 -36.62789474
OS 46.64174314 -36.65147102
OS 46.6611589 -36.67920782
OS 46.67918782 -36.71110514
OS 46.69444306 -36.74716298
OS 46.69444306 -36.74854982
OS 46.6958299 -36.7513235
OS 46.69860358 -36.75687086
OS 46.69999042 -36.7651919
OS 46.70415094 -36.77489978
OS 46.70692462 -36.7859945
OS 46.7096983 -36.79847606
OS 46.71385882 -36.8137313
OS 46.71801934 -36.82898654
OS 46.72079302 -36.84701546
OS 46.72772722 -36.88584698
OS 46.73188774 -36.92883902
OS 46.73327458 -36.97599158
OS 46.73327458 -36.97737842
OS 46.73327458 -36.9801521
OS 46.73327458 -36.9870863
OS 46.73327458 -36.9940205
OS 46.73188774 -37.00372838
OS 46.73188774 -37.0148231
OS 46.7305009 -37.04117306
OS 46.72634038 -37.07168354
OS 46.72217986 -37.10358086
OS 46.71524566 -37.13686502
OS 46.70692462 -37.17014918
OS 46.70692462 -37.17153602
OS 46.70553778 -37.1743097
OS 46.70415094 -37.17847022
OS 46.7027641 -37.18401758
OS 46.69721674 -37.19927282
OS 46.6888957 -37.21868858
OS 46.68057466 -37.24087802
OS 46.66947994 -37.26306746
OS 46.65561154 -37.28664374
OS 46.64174314 -37.30883318
OS 46.6403563 -37.31160686
OS 46.63480894 -37.31854106
OS 46.6264879 -37.32824894
OS 46.61539318 -37.3407305
OS 46.60291162 -37.3545989
OS 46.58765638 -37.3684673
OS 46.57240114 -37.38372254
OS 46.55437222 -37.3962041
OS 46.55159854 -37.39759094
OS 46.54605118 -37.40175146
OS 46.5363433 -37.40729882
OS 46.5224749 -37.41423302
OS 46.50583282 -37.42255406
OS 46.48641706 -37.42948826
OS 46.46422762 -37.4378093
OS 46.4392645 -37.4447435
OS 46.43649082 -37.4447435
OS 46.4323303 -37.44613034
OS 46.42816978 -37.44751718
OS 46.41430138 -37.44890402
OS 46.39488562 -37.4516777
OS 46.37269618 -37.45445138
OS 46.34634622 -37.45722506
OS 46.31722258 -37.4586119
OS 46.28532526 -37.45999874
OS 45.9400021 -37.45999874
OS 45.9400021 -36.50030546
OS 46.30890154 -36.50030546
OS 46.33386466 -36.5016923
OE
OB 46.28948578 -36.61402634 H
OS 46.06759138 -36.61402634
OS 46.06759138 -37.34627786
OS 46.29503314 -37.34627786
OS 46.30474102 -37.34489102
OS 46.32554362 -37.34350418
OS 46.3491199 -37.34211734
OS 46.37408302 -37.33934366
OS 46.39904614 -37.33518314
OS 46.41984874 -37.32963578
OS 46.42262242 -37.32824894
OS 46.42955662 -37.3268621
OS 46.4392645 -37.32270158
OS 46.45174606 -37.31715422
OS 46.46561446 -37.30883318
OS 46.47948286 -37.30051214
OS 46.49335126 -37.29080426
OS 46.50721966 -37.27970954
OS 46.5086065 -37.27693586
OS 46.51415386 -37.2713885
OS 46.5224749 -37.26168062
OS 46.53218278 -37.24781222
OS 46.5432775 -37.2297833
OS 46.55575906 -37.2089807
OS 46.56685378 -37.18540442
OS 46.57656166 -37.15905446
OS 46.57656166 -37.15766762
OS 46.5779485 -37.15489394
OS 46.57933534 -37.15073342
OS 46.58072218 -37.14518606
OS 46.58210902 -37.13825186
OS 46.5848827 -37.12854398
OS 46.58765638 -37.1188361
OS 46.59043006 -37.10774138
OS 46.59459058 -37.08000458
OS 46.5987511 -37.04810726
OS 46.60152478 -37.01204942
OS 46.60291162 -36.9732179
OS 46.60291162 -36.97183106
OS 46.60291162 -36.9662837
OS 46.60291162 -36.9593495
OS 46.60152478 -36.94825478
OS 46.60152478 -36.93577322
OS 46.60013794 -36.92190482
OS 46.5987511 -36.90526274
OS 46.59736426 -36.88862066
OS 46.59043006 -36.85117598
OS 46.58210902 -36.81234446
OS 46.56962746 -36.77628662
OS 46.56130642 -36.7582577
OS 46.55298538 -36.74300246
OS 46.55298538 -36.74161562
OS 46.5502117 -36.73884194
OS 46.54743802 -36.73468142
OS 46.54466434 -36.72913406
OS 46.53356962 -36.71526566
OS 46.51970122 -36.69862358
OS 46.5016723 -36.68059466
OS 46.4808697 -36.66256574
OS 46.45729342 -36.6473105
OS 46.4323303 -36.63482894
OS 46.42955662 -36.6334421
OS 46.42262242 -36.63205526
OS 46.41014086 -36.62789474
OS 46.39211194 -36.62373422
OS 46.3699225 -36.62096054
OS 46.3421857 -36.61680002
OS 46.32554362 -36.61541318
OS 46.3075147 -36.61541318
OS 46.28948578 -36.61402634
OE
OB 47.23531066 -36.60015794 H
OS 47.23531066 -36.60154478
OS 47.23392382 -36.60431846
OS 47.23392382 -36.60986582
OS 47.23115014 -36.61541318
OS 47.2297633 -36.62512106
OS 47.22698962 -36.63482894
OS 47.22144226 -36.65840522
OS 47.21450806 -36.68614202
OS 47.20480018 -36.7166525
OS 47.1950923 -36.74993666
OS 47.18261074 -36.78460766
OS 47.07859774 -37.06474934
OS 47.4031183 -37.06474934
OS 47.30326582 -36.80124974
OS 47.30326582 -36.7998629
OS 47.30187898 -36.79570238
OS 47.2991053 -36.78876818
OS 47.29633162 -36.78044714
OS 47.2921711 -36.77073926
OS 47.28801058 -36.7582577
OS 47.28385006 -36.7443893
OS 47.2783027 -36.7305209
OS 47.26720798 -36.69862358
OS 47.25611326 -36.66533942
OS 47.24501854 -36.63205526
OS 47.23531066 -36.60015794
OE
SE
S P 0
OB 53.64989524 -38.94890356 I
OS 53.57130764 -38.94890356
OS 53.57130764 -38.4487166
OS 53.57038308 -38.44964116
OS 53.56576028 -38.4533394
OS 53.56021292 -38.45888676
OS 53.55096732 -38.46535868
OS 53.54079716 -38.47367972
OS 53.52785332 -38.48292532
OS 53.51306036 -38.49309548
OS 53.49641828 -38.50326564
OS 53.49549372 -38.50326564
OS 53.49456916 -38.5041902
OS 53.4890218 -38.50788844
OS 53.4797762 -38.51251124
OS 53.46868148 -38.5180586
OS 53.45573764 -38.52453052
OS 53.44186924 -38.53100244
OS 53.42800084 -38.53747436
OS 53.41413244 -38.54302172
OS 53.41413244 -38.4672078
OS 53.415057 -38.4672078
OS 53.41690612 -38.46535868
OS 53.42060436 -38.46443412
OS 53.42522716 -38.46166044
OS 53.43077452 -38.45888676
OS 53.43724644 -38.45518852
OS 53.45296396 -38.44594292
OS 53.47145516 -38.43577276
OS 53.48994636 -38.42282892
OS 53.50936212 -38.40803596
OS 53.52877788 -38.39231844
OS 53.52970244 -38.39139388
OS 53.530627 -38.39046932
OS 53.53340068 -38.38769564
OS 53.53709892 -38.38492196
OS 53.54541996 -38.37567636
OS 53.55651468 -38.36458164
OS 53.5676094 -38.3516378
OS 53.57962868 -38.33684484
OS 53.58979884 -38.32205188
OS 53.59904444 -38.30633436
OS 53.64989524 -38.30633436
OS 53.64989524 -38.94890356
OE
OB 54.07334372 -38.30725892 I
OS 54.0807402 -38.30818348
OS 54.08906124 -38.30910804
OS 54.09830684 -38.3100326
OS 54.10755244 -38.31280628
OS 54.12974188 -38.31835364
OS 54.15193132 -38.32667468
OS 54.16302604 -38.33222204
OS 54.17412076 -38.33869396
OS 54.18429092 -38.347015
OS 54.19446108 -38.35533604
OS 54.19538564 -38.3562606
OS 54.1963102 -38.35718516
OS 54.19908388 -38.35995884
OS 54.20278212 -38.36365708
OS 54.20648036 -38.36920444
OS 54.21110316 -38.3747518
OS 54.22034876 -38.3886202
OS 54.22959436 -38.40618684
OS 54.2379154 -38.42652716
OS 54.24438732 -38.44964116
OS 54.24531188 -38.46166044
OS 54.24623644 -38.47460428
OS 54.24623644 -38.47552884
OS 54.24623644 -38.4764534
OS 54.24623644 -38.48200076
OS 54.24531188 -38.4903218
OS 54.24346276 -38.50049196
OS 54.24068908 -38.5134358
OS 54.23606628 -38.52637964
OS 54.23051892 -38.53932348
OS 54.22219788 -38.55226732
OS 54.22127332 -38.55411644
OS 54.21757508 -38.55781468
OS 54.21202772 -38.56336204
OS 54.20463124 -38.57075852
OS 54.19446108 -38.57907956
OS 54.1824418 -38.5874006
OS 54.1685734 -38.59572164
OS 54.15193132 -38.60311812
OS 54.15285588 -38.60311812
OS 54.154705 -38.60404268
OS 54.15747868 -38.60496724
OS 54.16117692 -38.60681636
OS 54.17227164 -38.61143916
OS 54.18521548 -38.61791108
OS 54.19908388 -38.62715668
OS 54.21387684 -38.63732684
OS 54.22774524 -38.65027068
OS 54.24068908 -38.66506364
OS 54.24068908 -38.6659882
OS 54.24161364 -38.66691276
OS 54.24531188 -38.67246012
OS 54.25085924 -38.68170572
OS 54.2564066 -38.693725
OS 54.26195396 -38.70851796
OS 54.26750132 -38.7260846
OS 54.27119956 -38.74550036
OS 54.27212412 -38.76676524
OS 54.27212412 -38.7676898
OS 54.27212412 -38.77046348
OS 54.27212412 -38.77508628
OS 54.27119956 -38.78063364
OS 54.270275 -38.78710556
OS 54.26935044 -38.7954266
OS 54.26750132 -38.8046722
OS 54.26472764 -38.81484236
OS 54.25825572 -38.83610724
OS 54.25363292 -38.84812652
OS 54.247161 -38.85922124
OS 54.24068908 -38.87124052
OS 54.2332926 -38.88233524
OS 54.224047 -38.89342996
OS 54.21387684 -38.90452468
OS 54.21295228 -38.90544924
OS 54.21110316 -38.90729836
OS 54.20832948 -38.91007204
OS 54.20370668 -38.91284572
OS 54.19723476 -38.91746852
OS 54.19076284 -38.92209132
OS 54.1824418 -38.92671412
OS 54.1731962 -38.93226148
OS 54.16302604 -38.93780884
OS 54.15100676 -38.94243164
OS 54.13806292 -38.94705444
OS 54.12511908 -38.95167724
OS 54.11032612 -38.95445092
OS 54.0946086 -38.9572246
OS 54.07889108 -38.95907372
OS 54.06132444 -38.95999828
OS 54.05207884 -38.95999828
OS 54.04560692 -38.95907372
OS 54.03728588 -38.95814916
OS 54.02804028 -38.9572246
OS 54.01787012 -38.95537548
OS 54.0067754 -38.9526018
OS 53.98181228 -38.94612988
OS 53.96886844 -38.94150708
OS 53.95684916 -38.93688428
OS 53.94390532 -38.93041236
OS 53.93096148 -38.92301588
OS 53.9189422 -38.91469484
OS 53.90784748 -38.90452468
OS 53.90692292 -38.90360012
OS 53.9050738 -38.901751
OS 53.90230012 -38.89897732
OS 53.89860188 -38.89435452
OS 53.89490364 -38.88880716
OS 53.88935628 -38.88233524
OS 53.88473348 -38.87493876
OS 53.87918612 -38.86569316
OS 53.87363876 -38.85644756
OS 53.86901596 -38.84535284
OS 53.85977036 -38.82223884
OS 53.85607212 -38.80837044
OS 53.85329844 -38.79450204
OS 53.85144932 -38.77970908
OS 53.85052476 -38.76491612
OS 53.85052476 -38.76399156
OS 53.85052476 -38.76214244
OS 53.85052476 -38.7584442
OS 53.85144932 -38.75474596
OS 53.85144932 -38.7491986
OS 53.85237388 -38.74272668
OS 53.854223 -38.72793372
OS 53.85792124 -38.71129164
OS 53.8634686 -38.69464956
OS 53.87178964 -38.67708292
OS 53.8819598 -38.66044084
OS 53.8819598 -38.65951628
OS 53.88380892 -38.65859172
OS 53.88750716 -38.65396892
OS 53.89490364 -38.64657244
OS 53.9050738 -38.63732684
OS 53.91801764 -38.62808124
OS 53.93373516 -38.61791108
OS 53.9513018 -38.60959004
OS 53.97256668 -38.60311812
OS 53.97164212 -38.60311812
OS 53.97071756 -38.60219356
OS 53.96794388 -38.601269
OS 53.96424564 -38.59941988
OS 53.9559246 -38.59572164
OS 53.94482988 -38.59017428
OS 53.9328106 -38.5827778
OS 53.92079132 -38.5735322
OS 53.9096966 -38.56336204
OS 53.89952644 -38.55226732
OS 53.89860188 -38.5504182
OS 53.8958282 -38.54671996
OS 53.89212996 -38.53932348
OS 53.88843172 -38.53007788
OS 53.88380892 -38.5180586
OS 53.88011068 -38.5041902
OS 53.877337 -38.48847268
OS 53.87641244 -38.4718306
OS 53.87641244 -38.47090604
OS 53.87641244 -38.46905692
OS 53.87641244 -38.46535868
OS 53.877337 -38.45981132
OS 53.87826156 -38.45426396
OS 53.87918612 -38.44686748
OS 53.88288436 -38.43114996
OS 53.88843172 -38.41265876
OS 53.89767732 -38.393243
OS 53.90322468 -38.38307284
OS 53.9096966 -38.37290268
OS 53.91801764 -38.36365708
OS 53.92633868 -38.35441148
OS 53.92726324 -38.35348692
OS 53.92911236 -38.35256236
OS 53.93188604 -38.34978868
OS 53.93558428 -38.347015
OS 53.94020708 -38.34331676
OS 53.946679 -38.33961852
OS 53.95407548 -38.33499572
OS 53.96147196 -38.33037292
OS 53.97071756 -38.32575012
OS 53.98088772 -38.32112732
OS 53.99198244 -38.31742908
OS 54.00400172 -38.31373084
OS 54.0298894 -38.30818348
OS 54.04468236 -38.30725892
OS 54.05947532 -38.30633436
OS 54.06779636 -38.30633436
OS 54.07334372 -38.30725892
OE
OB 53.23846604 -38.94890356 I
OS 53.14878372 -38.94890356
OS 53.14878372 -38.85922124
OS 53.23846604 -38.85922124
OS 53.23846604 -38.94890356
OE
OB 53.00177868 -38.39231844 I
OS 52.74567556 -38.39231844
OS 52.71146684 -38.56521116
OS 52.7123914 -38.5642866
OS 52.71424052 -38.56336204
OS 52.7170142 -38.56151292
OS 52.721637 -38.55873924
OS 52.72718436 -38.55596556
OS 52.73365628 -38.55226732
OS 52.74844924 -38.54487084
OS 52.76694044 -38.53747436
OS 52.78728076 -38.53100244
OS 52.8094702 -38.52637964
OS 52.82056492 -38.52453052
OS 52.84090524 -38.52453052
OS 52.8464526 -38.52545508
OS 52.85384908 -38.52637964
OS 52.86217012 -38.5273042
OS 52.87141572 -38.52915332
OS 52.88158588 -38.531927
OS 52.90377532 -38.53839892
OS 52.9157946 -38.54302172
OS 52.92781388 -38.54949364
OS 52.93983316 -38.55596556
OS 52.95185244 -38.56336204
OS 52.96294716 -38.57260764
OS 52.97404188 -38.5827778
OS 52.97496644 -38.58370236
OS 52.97681556 -38.58555148
OS 52.97958924 -38.58832516
OS 52.98328748 -38.59294796
OS 52.98791028 -38.59941988
OS 52.99253308 -38.6058918
OS 52.99808044 -38.61421284
OS 53.0036278 -38.62345844
OS 53.0082506 -38.6336286
OS 53.01379796 -38.64472332
OS 53.01842076 -38.65766716
OS 53.02304356 -38.670611
OS 53.0267418 -38.6844794
OS 53.02951548 -38.70019692
OS 53.0313646 -38.71591444
OS 53.03228916 -38.73255652
OS 53.03228916 -38.73348108
OS 53.03228916 -38.73625476
OS 53.03228916 -38.74087756
OS 53.0313646 -38.74734948
OS 53.03044004 -38.75474596
OS 53.02951548 -38.763067
OS 53.02766636 -38.77323716
OS 53.02581724 -38.78340732
OS 53.02026988 -38.80744588
OS 53.01102428 -38.832409
OS 53.00547692 -38.84535284
OS 52.99808044 -38.85737212
OS 52.99068396 -38.87031596
OS 52.98143836 -38.88233524
OS 52.9805138 -38.8832598
OS 52.97866468 -38.88603348
OS 52.97496644 -38.88973172
OS 52.97034364 -38.89435452
OS 52.96387172 -38.89990188
OS 52.95647524 -38.90729836
OS 52.94722964 -38.91377028
OS 52.93705948 -38.92116676
OS 52.92596476 -38.92856324
OS 52.91302092 -38.93503516
OS 52.89915252 -38.94150708
OS 52.88435956 -38.947979
OS 52.86864204 -38.9526018
OS 52.8510754 -38.95630004
OS 52.8325842 -38.95907372
OS 52.81316844 -38.95999828
OS 52.8048474 -38.95999828
OS 52.79837548 -38.95907372
OS 52.790979 -38.95814916
OS 52.78265796 -38.9572246
OS 52.7724878 -38.95630004
OS 52.76231764 -38.95352636
OS 52.73920364 -38.947979
OS 52.71608964 -38.93965796
OS 52.70407036 -38.9341106
OS 52.69205108 -38.92763868
OS 52.68095636 -38.9202422
OS 52.66986164 -38.91192116
OS 52.66893708 -38.9109966
OS 52.66708796 -38.91007204
OS 52.66523884 -38.9063738
OS 52.6615406 -38.90267556
OS 52.6569178 -38.89805276
OS 52.652295 -38.8925054
OS 52.64674764 -38.88510892
OS 52.64212484 -38.87678788
OS 52.63657748 -38.86846684
OS 52.63103012 -38.85829668
OS 52.62085996 -38.83610724
OS 52.61253892 -38.81021956
OS 52.60976524 -38.79635116
OS 52.60791612 -38.7815582
OS 52.69020196 -38.77508628
OS 52.69020196 -38.77601084
OS 52.69020196 -38.77785996
OS 52.69112652 -38.78063364
OS 52.69205108 -38.78525644
OS 52.69482476 -38.7954266
OS 52.698523 -38.809295
OS 52.70407036 -38.8231634
OS 52.71146684 -38.83888092
OS 52.72071244 -38.85274932
OS 52.73180716 -38.86569316
OS 52.73365628 -38.86661772
OS 52.73735452 -38.87031596
OS 52.744751 -38.87493876
OS 52.75492116 -38.88048612
OS 52.76601588 -38.88603348
OS 52.77988428 -38.89065628
OS 52.7956018 -38.89435452
OS 52.81316844 -38.89527908
OS 52.8187158 -38.89527908
OS 52.82241404 -38.89435452
OS 52.83350876 -38.89342996
OS 52.8464526 -38.88973172
OS 52.86217012 -38.88510892
OS 52.87788764 -38.87771244
OS 52.89452972 -38.86661772
OS 52.9019262 -38.8601458
OS 52.90932268 -38.85274932
OS 52.91024724 -38.85182476
OS 52.9111718 -38.8509002
OS 52.91302092 -38.84812652
OS 52.9157946 -38.84535284
OS 52.92226652 -38.83518268
OS 52.929663 -38.82223884
OS 52.93613492 -38.80652132
OS 52.94260684 -38.78710556
OS 52.94722964 -38.76399156
OS 52.94907876 -38.75197228
OS 52.94907876 -38.73902844
OS 52.94907876 -38.73810388
OS 52.94907876 -38.73625476
OS 52.94907876 -38.73255652
OS 52.9481542 -38.72793372
OS 52.9481542 -38.72238636
OS 52.94722964 -38.71591444
OS 52.94445596 -38.70112148
OS 52.93983316 -38.68355484
OS 52.93336124 -38.6659882
OS 52.92411564 -38.64934612
OS 52.9111718 -38.6336286
OS 52.9111718 -38.63270404
OS 52.90932268 -38.63177948
OS 52.90469988 -38.62715668
OS 52.89637884 -38.62068476
OS 52.88528412 -38.61328828
OS 52.87049116 -38.60681636
OS 52.85384908 -38.60034444
OS 52.83443332 -38.59572164
OS 52.8233386 -38.59387252
OS 52.80577196 -38.59387252
OS 52.79837548 -38.59479708
OS 52.78912988 -38.59572164
OS 52.77803516 -38.59849532
OS 52.76694044 -38.601269
OS 52.75492116 -38.6058918
OS 52.74290188 -38.61143916
OS 52.74197732 -38.61236372
OS 52.73827908 -38.61421284
OS 52.73273172 -38.61883564
OS 52.72533524 -38.62345844
OS 52.71793876 -38.62993036
OS 52.71054228 -38.6382514
OS 52.70222124 -38.64657244
OS 52.69574932 -38.6567426
OS 52.62178452 -38.64657244
OS 52.68373004 -38.31742908
OS 53.00177868 -38.31742908
OS 53.00177868 -38.39231844
OE
OB 53.23846604 -38.57445676 I
OS 53.14878372 -38.57445676
OS 53.14878372 -38.48477444
OS 53.23846604 -38.48477444
OS 53.23846604 -38.57445676
OE
OB 54.48199924 -38.57445676 I
OS 54.39231692 -38.57445676
OS 54.39231692 -38.48477444
OS 54.48199924 -38.48477444
OS 54.48199924 -38.57445676
OE
OB 56.14990548 -38.3100326 I
OS 56.165623 -38.31095716
OS 56.18226508 -38.31188172
OS 56.1979826 -38.31373084
OS 56.211851 -38.31557996
OS 56.21370012 -38.31557996
OS 56.22017204 -38.31742908
OS 56.22849308 -38.3192782
OS 56.2395878 -38.32205188
OS 56.25160708 -38.32667468
OS 56.26455092 -38.33222204
OS 56.27841932 -38.33869396
OS 56.2904386 -38.34609044
OS 56.29228772 -38.347015
OS 56.29598596 -38.34978868
OS 56.30153332 -38.35533604
OS 56.3089298 -38.36180796
OS 56.31725084 -38.370129
OS 56.32557188 -38.38122372
OS 56.33481748 -38.393243
OS 56.34221396 -38.4071114
OS 56.34313852 -38.40896052
OS 56.34498764 -38.41358332
OS 56.34868588 -38.42190436
OS 56.35238412 -38.43299908
OS 56.3551578 -38.44594292
OS 56.35885604 -38.46073588
OS 56.36070516 -38.47737796
OS 56.36162972 -38.4949446
OS 56.36162972 -38.49586916
OS 56.36162972 -38.49864284
OS 56.36162972 -38.50234108
OS 56.36070516 -38.508813
OS 56.3597806 -38.51528492
OS 56.35885604 -38.52360596
OS 56.35700692 -38.53285156
OS 56.3551578 -38.54302172
OS 56.34868588 -38.5642866
OS 56.34498764 -38.57538132
OS 56.33944028 -38.5874006
OS 56.33296836 -38.59941988
OS 56.32649644 -38.6105146
OS 56.3181754 -38.62160932
OS 56.3089298 -38.63270404
OS 56.30800524 -38.6336286
OS 56.30615612 -38.63547772
OS 56.30338244 -38.6382514
OS 56.29875964 -38.64102508
OS 56.29321228 -38.64564788
OS 56.2858158 -38.65027068
OS 56.2765702 -38.65581804
OS 56.26640004 -38.66044084
OS 56.25438076 -38.6659882
OS 56.24051236 -38.67153556
OS 56.2257194 -38.67615836
OS 56.20815276 -38.6798566
OS 56.18966156 -38.68355484
OS 56.16932124 -38.68632852
OS 56.14620724 -38.68817764
OS 56.12216868 -38.6891022
OS 55.95852156 -38.6891022
OS 55.95852156 -38.94890356
OS 55.87346204 -38.94890356
OS 55.87346204 -38.30910804
OS 56.13603708 -38.30910804
OS 56.14990548 -38.3100326
OE
OB 57.07723916 -38.94890356 I
OS 56.99587788 -38.94890356
OS 56.99587788 -38.41358332
OS 56.80911676 -38.94890356
OS 56.73330284 -38.94890356
OS 56.54839084 -38.40433772
OS 56.54839084 -38.94890356
OS 56.46702956 -38.94890356
OS 56.46702956 -38.30910804
OS 56.59369428 -38.30910804
OS 56.74532212 -38.763067
OS 56.74532212 -38.76399156
OS 56.74624668 -38.76584068
OS 56.74717124 -38.76861436
OS 56.74902036 -38.77323716
OS 56.7527186 -38.78433188
OS 56.7573414 -38.79820028
OS 56.7619642 -38.8139178
OS 56.76751156 -38.82963532
OS 56.77213436 -38.84442828
OS 56.7758326 -38.85737212
OS 56.77675716 -38.855523
OS 56.77768172 -38.8509002
OS 56.7804554 -38.84257916
OS 56.78415364 -38.83148444
OS 56.78877644 -38.81669148
OS 56.79524836 -38.79912484
OS 56.80172028 -38.77878452
OS 56.81004132 -38.75474596
OS 56.96351828 -38.30910804
OS 57.07723916 -38.30910804
OS 57.07723916 -38.94890356
OE
OB 55.39084172 -38.94890356 I
OS 55.31225412 -38.94890356
OS 55.31225412 -38.4487166
OS 55.31132956 -38.44964116
OS 55.30670676 -38.4533394
OS 55.3011594 -38.45888676
OS 55.2919138 -38.46535868
OS 55.28174364 -38.47367972
OS 55.2687998 -38.48292532
OS 55.25400684 -38.49309548
OS 55.23736476 -38.50326564
OS 55.2364402 -38.50326564
OS 55.23551564 -38.5041902
OS 55.22996828 -38.50788844
OS 55.22072268 -38.51251124
OS 55.20962796 -38.5180586
OS 55.19668412 -38.52453052
OS 55.18281572 -38.53100244
OS 55.16894732 -38.53747436
OS 55.15507892 -38.54302172
OS 55.15507892 -38.4672078
OS 55.15600348 -38.4672078
OS 55.1578526 -38.46535868
OS 55.16155084 -38.46443412
OS 55.16617364 -38.46166044
OS 55.171721 -38.45888676
OS 55.17819292 -38.45518852
OS 55.19391044 -38.44594292
OS 55.21240164 -38.43577276
OS 55.23089284 -38.42282892
OS 55.2503086 -38.40803596
OS 55.26972436 -38.39231844
OS 55.27064892 -38.39139388
OS 55.27157348 -38.39046932
OS 55.27434716 -38.38769564
OS 55.2780454 -38.38492196
OS 55.28636644 -38.37567636
OS 55.29746116 -38.36458164
OS 55.30855588 -38.3516378
OS 55.32057516 -38.33684484
OS 55.33074532 -38.32205188
OS 55.33999092 -38.30633436
OS 55.39084172 -38.30633436
OS 55.39084172 -38.94890356
OE
OB 54.48199924 -38.94890356 I
OS 54.39231692 -38.94890356
OS 54.39231692 -38.85922124
OS 54.48199924 -38.85922124
OS 54.48199924 -38.94890356
OE
OB 54.825011 -38.30725892 I
OS 54.83703028 -38.30910804
OS 54.85089868 -38.31188172
OS 54.86569164 -38.31557996
OS 54.88140916 -38.32020276
OS 54.89620212 -38.32759924
OS 54.89712668 -38.32759924
OS 54.89805124 -38.3285238
OS 54.90267404 -38.33129748
OS 54.91007052 -38.33592028
OS 54.91931612 -38.3423922
OS 54.92948628 -38.3516378
OS 54.940581 -38.36180796
OS 54.95075116 -38.37382724
OS 54.96092132 -38.38769564
OS 54.96184588 -38.38954476
OS 54.96554412 -38.39416756
OS 54.96924236 -38.4024886
OS 54.97571428 -38.41450788
OS 54.98126164 -38.42837628
OS 54.98865812 -38.4440938
OS 54.99513004 -38.462585
OS 55.0006774 -38.48292532
OS 55.0006774 -38.48384988
OS 55.00160196 -38.485699
OS 55.00252652 -38.48847268
OS 55.00345108 -38.49309548
OS 55.00437564 -38.49864284
OS 55.0053002 -38.50511476
OS 55.00714932 -38.5134358
OS 55.00807388 -38.5226814
OS 55.009923 -38.53285156
OS 55.01084756 -38.54394628
OS 55.01177212 -38.55689012
OS 55.01362124 -38.56983396
OS 55.0145458 -38.58462692
OS 55.0145458 -38.59941988
OS 55.01547036 -38.61606196
OS 55.01547036 -38.6336286
OS 55.01547036 -38.63455316
OS 55.01547036 -38.6382514
OS 55.01547036 -38.64472332
OS 55.01547036 -38.6521198
OS 55.0145458 -38.66228996
OS 55.0145458 -38.67338468
OS 55.01362124 -38.68540396
OS 55.01269668 -38.6983478
OS 55.009923 -38.72793372
OS 55.0053002 -38.7584442
OS 54.99975284 -38.78803012
OS 54.9960546 -38.80189852
OS 54.9914318 -38.81576692
OS 54.9914318 -38.81669148
OS 54.99050724 -38.8185406
OS 54.98865812 -38.82223884
OS 54.986809 -38.82686164
OS 54.98495988 -38.83333356
OS 54.98126164 -38.83980548
OS 54.97386516 -38.855523
OS 54.96461956 -38.87216508
OS 54.95260028 -38.89065628
OS 54.93873188 -38.90729836
OS 54.9220898 -38.92301588
OS 54.92116524 -38.92301588
OS 54.92024068 -38.924865
OS 54.917467 -38.92671412
OS 54.91376876 -38.92856324
OS 54.90914596 -38.93133692
OS 54.90452316 -38.93503516
OS 54.89065476 -38.94150708
OS 54.87401268 -38.947979
OS 54.85459692 -38.95445092
OS 54.83148292 -38.95814916
OS 54.8065198 -38.95999828
OS 54.7972742 -38.95999828
OS 54.79080228 -38.95907372
OS 54.7834058 -38.95814916
OS 54.7741602 -38.95630004
OS 54.76399004 -38.95445092
OS 54.75289532 -38.95167724
OS 54.7418006 -38.947979
OS 54.72978132 -38.94428076
OS 54.71776204 -38.9387334
OS 54.70574276 -38.93226148
OS 54.69372348 -38.924865
OS 54.6817042 -38.9156194
OS 54.67060948 -38.90544924
OS 54.66043932 -38.89435452
OS 54.65951476 -38.89342996
OS 54.65766564 -38.89065628
OS 54.65489196 -38.88603348
OS 54.65026916 -38.878637
OS 54.64564636 -38.87031596
OS 54.64102356 -38.85922124
OS 54.63455164 -38.8462774
OS 54.62900428 -38.83148444
OS 54.62345692 -38.81484236
OS 54.61790956 -38.7954266
OS 54.6123622 -38.77416172
OS 54.6077394 -38.75012316
OS 54.6031166 -38.72423548
OS 54.60034292 -38.69649868
OS 54.5984938 -38.6659882
OS 54.59756924 -38.6336286
OS 54.59756924 -38.63270404
OS 54.59756924 -38.6290058
OS 54.59756924 -38.62253388
OS 54.59756924 -38.6151374
OS 54.5984938 -38.60496724
OS 54.5984938 -38.59387252
OS 54.59941836 -38.58185324
OS 54.60034292 -38.56798484
OS 54.6031166 -38.53932348
OS 54.6077394 -38.508813
OS 54.61328676 -38.47830252
OS 54.616985 -38.46443412
OS 54.62068324 -38.45056572
OS 54.62068324 -38.44964116
OS 54.6216078 -38.44779204
OS 54.62345692 -38.4440938
OS 54.62530604 -38.439471
OS 54.62715516 -38.43299908
OS 54.6308534 -38.42652716
OS 54.63824988 -38.41080964
OS 54.64749548 -38.39416756
OS 54.65951476 -38.37660092
OS 54.67338316 -38.35903428
OS 54.69002524 -38.34424132
OS 54.6909498 -38.34424132
OS 54.69187436 -38.3423922
OS 54.69464804 -38.34054308
OS 54.69834628 -38.33869396
OS 54.70296908 -38.33499572
OS 54.70851644 -38.33222204
OS 54.72238484 -38.32482556
OS 54.73902692 -38.31835364
OS 54.75844268 -38.31188172
OS 54.78155668 -38.30818348
OS 54.8065198 -38.30633436
OS 54.81484084 -38.30633436
OS 54.825011 -38.30725892
OE
OB 49.95350436 -38.72331092 I
OS 50.040413 -38.72331092
OS 50.040413 -38.7954266
OS 49.95350436 -38.7954266
OS 49.95350436 -38.94890356
OS 49.87491676 -38.94890356
OS 49.87491676 -38.7954266
OS 49.5966242 -38.7954266
OS 49.5966242 -38.72331092
OS 49.88970972 -38.30910804
OS 49.95350436 -38.30910804
OS 49.95350436 -38.72331092
OE
OB 50.1467374 -38.95999828 I
OS 50.08386732 -38.95999828
OS 50.26970388 -38.29801332
OS 50.33257396 -38.29801332
OS 50.1467374 -38.95999828
OE
OB 50.59699812 -38.30725892 I
OS 50.6043946 -38.30818348
OS 50.6136402 -38.30910804
OS 50.62381036 -38.31095716
OS 50.63398052 -38.31280628
OS 50.65801908 -38.3192782
OS 50.68205764 -38.3285238
OS 50.69407692 -38.33407116
OS 50.7060962 -38.34054308
OS 50.71719092 -38.34886412
OS 50.72736108 -38.35810972
OS 50.72828564 -38.35903428
OS 50.73013476 -38.35995884
OS 50.73198388 -38.36365708
OS 50.73568212 -38.36735532
OS 50.74030492 -38.37197812
OS 50.74492772 -38.37845004
OS 50.74955052 -38.38492196
OS 50.75509788 -38.393243
OS 50.76434348 -38.41080964
OS 50.77358908 -38.43299908
OS 50.77728732 -38.4440938
OS 50.77913644 -38.45703764
OS 50.78098556 -38.46998148
OS 50.78191012 -38.48384988
OS 50.78191012 -38.485699
OS 50.78191012 -38.4903218
OS 50.78098556 -38.49771828
OS 50.780061 -38.50788844
OS 50.77821188 -38.51898316
OS 50.77451364 -38.531927
OS 50.7708154 -38.5457954
OS 50.76526804 -38.5596638
OS 50.76434348 -38.56151292
OS 50.76249436 -38.56613572
OS 50.75879612 -38.5735322
OS 50.75324876 -38.58370236
OS 50.74585228 -38.59479708
OS 50.73660668 -38.60866548
OS 50.72551196 -38.62253388
OS 50.71256812 -38.6382514
OS 50.710719 -38.64010052
OS 50.7060962 -38.64564788
OS 50.7014734 -38.65027068
OS 50.6968506 -38.65489348
OS 50.69130324 -38.66044084
OS 50.68390676 -38.66783732
OS 50.67651028 -38.6752338
OS 50.66726468 -38.68355484
OS 50.65801908 -38.69280044
OS 50.64692436 -38.7029706
OS 50.63490508 -38.71314076
OS 50.62196124 -38.72516004
OS 50.60716828 -38.73717932
OS 50.59237532 -38.75012316
OS 50.59145076 -38.75104772
OS 50.58960164 -38.75289684
OS 50.5859034 -38.75567052
OS 50.5812806 -38.75936876
OS 50.57573324 -38.76491612
OS 50.56926132 -38.77046348
OS 50.55446836 -38.78248276
OS 50.53875084 -38.79635116
OS 50.52395788 -38.81021956
OS 50.51101404 -38.82223884
OS 50.50546668 -38.82686164
OS 50.50084388 -38.83148444
OS 50.49991932 -38.832409
OS 50.49714564 -38.83518268
OS 50.4934474 -38.83888092
OS 50.4888246 -38.84442828
OS 50.4842018 -38.8509002
OS 50.47865444 -38.85737212
OS 50.46755972 -38.87308964
OS 50.78283468 -38.87308964
OS 50.78283468 -38.94890356
OS 50.35846164 -38.94890356
OS 50.35846164 -38.947979
OS 50.35846164 -38.94428076
OS 50.35846164 -38.9387334
OS 50.3593862 -38.93133692
OS 50.36031076 -38.92301588
OS 50.36215988 -38.91377028
OS 50.364009 -38.90452468
OS 50.36770724 -38.89435452
OS 50.36770724 -38.89342996
OS 50.3686318 -38.8925054
OS 50.37048092 -38.88695804
OS 50.37417916 -38.878637
OS 50.37972652 -38.86754228
OS 50.387123 -38.85459844
OS 50.3963686 -38.83980548
OS 50.40653876 -38.82501252
OS 50.4194826 -38.809295
OS 50.4194826 -38.80837044
OS 50.42133172 -38.80744588
OS 50.42595452 -38.80189852
OS 50.43427556 -38.79357748
OS 50.44629484 -38.7815582
OS 50.46016324 -38.7676898
OS 50.47772988 -38.75104772
OS 50.49899476 -38.73255652
OS 50.52210876 -38.71314076
OS 50.52303332 -38.7122162
OS 50.52673156 -38.70944252
OS 50.53227892 -38.70481972
OS 50.53875084 -38.69927236
OS 50.54707188 -38.69187588
OS 50.55724204 -38.68355484
OS 50.5674122 -38.67430924
OS 50.57943148 -38.66413908
OS 50.60254548 -38.64194964
OS 50.62565948 -38.6197602
OS 50.6367542 -38.60866548
OS 50.64692436 -38.59757076
OS 50.65616996 -38.5874006
OS 50.66356644 -38.57723044
OS 50.66356644 -38.57630588
OS 50.66541556 -38.57538132
OS 50.66726468 -38.57260764
OS 50.6691138 -38.5689094
OS 50.67558572 -38.55873924
OS 50.6829822 -38.54671996
OS 50.68945412 -38.531927
OS 50.69592604 -38.51620948
OS 50.69962428 -38.49864284
OS 50.7014734 -38.48200076
OS 50.7014734 -38.4810762
OS 50.7014734 -38.48015164
OS 50.70054884 -38.47460428
OS 50.69962428 -38.46535868
OS 50.6968506 -38.45518852
OS 50.69315236 -38.44224468
OS 50.68668044 -38.42930084
OS 50.6783594 -38.416357
OS 50.66726468 -38.40341316
OS 50.66541556 -38.40156404
OS 50.66079276 -38.3978658
OS 50.65432084 -38.393243
OS 50.64415068 -38.38677108
OS 50.63120684 -38.38122372
OS 50.61641388 -38.37567636
OS 50.59884724 -38.37197812
OS 50.57943148 -38.37105356
OS 50.57388412 -38.37105356
OS 50.57018588 -38.37197812
OS 50.55909116 -38.37290268
OS 50.54614732 -38.37567636
OS 50.53227892 -38.3793746
OS 50.5165614 -38.38584652
OS 50.50176844 -38.39416756
OS 50.48790004 -38.40526228
OS 50.48605092 -38.4071114
OS 50.48235268 -38.4117342
OS 50.47680532 -38.41913068
OS 50.47125796 -38.4302254
OS 50.46478604 -38.44316924
OS 50.45923868 -38.45981132
OS 50.45554044 -38.47830252
OS 50.45369132 -38.4995674
OS 50.3732546 -38.49124636
OS 50.3732546 -38.4903218
OS 50.37417916 -38.48754812
OS 50.37417916 -38.48292532
OS 50.37510372 -38.4764534
OS 50.37695284 -38.46905692
OS 50.37880196 -38.46073588
OS 50.38157564 -38.45056572
OS 50.38434932 -38.44039556
OS 50.3917458 -38.41820612
OS 50.40284052 -38.39601668
OS 50.40931244 -38.38492196
OS 50.41763348 -38.37382724
OS 50.42595452 -38.36365708
OS 50.43520012 -38.35441148
OS 50.43612468 -38.35348692
OS 50.4379738 -38.35256236
OS 50.44074748 -38.34978868
OS 50.44537028 -38.347015
OS 50.45091764 -38.34331676
OS 50.45738956 -38.33961852
OS 50.46478604 -38.33499572
OS 50.47403164 -38.33037292
OS 50.4842018 -38.32575012
OS 50.49529652 -38.32112732
OS 50.5073158 -38.31742908
OS 50.52025964 -38.31373084
OS 50.53412804 -38.31095716
OS 50.548921 -38.30818348
OS 50.56463852 -38.30725892
OS 50.5812806 -38.30633436
OS 50.5905262 -38.30633436
OS 50.59699812 -38.30725892
OE
OB 48.67576244 -38.94890356 I
OS 48.59717484 -38.94890356
OS 48.59717484 -38.4487166
OS 48.59625028 -38.44964116
OS 48.59162748 -38.4533394
OS 48.58608012 -38.45888676
OS 48.57683452 -38.46535868
OS 48.56666436 -38.47367972
OS 48.55372052 -38.48292532
OS 48.53892756 -38.49309548
OS 48.52228548 -38.50326564
OS 48.52136092 -38.50326564
OS 48.52043636 -38.5041902
OS 48.514889 -38.50788844
OS 48.5056434 -38.51251124
OS 48.49454868 -38.5180586
OS 48.48160484 -38.52453052
OS 48.46773644 -38.53100244
OS 48.45386804 -38.53747436
OS 48.43999964 -38.54302172
OS 48.43999964 -38.4672078
OS 48.4409242 -38.4672078
OS 48.44277332 -38.46535868
OS 48.44647156 -38.46443412
OS 48.45109436 -38.46166044
OS 48.45664172 -38.45888676
OS 48.46311364 -38.45518852
OS 48.47883116 -38.44594292
OS 48.49732236 -38.43577276
OS 48.51581356 -38.42282892
OS 48.53522932 -38.40803596
OS 48.55464508 -38.39231844
OS 48.55556964 -38.39139388
OS 48.5564942 -38.39046932
OS 48.55926788 -38.38769564
OS 48.56296612 -38.38492196
OS 48.57128716 -38.37567636
OS 48.58238188 -38.36458164
OS 48.5934766 -38.3516378
OS 48.60549588 -38.33684484
OS 48.61566604 -38.32205188
OS 48.62491164 -38.30633436
OS 48.67576244 -38.30633436
OS 48.67576244 -38.94890356
OE
OB 48.9032042 -38.95999828 I
OS 48.84033412 -38.95999828
OS 49.02617068 -38.29801332
OS 49.08904076 -38.29801332
OS 48.9032042 -38.95999828
OE
OB 49.35346492 -38.30725892 I
OS 49.3608614 -38.30818348
OS 49.370107 -38.30910804
OS 49.38027716 -38.31095716
OS 49.39044732 -38.31280628
OS 49.41448588 -38.3192782
OS 49.43852444 -38.3285238
OS 49.45054372 -38.33407116
OS 49.462563 -38.34054308
OS 49.47365772 -38.34886412
OS 49.48382788 -38.35810972
OS 49.48475244 -38.35903428
OS 49.48660156 -38.35995884
OS 49.48845068 -38.36365708
OS 49.49214892 -38.36735532
OS 49.49677172 -38.37197812
OS 49.50139452 -38.37845004
OS 49.50601732 -38.38492196
OS 49.51156468 -38.393243
OS 49.52081028 -38.41080964
OS 49.53005588 -38.43299908
OS 49.53375412 -38.4440938
OS 49.53560324 -38.45703764
OS 49.53745236 -38.46998148
OS 49.53837692 -38.48384988
OS 49.53837692 -38.485699
OS 49.53837692 -38.4903218
OS 49.53745236 -38.49771828
OS 49.5365278 -38.50788844
OS 49.53467868 -38.51898316
OS 49.53098044 -38.531927
OS 49.5272822 -38.5457954
OS 49.52173484 -38.5596638
OS 49.52081028 -38.56151292
OS 49.51896116 -38.56613572
OS 49.51526292 -38.5735322
OS 49.50971556 -38.58370236
OS 49.50231908 -38.59479708
OS 49.49307348 -38.60866548
OS 49.48197876 -38.62253388
OS 49.46903492 -38.6382514
OS 49.4671858 -38.64010052
OS 49.462563 -38.64564788
OS 49.4579402 -38.65027068
OS 49.4533174 -38.65489348
OS 49.44777004 -38.66044084
OS 49.44037356 -38.66783732
OS 49.43297708 -38.6752338
OS 49.42373148 -38.68355484
OS 49.41448588 -38.69280044
OS 49.40339116 -38.7029706
OS 49.39137188 -38.71314076
OS 49.37842804 -38.72516004
OS 49.36363508 -38.73717932
OS 49.34884212 -38.75012316
OS 49.34791756 -38.75104772
OS 49.34606844 -38.75289684
OS 49.3423702 -38.75567052
OS 49.3377474 -38.75936876
OS 49.33220004 -38.76491612
OS 49.32572812 -38.77046348
OS 49.31093516 -38.78248276
OS 49.29521764 -38.79635116
OS 49.28042468 -38.81021956
OS 49.26748084 -38.82223884
OS 49.26193348 -38.82686164
OS 49.25731068 -38.83148444
OS 49.25638612 -38.832409
OS 49.25361244 -38.83518268
OS 49.2499142 -38.83888092
OS 49.2452914 -38.84442828
OS 49.2406686 -38.8509002
OS 49.23512124 -38.85737212
OS 49.22402652 -38.87308964
OS 49.53930148 -38.87308964
OS 49.53930148 -38.94890356
OS 49.11492844 -38.94890356
OS 49.11492844 -38.947979
OS 49.11492844 -38.94428076
OS 49.11492844 -38.9387334
OS 49.115853 -38.93133692
OS 49.11677756 -38.92301588
OS 49.11862668 -38.91377028
OS 49.1204758 -38.90452468
OS 49.12417404 -38.89435452
OS 49.12417404 -38.89342996
OS 49.1250986 -38.8925054
OS 49.12694772 -38.88695804
OS 49.13064596 -38.878637
OS 49.13619332 -38.86754228
OS 49.1435898 -38.85459844
OS 49.1528354 -38.83980548
OS 49.16300556 -38.82501252
OS 49.1759494 -38.809295
OS 49.1759494 -38.80837044
OS 49.17779852 -38.80744588
OS 49.18242132 -38.80189852
OS 49.19074236 -38.79357748
OS 49.20276164 -38.7815582
OS 49.21663004 -38.7676898
OS 49.23419668 -38.75104772
OS 49.25546156 -38.73255652
OS 49.27857556 -38.71314076
OS 49.27950012 -38.7122162
OS 49.28319836 -38.70944252
OS 49.28874572 -38.70481972
OS 49.29521764 -38.69927236
OS 49.30353868 -38.69187588
OS 49.31370884 -38.68355484
OS 49.323879 -38.67430924
OS 49.33589828 -38.66413908
OS 49.35901228 -38.64194964
OS 49.38212628 -38.6197602
OS 49.393221 -38.60866548
OS 49.40339116 -38.59757076
OS 49.41263676 -38.5874006
OS 49.42003324 -38.57723044
OS 49.42003324 -38.57630588
OS 49.42188236 -38.57538132
OS 49.42373148 -38.57260764
OS 49.4255806 -38.5689094
OS 49.43205252 -38.55873924
OS 49.439449 -38.54671996
OS 49.44592092 -38.531927
OS 49.45239284 -38.51620948
OS 49.45609108 -38.49864284
OS 49.4579402 -38.48200076
OS 49.4579402 -38.4810762
OS 49.4579402 -38.48015164
OS 49.45701564 -38.47460428
OS 49.45609108 -38.46535868
OS 49.4533174 -38.45518852
OS 49.44961916 -38.44224468
OS 49.44314724 -38.42930084
OS 49.4348262 -38.416357
OS 49.42373148 -38.40341316
OS 49.42188236 -38.40156404
OS 49.41725956 -38.3978658
OS 49.41078764 -38.393243
OS 49.40061748 -38.38677108
OS 49.38767364 -38.38122372
OS 49.37288068 -38.37567636
OS 49.35531404 -38.37197812
OS 49.33589828 -38.37105356
OS 49.33035092 -38.37105356
OS 49.32665268 -38.37197812
OS 49.31555796 -38.37290268
OS 49.30261412 -38.37567636
OS 49.28874572 -38.3793746
OS 49.2730282 -38.38584652
OS 49.25823524 -38.39416756
OS 49.24436684 -38.40526228
OS 49.24251772 -38.4071114
OS 49.23881948 -38.4117342
OS 49.23327212 -38.41913068
OS 49.22772476 -38.4302254
OS 49.22125284 -38.44316924
OS 49.21570548 -38.45981132
OS 49.21200724 -38.47830252
OS 49.21015812 -38.4995674
OS 49.1297214 -38.49124636
OS 49.1297214 -38.4903218
OS 49.13064596 -38.48754812
OS 49.13064596 -38.48292532
OS 49.13157052 -38.4764534
OS 49.13341964 -38.46905692
OS 49.13526876 -38.46073588
OS 49.13804244 -38.45056572
OS 49.14081612 -38.44039556
OS 49.1482126 -38.41820612
OS 49.15930732 -38.39601668
OS 49.16577924 -38.38492196
OS 49.17410028 -38.37382724
OS 49.18242132 -38.36365708
OS 49.19166692 -38.35441148
OS 49.19259148 -38.35348692
OS 49.1944406 -38.35256236
OS 49.19721428 -38.34978868
OS 49.20183708 -38.347015
OS 49.20738444 -38.34331676
OS 49.21385636 -38.33961852
OS 49.22125284 -38.33499572
OS 49.23049844 -38.33037292
OS 49.2406686 -38.32575012
OS 49.25176332 -38.32112732
OS 49.2637826 -38.31742908
OS 49.27672644 -38.31373084
OS 49.29059484 -38.31095716
OS 49.3053878 -38.30818348
OS 49.32110532 -38.30725892
OS 49.3377474 -38.30633436
OS 49.346993 -38.30633436
OS 49.35346492 -38.30725892
OE
OB 51.0944114 -38.30725892 I
OS 51.10643068 -38.30910804
OS 51.12029908 -38.31188172
OS 51.13509204 -38.31557996
OS 51.15080956 -38.32020276
OS 51.16560252 -38.32759924
OS 51.16652708 -38.32759924
OS 51.16745164 -38.3285238
OS 51.17207444 -38.33129748
OS 51.17947092 -38.33592028
OS 51.18871652 -38.3423922
OS 51.19888668 -38.3516378
OS 51.2099814 -38.36180796
OS 51.22015156 -38.37382724
OS 51.23032172 -38.38769564
OS 51.23124628 -38.38954476
OS 51.23494452 -38.39416756
OS 51.23864276 -38.4024886
OS 51.24511468 -38.41450788
OS 51.25066204 -38.42837628
OS 51.25805852 -38.4440938
OS 51.26453044 -38.462585
OS 51.2700778 -38.48292532
OS 51.2700778 -38.48384988
OS 51.27100236 -38.485699
OS 51.27192692 -38.48847268
OS 51.27285148 -38.49309548
OS 51.27377604 -38.49864284
OS 51.2747006 -38.50511476
OS 51.27654972 -38.5134358
OS 51.27747428 -38.5226814
OS 51.2793234 -38.53285156
OS 51.28024796 -38.54394628
OS 51.28117252 -38.55689012
OS 51.28302164 -38.56983396
OS 51.2839462 -38.58462692
OS 51.2839462 -38.59941988
OS 51.28487076 -38.61606196
OS 51.28487076 -38.6336286
OS 51.28487076 -38.63455316
OS 51.28487076 -38.6382514
OS 51.28487076 -38.64472332
OS 51.28487076 -38.6521198
OS 51.2839462 -38.66228996
OS 51.2839462 -38.67338468
OS 51.28302164 -38.68540396
OS 51.28209708 -38.6983478
OS 51.2793234 -38.72793372
OS 51.2747006 -38.7584442
OS 51.26915324 -38.78803012
OS 51.265455 -38.80189852
OS 51.2608322 -38.81576692
OS 51.2608322 -38.81669148
OS 51.25990764 -38.8185406
OS 51.25805852 -38.82223884
OS 51.2562094 -38.82686164
OS 51.25436028 -38.83333356
OS 51.25066204 -38.83980548
OS 51.24326556 -38.855523
OS 51.23401996 -38.87216508
OS 51.22200068 -38.89065628
OS 51.20813228 -38.90729836
OS 51.1914902 -38.92301588
OS 51.19056564 -38.92301588
OS 51.18964108 -38.924865
OS 51.1868674 -38.92671412
OS 51.18316916 -38.92856324
OS 51.17854636 -38.93133692
OS 51.17392356 -38.93503516
OS 51.16005516 -38.94150708
OS 51.14341308 -38.947979
OS 51.12399732 -38.95445092
OS 51.10088332 -38.95814916
OS 51.0759202 -38.95999828
OS 51.0666746 -38.95999828
OS 51.06020268 -38.95907372
OS 51.0528062 -38.95814916
OS 51.0435606 -38.95630004
OS 51.03339044 -38.95445092
OS 51.02229572 -38.95167724
OS 51.011201 -38.947979
OS 50.99918172 -38.94428076
OS 50.98716244 -38.9387334
OS 50.97514316 -38.93226148
OS 50.96312388 -38.924865
OS 50.9511046 -38.9156194
OS 50.94000988 -38.90544924
OS 50.92983972 -38.89435452
OS 50.92891516 -38.89342996
OS 50.92706604 -38.89065628
OS 50.92429236 -38.88603348
OS 50.91966956 -38.878637
OS 50.91504676 -38.87031596
OS 50.91042396 -38.85922124
OS 50.90395204 -38.8462774
OS 50.89840468 -38.83148444
OS 50.89285732 -38.81484236
OS 50.88730996 -38.7954266
OS 50.8817626 -38.77416172
OS 50.8771398 -38.75012316
OS 50.872517 -38.72423548
OS 50.86974332 -38.69649868
OS 50.8678942 -38.6659882
OS 50.86696964 -38.6336286
OS 50.86696964 -38.63270404
OS 50.86696964 -38.6290058
OS 50.86696964 -38.62253388
OS 50.86696964 -38.6151374
OS 50.8678942 -38.60496724
OS 50.8678942 -38.59387252
OS 50.86881876 -38.58185324
OS 50.86974332 -38.56798484
OS 50.872517 -38.53932348
OS 50.8771398 -38.508813
OS 50.88268716 -38.47830252
OS 50.8863854 -38.46443412
OS 50.89008364 -38.45056572
OS 50.89008364 -38.44964116
OS 50.8910082 -38.44779204
OS 50.89285732 -38.4440938
OS 50.89470644 -38.439471
OS 50.89655556 -38.43299908
OS 50.9002538 -38.42652716
OS 50.90765028 -38.41080964
OS 50.91689588 -38.39416756
OS 50.92891516 -38.37660092
OS 50.94278356 -38.35903428
OS 50.95942564 -38.34424132
OS 50.9603502 -38.34424132
OS 50.96127476 -38.3423922
OS 50.96404844 -38.34054308
OS 50.96774668 -38.33869396
OS 50.97236948 -38.33499572
OS 50.97791684 -38.33222204
OS 50.99178524 -38.32482556
OS 51.00842732 -38.31835364
OS 51.02784308 -38.31188172
OS 51.05095708 -38.30818348
OS 51.0759202 -38.30633436
OS 51.08424124 -38.30633436
OS 51.0944114 -38.30725892
OE
OB 51.59182468 -38.30725892 I
OS 51.59922116 -38.30818348
OS 51.60846676 -38.30910804
OS 51.61863692 -38.31095716
OS 51.62880708 -38.31280628
OS 51.65284564 -38.3192782
OS 51.6768842 -38.3285238
OS 51.68890348 -38.33407116
OS 51.70092276 -38.34054308
OS 51.71201748 -38.34886412
OS 51.72218764 -38.35810972
OS 51.7231122 -38.35903428
OS 51.72496132 -38.35995884
OS 51.72681044 -38.36365708
OS 51.73050868 -38.36735532
OS 51.73513148 -38.37197812
OS 51.73975428 -38.37845004
OS 51.74437708 -38.38492196
OS 51.74992444 -38.393243
OS 51.75917004 -38.41080964
OS 51.76841564 -38.43299908
OS 51.77211388 -38.4440938
OS 51.773963 -38.45703764
OS 51.77581212 -38.46998148
OS 51.77673668 -38.48384988
OS 51.77673668 -38.485699
OS 51.77673668 -38.4903218
OS 51.77581212 -38.49771828
OS 51.77488756 -38.50788844
OS 51.77303844 -38.51898316
OS 51.7693402 -38.531927
OS 51.76564196 -38.5457954
OS 51.7600946 -38.5596638
OS 51.75917004 -38.56151292
OS 51.75732092 -38.56613572
OS 51.75362268 -38.5735322
OS 51.74807532 -38.58370236
OS 51.74067884 -38.59479708
OS 51.73143324 -38.60866548
OS 51.72033852 -38.62253388
OS 51.70739468 -38.6382514
OS 51.70554556 -38.64010052
OS 51.70092276 -38.64564788
OS 51.69629996 -38.65027068
OS 51.69167716 -38.65489348
OS 51.6861298 -38.66044084
OS 51.67873332 -38.66783732
OS 51.67133684 -38.6752338
OS 51.66209124 -38.68355484
OS 51.65284564 -38.69280044
OS 51.64175092 -38.7029706
OS 51.62973164 -38.71314076
OS 51.6167878 -38.72516004
OS 51.60199484 -38.73717932
OS 51.58720188 -38.75012316
OS 51.58627732 -38.75104772
OS 51.5844282 -38.75289684
OS 51.58072996 -38.75567052
OS 51.57610716 -38.75936876
OS 51.5705598 -38.76491612
OS 51.56408788 -38.77046348
OS 51.54929492 -38.78248276
OS 51.5335774 -38.79635116
OS 51.51878444 -38.81021956
OS 51.5058406 -38.82223884
OS 51.50029324 -38.82686164
OS 51.49567044 -38.83148444
OS 51.49474588 -38.832409
OS 51.4919722 -38.83518268
OS 51.48827396 -38.83888092
OS 51.48365116 -38.84442828
OS 51.47902836 -38.8509002
OS 51.473481 -38.85737212
OS 51.46238628 -38.87308964
OS 51.77766124 -38.87308964
OS 51.77766124 -38.94890356
OS 51.3532882 -38.94890356
OS 51.3532882 -38.947979
OS 51.3532882 -38.94428076
OS 51.3532882 -38.9387334
OS 51.35421276 -38.93133692
OS 51.35513732 -38.92301588
OS 51.35698644 -38.91377028
OS 51.35883556 -38.90452468
OS 51.3625338 -38.89435452
OS 51.3625338 -38.89342996
OS 51.36345836 -38.8925054
OS 51.36530748 -38.88695804
OS 51.36900572 -38.878637
OS 51.37455308 -38.86754228
OS 51.38194956 -38.85459844
OS 51.39119516 -38.83980548
OS 51.40136532 -38.82501252
OS 51.41430916 -38.809295
OS 51.41430916 -38.80837044
OS 51.41615828 -38.80744588
OS 51.42078108 -38.80189852
OS 51.42910212 -38.79357748
OS 51.4411214 -38.7815582
OS 51.4549898 -38.7676898
OS 51.47255644 -38.75104772
OS 51.49382132 -38.73255652
OS 51.51693532 -38.71314076
OS 51.51785988 -38.7122162
OS 51.52155812 -38.70944252
OS 51.52710548 -38.70481972
OS 51.5335774 -38.69927236
OS 51.54189844 -38.69187588
OS 51.5520686 -38.68355484
OS 51.56223876 -38.67430924
OS 51.57425804 -38.66413908
OS 51.59737204 -38.64194964
OS 51.62048604 -38.6197602
OS 51.63158076 -38.60866548
OS 51.64175092 -38.59757076
OS 51.65099652 -38.5874006
OS 51.658393 -38.57723044
OS 51.658393 -38.57630588
OS 51.66024212 -38.57538132
OS 51.66209124 -38.57260764
OS 51.66394036 -38.5689094
OS 51.67041228 -38.55873924
OS 51.67780876 -38.54671996
OS 51.68428068 -38.531927
OS 51.6907526 -38.51620948
OS 51.69445084 -38.49864284
OS 51.69629996 -38.48200076
OS 51.69629996 -38.4810762
OS 51.69629996 -38.48015164
OS 51.6953754 -38.47460428
OS 51.69445084 -38.46535868
OS 51.69167716 -38.45518852
OS 51.68797892 -38.44224468
OS 51.681507 -38.42930084
OS 51.67318596 -38.416357
OS 51.66209124 -38.40341316
OS 51.66024212 -38.40156404
OS 51.65561932 -38.3978658
OS 51.6491474 -38.393243
OS 51.63897724 -38.38677108
OS 51.6260334 -38.38122372
OS 51.61124044 -38.37567636
OS 51.5936738 -38.37197812
OS 51.57425804 -38.37105356
OS 51.56871068 -38.37105356
OS 51.56501244 -38.37197812
OS 51.55391772 -38.37290268
OS 51.54097388 -38.37567636
OS 51.52710548 -38.3793746
OS 51.51138796 -38.38584652
OS 51.496595 -38.39416756
OS 51.4827266 -38.40526228
OS 51.48087748 -38.4071114
OS 51.47717924 -38.4117342
OS 51.47163188 -38.41913068
OS 51.46608452 -38.4302254
OS 51.4596126 -38.44316924
OS 51.45406524 -38.45981132
OS 51.450367 -38.47830252
OS 51.44851788 -38.4995674
OS 51.36808116 -38.49124636
OS 51.36808116 -38.4903218
OS 51.36900572 -38.48754812
OS 51.36900572 -38.48292532
OS 51.36993028 -38.4764534
OS 51.3717794 -38.46905692
OS 51.37362852 -38.46073588
OS 51.3764022 -38.45056572
OS 51.37917588 -38.44039556
OS 51.38657236 -38.41820612
OS 51.39766708 -38.39601668
OS 51.404139 -38.38492196
OS 51.41246004 -38.37382724
OS 51.42078108 -38.36365708
OS 51.43002668 -38.35441148
OS 51.43095124 -38.35348692
OS 51.43280036 -38.35256236
OS 51.43557404 -38.34978868
OS 51.44019684 -38.347015
OS 51.4457442 -38.34331676
OS 51.45221612 -38.33961852
OS 51.4596126 -38.33499572
OS 51.4688582 -38.33037292
OS 51.47902836 -38.32575012
OS 51.49012308 -38.32112732
OS 51.50214236 -38.31742908
OS 51.5150862 -38.31373084
OS 51.5289546 -38.31095716
OS 51.54374756 -38.30818348
OS 51.55946508 -38.30725892
OS 51.57610716 -38.30633436
OS 51.58535276 -38.30633436
OS 51.59182468 -38.30725892
OE
OB 52.08184148 -38.30725892 I
OS 52.09386076 -38.30910804
OS 52.10865372 -38.31188172
OS 52.1252958 -38.31650452
OS 52.14193788 -38.32205188
OS 52.15857996 -38.32944836
OS 52.15950452 -38.32944836
OS 52.16042908 -38.33037292
OS 52.16597644 -38.3331466
OS 52.17429748 -38.33869396
OS 52.18354308 -38.34516588
OS 52.1946378 -38.35441148
OS 52.20573252 -38.36458164
OS 52.21682724 -38.37660092
OS 52.22607284 -38.39046932
OS 52.2269974 -38.39231844
OS 52.22977108 -38.39694124
OS 52.23346932 -38.40526228
OS 52.23809212 -38.41543244
OS 52.24271492 -38.42745172
OS 52.24641316 -38.44132012
OS 52.24918684 -38.45703764
OS 52.2501114 -38.47275516
OS 52.2501114 -38.47460428
OS 52.2501114 -38.48015164
OS 52.24918684 -38.48754812
OS 52.24733772 -38.49771828
OS 52.24456404 -38.50973756
OS 52.23994124 -38.5226814
OS 52.23439388 -38.53562524
OS 52.2269974 -38.54856908
OS 52.22607284 -38.5504182
OS 52.22329916 -38.55411644
OS 52.2177518 -38.56058836
OS 52.21035532 -38.56798484
OS 52.20110972 -38.57630588
OS 52.190015 -38.58555148
OS 52.17707116 -38.59387252
OS 52.16135364 -38.60219356
OS 52.1622782 -38.60219356
OS 52.16412732 -38.60311812
OS 52.166901 -38.60404268
OS 52.17059924 -38.60496724
OS 52.1807694 -38.60866548
OS 52.19371324 -38.61421284
OS 52.2085062 -38.62160932
OS 52.22329916 -38.63085492
OS 52.23716756 -38.6428742
OS 52.2501114 -38.6567426
OS 52.25103596 -38.65859172
OS 52.2547342 -38.66413908
OS 52.26028156 -38.67338468
OS 52.26582892 -38.68540396
OS 52.27137628 -38.70019692
OS 52.27692364 -38.71776356
OS 52.28062188 -38.73810388
OS 52.28154644 -38.76029332
OS 52.28154644 -38.76121788
OS 52.28154644 -38.76399156
OS 52.28154644 -38.76861436
OS 52.28062188 -38.77416172
OS 52.27969732 -38.7815582
OS 52.2778482 -38.78987924
OS 52.27599908 -38.79912484
OS 52.27414996 -38.809295
OS 52.26675348 -38.83148444
OS 52.26120612 -38.84350372
OS 52.25565876 -38.85459844
OS 52.24826228 -38.86661772
OS 52.23994124 -38.878637
OS 52.23069564 -38.89065628
OS 52.21960092 -38.901751
OS 52.21867636 -38.90267556
OS 52.21682724 -38.90452468
OS 52.213129 -38.90729836
OS 52.2085062 -38.9109966
OS 52.20295884 -38.9156194
OS 52.19556236 -38.9202422
OS 52.18724132 -38.92578956
OS 52.17707116 -38.93041236
OS 52.166901 -38.93595972
OS 52.15488172 -38.94150708
OS 52.14286244 -38.94612988
OS 52.12899404 -38.95075268
OS 52.11420108 -38.95445092
OS 52.09848356 -38.9572246
OS 52.08276604 -38.95907372
OS 52.0651994 -38.95999828
OS 52.05687836 -38.95999828
OS 52.051331 -38.95907372
OS 52.04393452 -38.95814916
OS 52.03561348 -38.9572246
OS 52.02636788 -38.95537548
OS 52.01619772 -38.95352636
OS 51.99400828 -38.947979
OS 51.97089428 -38.9387334
OS 51.958875 -38.93318604
OS 51.94778028 -38.92671412
OS 51.93668556 -38.91839308
OS 51.92559084 -38.91007204
OS 51.92466628 -38.90914748
OS 51.92281716 -38.90729836
OS 51.92004348 -38.90452468
OS 51.9172698 -38.90082644
OS 51.912647 -38.89620364
OS 51.9080242 -38.88973172
OS 51.90247684 -38.8832598
OS 51.89692948 -38.87493876
OS 51.89138212 -38.86569316
OS 51.88583476 -38.85644756
OS 51.8756646 -38.83425812
OS 51.86734356 -38.80837044
OS 51.86456988 -38.79450204
OS 51.86272076 -38.77970908
OS 51.94130836 -38.76953892
OS 51.94130836 -38.77046348
OS 51.94223292 -38.7723126
OS 51.94315748 -38.77601084
OS 51.94408204 -38.78063364
OS 51.9450066 -38.786181
OS 51.94685572 -38.79265292
OS 51.95147852 -38.80652132
OS 51.95795044 -38.8231634
OS 51.96627148 -38.83888092
OS 51.97551708 -38.85367388
OS 51.9866118 -38.86661772
OS 51.98846092 -38.86754228
OS 51.99215916 -38.87124052
OS 51.99955564 -38.87586332
OS 52.00880124 -38.88048612
OS 52.01989596 -38.88603348
OS 52.03376436 -38.89065628
OS 52.04948188 -38.89435452
OS 52.06612396 -38.89527908
OS 52.07167132 -38.89527908
OS 52.07536956 -38.89435452
OS 52.08553972 -38.89342996
OS 52.09848356 -38.89065628
OS 52.11327652 -38.88603348
OS 52.12899404 -38.87956156
OS 52.14471156 -38.87031596
OS 52.15950452 -38.85737212
OS 52.16135364 -38.855523
OS 52.16597644 -38.84997564
OS 52.1715238 -38.8416546
OS 52.17892028 -38.83055988
OS 52.18631676 -38.81669148
OS 52.19186412 -38.80097396
OS 52.19648692 -38.78248276
OS 52.19833604 -38.76214244
OS 52.19833604 -38.76121788
OS 52.19833604 -38.75936876
OS 52.19833604 -38.75659508
OS 52.19741148 -38.75289684
OS 52.19648692 -38.74272668
OS 52.19371324 -38.7307074
OS 52.190015 -38.71591444
OS 52.18354308 -38.70112148
OS 52.17429748 -38.68632852
OS 52.1622782 -38.67246012
OS 52.16042908 -38.670611
OS 52.15580628 -38.66691276
OS 52.1484098 -38.6613654
OS 52.13823964 -38.65489348
OS 52.1252958 -38.64842156
OS 52.10957828 -38.6428742
OS 52.09201164 -38.63917596
OS 52.07259588 -38.63732684
OS 52.06427484 -38.63732684
OS 52.05780292 -38.6382514
OS 52.04948188 -38.63917596
OS 52.04023628 -38.64102508
OS 52.02914156 -38.6428742
OS 52.01712228 -38.64564788
OS 52.02636788 -38.57630588
OS 52.03099068 -38.57630588
OS 52.03468892 -38.57723044
OS 52.0467082 -38.57723044
OS 52.05687836 -38.57538132
OS 52.06889764 -38.5735322
OS 52.08276604 -38.57075852
OS 52.09848356 -38.56613572
OS 52.11327652 -38.5596638
OS 52.12899404 -38.55134276
OS 52.1299186 -38.55134276
OS 52.13084316 -38.5504182
OS 52.13546596 -38.54671996
OS 52.14193788 -38.54024804
OS 52.14933436 -38.531927
OS 52.15673084 -38.51990772
OS 52.16320276 -38.50603932
OS 52.16782556 -38.4903218
OS 52.16967468 -38.4810762
OS 52.16967468 -38.47090604
OS 52.16967468 -38.46998148
OS 52.16967468 -38.46905692
OS 52.16967468 -38.46350956
OS 52.16782556 -38.45611308
OS 52.16597644 -38.44594292
OS 52.1622782 -38.4348482
OS 52.1576554 -38.42282892
OS 52.15025892 -38.41080964
OS 52.14008876 -38.39971492
OS 52.1391642 -38.39879036
OS 52.1345414 -38.39509212
OS 52.12806948 -38.39046932
OS 52.11974844 -38.38492196
OS 52.10865372 -38.38029916
OS 52.09570988 -38.37567636
OS 52.08091692 -38.37197812
OS 52.06427484 -38.37105356
OS 52.05687836 -38.37105356
OS 52.04855732 -38.37290268
OS 52.0374626 -38.3747518
OS 52.02544332 -38.37845004
OS 52.01342404 -38.38307284
OS 52.0004802 -38.39046932
OS 51.98846092 -38.39971492
OS 51.98753636 -38.40063948
OS 51.98383812 -38.40526228
OS 51.97829076 -38.4117342
OS 51.97181884 -38.4209798
OS 51.96534692 -38.43299908
OS 51.958875 -38.44779204
OS 51.95332764 -38.46535868
OS 51.9496294 -38.485699
OS 51.8710418 -38.4718306
OS 51.8710418 -38.47090604
OS 51.87196636 -38.46813236
OS 51.87289092 -38.46443412
OS 51.87381548 -38.45888676
OS 51.8756646 -38.45241484
OS 51.87843828 -38.44501836
OS 51.88398564 -38.42745172
OS 51.89323124 -38.4071114
OS 51.90432596 -38.38677108
OS 51.91819436 -38.36735532
OS 51.935761 -38.34978868
OS 51.93668556 -38.34886412
OS 51.93853468 -38.34793956
OS 51.94130836 -38.34609044
OS 51.9450066 -38.34331676
OS 51.9496294 -38.33961852
OS 51.95610132 -38.33592028
OS 51.96257324 -38.33222204
OS 51.97089428 -38.32759924
OS 51.98938548 -38.32020276
OS 52.01065036 -38.31280628
OS 52.03561348 -38.30818348
OS 52.04855732 -38.30633436
OS 52.07167132 -38.30633436
OS 52.08184148 -38.30725892
OE
OB 56.14158444 -38.38492196 H
OS 55.95852156 -38.38492196
OS 55.95852156 -38.61328828
OS 56.13048972 -38.61328828
OS 56.13696164 -38.61236372
OS 56.14343356 -38.61236372
OS 56.15083004 -38.61143916
OS 56.16839668 -38.60959004
OS 56.18781244 -38.6058918
OS 56.2072282 -38.60034444
OS 56.22479484 -38.59294796
OS 56.23311588 -38.58832516
OS 56.2395878 -38.5827778
OS 56.24143692 -38.58092868
OS 56.24513516 -38.57723044
OS 56.25068252 -38.56983396
OS 56.25715444 -38.56058836
OS 56.26362636 -38.54856908
OS 56.26917372 -38.53377612
OS 56.27287196 -38.51713404
OS 56.27472108 -38.49771828
OS 56.27472108 -38.49679372
OS 56.27472108 -38.49586916
OS 56.27472108 -38.49124636
OS 56.27379652 -38.48292532
OS 56.2719474 -38.47367972
OS 56.27009828 -38.46350956
OS 56.26640004 -38.45149028
OS 56.26085268 -38.44039556
OS 56.25438076 -38.42930084
OS 56.2534562 -38.42837628
OS 56.25068252 -38.42467804
OS 56.24605972 -38.42005524
OS 56.24051236 -38.41358332
OS 56.23219132 -38.4071114
OS 56.22294572 -38.40156404
OS 56.21277556 -38.39601668
OS 56.20075628 -38.39139388
OS 56.19983172 -38.39139388
OS 56.19613348 -38.39046932
OS 56.19058612 -38.38954476
OS 56.18318964 -38.38769564
OS 56.17209492 -38.38677108
OS 56.15822652 -38.38584652
OS 56.14158444 -38.38492196
OE
OB 49.87491676 -38.43669732 H
OS 49.67336268 -38.72331092
OS 49.87491676 -38.72331092
OS 49.87491676 -38.43669732
OE
OB 54.06132444 -38.37105356 H
OS 54.05392796 -38.37105356
OS 54.04560692 -38.37290268
OS 54.0345122 -38.3747518
OS 54.02249292 -38.37845004
OS 54.00954908 -38.38307284
OS 53.9975298 -38.39046932
OS 53.98551052 -38.40063948
OS 53.98458596 -38.40156404
OS 53.98088772 -38.40526228
OS 53.97626492 -38.4117342
OS 53.97164212 -38.42005524
OS 53.96609476 -38.4302254
OS 53.96147196 -38.44224468
OS 53.95777372 -38.45518852
OS 53.95684916 -38.46998148
OS 53.95684916 -38.47090604
OS 53.95684916 -38.4718306
OS 53.95777372 -38.47737796
OS 53.95869828 -38.485699
OS 53.9605474 -38.49586916
OS 53.96424564 -38.50788844
OS 53.96886844 -38.51990772
OS 53.97626492 -38.53285156
OS 53.98551052 -38.54394628
OS 53.98643508 -38.54487084
OS 53.99105788 -38.54856908
OS 53.9975298 -38.55319188
OS 54.00585084 -38.55781468
OS 54.01694556 -38.56336204
OS 54.0298894 -38.56798484
OS 54.04468236 -38.57168308
OS 54.06132444 -38.57260764
OS 54.06317356 -38.57260764
OS 54.06872092 -38.57168308
OS 54.07704196 -38.57075852
OS 54.08813668 -38.5689094
OS 54.10015596 -38.56521116
OS 54.11217524 -38.56058836
OS 54.12511908 -38.55319188
OS 54.1362138 -38.54394628
OS 54.13713836 -38.54302172
OS 54.1408366 -38.53839892
OS 54.1454594 -38.53285156
OS 54.15100676 -38.52453052
OS 54.15655412 -38.51436036
OS 54.16117692 -38.50234108
OS 54.16487516 -38.48847268
OS 54.16579972 -38.47367972
OS 54.16579972 -38.47275516
OS 54.16579972 -38.4718306
OS 54.16579972 -38.46628324
OS 54.1639506 -38.4579622
OS 54.16210148 -38.44779204
OS 54.15840324 -38.43669732
OS 54.15285588 -38.42467804
OS 54.1454594 -38.41265876
OS 54.13528924 -38.40063948
OS 54.13436468 -38.39971492
OS 54.12974188 -38.39601668
OS 54.12326996 -38.39139388
OS 54.11494892 -38.38584652
OS 54.1038542 -38.38029916
OS 54.09183492 -38.37567636
OS 54.07704196 -38.37197812
OS 54.06132444 -38.37105356
OE
OB 54.05855076 -38.63640228 H
OS 54.0530034 -38.63640228
OS 54.04930516 -38.63732684
OS 54.039135 -38.6382514
OS 54.02619116 -38.64102508
OS 54.0113982 -38.64564788
OS 53.99660524 -38.6521198
OS 53.98088772 -38.6613654
OS 53.96701932 -38.67338468
OS 53.9651702 -38.6752338
OS 53.96147196 -38.6798566
OS 53.9559246 -38.68817764
OS 53.94945268 -38.6983478
OS 53.9420562 -38.7122162
OS 53.93650884 -38.72793372
OS 53.9328106 -38.74550036
OS 53.93096148 -38.76491612
OS 53.93096148 -38.76676524
OS 53.93096148 -38.77046348
OS 53.93188604 -38.7769354
OS 53.9328106 -38.78525644
OS 53.93465972 -38.7954266
OS 53.9374334 -38.80652132
OS 53.94113164 -38.81761604
OS 53.94575444 -38.82963532
OS 53.946679 -38.83055988
OS 53.94852812 -38.83518268
OS 53.95222636 -38.84073004
OS 53.95777372 -38.84720196
OS 53.96424564 -38.855523
OS 53.97256668 -38.86384404
OS 53.98181228 -38.87124052
OS 53.992907 -38.878637
OS 53.99475612 -38.87956156
OS 53.99845436 -38.88141068
OS 54.00492628 -38.88418436
OS 54.01324732 -38.88695804
OS 54.02341748 -38.88973172
OS 54.03543676 -38.8925054
OS 54.0483806 -38.89435452
OS 54.06132444 -38.89527908
OS 54.0668718 -38.89527908
OS 54.07057004 -38.89435452
OS 54.08166476 -38.89342996
OS 54.0946086 -38.89065628
OS 54.10940156 -38.88603348
OS 54.12511908 -38.88048612
OS 54.13991204 -38.87124052
OS 54.154705 -38.85922124
OS 54.15655412 -38.85737212
OS 54.16025236 -38.85274932
OS 54.16672428 -38.84442828
OS 54.1731962 -38.83425812
OS 54.17966812 -38.82131428
OS 54.18614004 -38.80559676
OS 54.18983828 -38.78710556
OS 54.1916874 -38.7676898
OS 54.1916874 -38.76676524
OS 54.1916874 -38.76491612
OS 54.1916874 -38.76214244
OS 54.19076284 -38.7584442
OS 54.18983828 -38.74827404
OS 54.1870646 -38.73440564
OS 54.1824418 -38.72053724
OS 54.17596988 -38.70481972
OS 54.16672428 -38.6891022
OS 54.15378044 -38.67430924
OS 54.15193132 -38.67246012
OS 54.14730852 -38.66876188
OS 54.13898748 -38.66228996
OS 54.12789276 -38.65489348
OS 54.11402436 -38.64842156
OS 54.09738228 -38.64194964
OS 54.07889108 -38.6382514
OS 54.05855076 -38.63640228
OE
OB 54.80559524 -38.37105356 H
OS 54.80004788 -38.37105356
OS 54.79634964 -38.37197812
OS 54.78617948 -38.37382724
OS 54.7741602 -38.37660092
OS 54.7602918 -38.38214828
OS 54.74549884 -38.39046932
OS 54.73810236 -38.39601668
OS 54.73070588 -38.40156404
OS 54.72423396 -38.40896052
OS 54.71776204 -38.41728156
OS 54.71776204 -38.41820612
OS 54.71591292 -38.42005524
OS 54.7140638 -38.42375348
OS 54.71129012 -38.42837628
OS 54.70851644 -38.43577276
OS 54.7048182 -38.4440938
OS 54.70204452 -38.45426396
OS 54.69834628 -38.46628324
OS 54.69464804 -38.48015164
OS 54.6909498 -38.49586916
OS 54.68725156 -38.5134358
OS 54.68447788 -38.53285156
OS 54.6817042 -38.555041
OS 54.67985508 -38.57907956
OS 54.67893052 -38.60496724
OS 54.67800596 -38.6336286
OS 54.67800596 -38.63547772
OS 54.67800596 -38.64010052
OS 54.67800596 -38.64842156
OS 54.67893052 -38.65951628
OS 54.67893052 -38.67153556
OS 54.67985508 -38.68632852
OS 54.68077964 -38.70204604
OS 54.68262876 -38.71868812
OS 54.68725156 -38.75474596
OS 54.69002524 -38.7723126
OS 54.69372348 -38.78895468
OS 54.69742172 -38.8046722
OS 54.70296908 -38.81946516
OS 54.70851644 -38.832409
OS 54.71498836 -38.84350372
OS 54.71498836 -38.84442828
OS 54.71683748 -38.84535284
OS 54.72146028 -38.85182476
OS 54.72978132 -38.8601458
OS 54.73995148 -38.8693914
OS 54.75381988 -38.878637
OS 54.7695374 -38.88695804
OS 54.78710404 -38.89342996
OS 54.79634964 -38.89435452
OS 54.8065198 -38.89527908
OS 54.81206716 -38.89527908
OS 54.8157654 -38.89435452
OS 54.825011 -38.8925054
OS 54.83795484 -38.88880716
OS 54.85182324 -38.88233524
OS 54.86754076 -38.87308964
OS 54.87493724 -38.86754228
OS 54.88233372 -38.8601458
OS 54.8897302 -38.85274932
OS 54.89712668 -38.84350372
OS 54.89712668 -38.84257916
OS 54.8989758 -38.84073004
OS 54.90082492 -38.83795636
OS 54.90267404 -38.83333356
OS 54.90637228 -38.82686164
OS 54.90914596 -38.8185406
OS 54.9128442 -38.809295
OS 54.91654244 -38.79820028
OS 54.91931612 -38.78433188
OS 54.92301436 -38.76953892
OS 54.9267126 -38.75197228
OS 54.92948628 -38.73348108
OS 54.9313354 -38.71129164
OS 54.93318452 -38.68817764
OS 54.93503364 -38.66228996
OS 54.93503364 -38.6336286
OS 54.93503364 -38.63270404
OS 54.93503364 -38.63177948
OS 54.93503364 -38.62715668
OS 54.93503364 -38.61883564
OS 54.93410908 -38.60774092
OS 54.93410908 -38.59572164
OS 54.93318452 -38.58092868
OS 54.93225996 -38.56521116
OS 54.93041084 -38.54764452
OS 54.92578804 -38.51251124
OS 54.92301436 -38.4949446
OS 54.91931612 -38.47830252
OS 54.91561788 -38.462585
OS 54.91007052 -38.44779204
OS 54.90452316 -38.4348482
OS 54.89805124 -38.42375348
OS 54.89805124 -38.42282892
OS 54.89620212 -38.42190436
OS 54.894353 -38.41913068
OS 54.89157932 -38.41543244
OS 54.88325828 -38.4071114
OS 54.87308812 -38.39694124
OS 54.85921972 -38.38769564
OS 54.8435022 -38.3793746
OS 54.83518116 -38.37567636
OS 54.82593556 -38.37290268
OS 54.8157654 -38.37197812
OS 54.80559524 -38.37105356
OE
OB 51.07499564 -38.37105356 H
OS 51.06944828 -38.37105356
OS 51.06575004 -38.37197812
OS 51.05557988 -38.37382724
OS 51.0435606 -38.37660092
OS 51.0296922 -38.38214828
OS 51.01489924 -38.39046932
OS 51.00750276 -38.39601668
OS 51.00010628 -38.40156404
OS 50.99363436 -38.40896052
OS 50.98716244 -38.41728156
OS 50.98716244 -38.41820612
OS 50.98531332 -38.42005524
OS 50.9834642 -38.42375348
OS 50.98069052 -38.42837628
OS 50.97791684 -38.43577276
OS 50.9742186 -38.4440938
OS 50.97144492 -38.45426396
OS 50.96774668 -38.46628324
OS 50.96404844 -38.48015164
OS 50.9603502 -38.49586916
OS 50.95665196 -38.5134358
OS 50.95387828 -38.53285156
OS 50.9511046 -38.555041
OS 50.94925548 -38.57907956
OS 50.94833092 -38.60496724
OS 50.94740636 -38.6336286
OS 50.94740636 -38.63547772
OS 50.94740636 -38.64010052
OS 50.94740636 -38.64842156
OS 50.94833092 -38.65951628
OS 50.94833092 -38.67153556
OS 50.94925548 -38.68632852
OS 50.95018004 -38.70204604
OS 50.95202916 -38.71868812
OS 50.95665196 -38.75474596
OS 50.95942564 -38.7723126
OS 50.96312388 -38.78895468
OS 50.96682212 -38.8046722
OS 50.97236948 -38.81946516
OS 50.97791684 -38.832409
OS 50.98438876 -38.84350372
OS 50.98438876 -38.84442828
OS 50.98623788 -38.84535284
OS 50.99086068 -38.85182476
OS 50.99918172 -38.8601458
OS 51.00935188 -38.8693914
OS 51.02322028 -38.878637
OS 51.0389378 -38.88695804
OS 51.05650444 -38.89342996
OS 51.06575004 -38.89435452
OS 51.0759202 -38.89527908
OS 51.08146756 -38.89527908
OS 51.0851658 -38.89435452
OS 51.0944114 -38.8925054
OS 51.10735524 -38.88880716
OS 51.12122364 -38.88233524
OS 51.13694116 -38.87308964
OS 51.14433764 -38.86754228
OS 51.15173412 -38.8601458
OS 51.1591306 -38.85274932
OS 51.16652708 -38.84350372
OS 51.16652708 -38.84257916
OS 51.1683762 -38.84073004
OS 51.17022532 -38.83795636
OS 51.17207444 -38.83333356
OS 51.17577268 -38.82686164
OS 51.17854636 -38.8185406
OS 51.1822446 -38.809295
OS 51.18594284 -38.79820028
OS 51.18871652 -38.78433188
OS 51.19241476 -38.76953892
OS 51.196113 -38.75197228
OS 51.19888668 -38.73348108
OS 51.2007358 -38.71129164
OS 51.20258492 -38.68817764
OS 51.20443404 -38.66228996
OS 51.20443404 -38.6336286
OS 51.20443404 -38.63270404
OS 51.20443404 -38.63177948
OS 51.20443404 -38.62715668
OS 51.20443404 -38.61883564
OS 51.20350948 -38.60774092
OS 51.20350948 -38.59572164
OS 51.20258492 -38.58092868
OS 51.20166036 -38.56521116
OS 51.19981124 -38.54764452
OS 51.19518844 -38.51251124
OS 51.19241476 -38.4949446
OS 51.18871652 -38.47830252
OS 51.18501828 -38.462585
OS 51.17947092 -38.44779204
OS 51.17392356 -38.4348482
OS 51.16745164 -38.42375348
OS 51.16745164 -38.42282892
OS 51.16560252 -38.42190436
OS 51.1637534 -38.41913068
OS 51.16097972 -38.41543244
OS 51.15265868 -38.4071114
OS 51.14248852 -38.39694124
OS 51.12862012 -38.38769564
OS 51.1129026 -38.3793746
OS 51.10458156 -38.37567636
OS 51.09533596 -38.37290268
OS 51.0851658 -38.37197812
OS 51.07499564 -38.37105356
OE
SE

### steps/pcb/layers/top_solder/features
UNITS=MM
#Layer_Color=8388736
#
#Feature symbol names
#
$0 r99.9998
$1 r1999.99854
$2 r2190.0007
$3 r5699.99876
$4 r1623.9998
$5 r1662.00074
$6 r1899.99874

#
#Feature attribute names
#
@0 .nomenclature
@1 .string
@2 .string_angle
@3 .geometry
@4 .pad_usage

#
#Feature attribute text strings
#
&0 SMD_RoundX1000.0005Y1000.0005
&1 Pad_Simple_X2090.0009Y2090.0009H1090.0004C2106.0004
&2 Pad_Simple_X5299.9996Y5299.9996H2999.9991C4015.9991
&3 Pad_Simple_X1524.0000Y1524.0000H762.0000C1778.0000
&4 Pad_Simple_X1562.0009Y1562.0009H961.9996C1977.9996
&5 Pad_Simple_X0.0000Y0.0000H3700.0002C4716.0002
&6 Pad_Simple_X1799.9989Y1799.9989H1200.0001C2216.0001

#
#Layer features
#
L -9.5600012 -24.45999934 40.4400004 -24.45999934 0 P 0
L -9.5600012 -35.9599992 -9.5600012 -24.45999934 0 P 0
L -9.5600012 -35.9599992 28.439999 -35.9599992 0 P 0
L -9.5600012 -39.45999982 -9.5600012 -35.9599992 0 P 0
L -9.5600012 -39.45999982 28.439999 -39.45999982 0 P 0
L -9.5600012 -42.96000044 -9.5600012 -39.45999982 0 P 0
L -9.5600012 -42.96000044 28.439999 -42.96000044 0 P 0
L -10.0600002 -23.96000034 62.93999858 -23.96000034 0 P 0
L -10.0600002 -43.45999944 -10.0600002 -23.96000034 0 P 0
L -10.0600002 -43.45999944 62.93999858 -43.45999944 0 P 0
L 28.439999 -35.96000174 45.44000056 -35.9599992 0 P 0
L 28.439999 -39.45999982 28.439999 -35.9599992 0 P 0
L 28.439999 -39.46000236 45.44000056 -39.45999982 0 P 0
L 28.439999 -42.96000044 28.439999 -39.45999982 0 P 0
L 28.439999 -42.96000298 45.44000056 -42.96000044 0 P 0
L 40.4400004 -24.45999934 62.43999958 -24.45999934 0 P 0
L 40.4400004 -35.9599992 40.4400004 -24.45999934 0 P 0
L 45.44000056 -35.9599992 62.43999958 -35.9599992 0 P 0
L 45.44000056 -39.45999982 62.43999958 -39.45999982 0 P 0
L 45.44000056 -42.96000044 45.44000056 -35.9599992 0 P 0
L 45.44000056 -42.96000044 62.43999958 -42.96000044 0 P 0
L 62.43999958 -35.9599992 62.43999958 -24.45999934 0 P 0
L 62.43999958 -42.96000044 62.43999958 -35.9599992 0 P 0
L 62.93999858 -43.45999944 62.93999858 -23.96000034 0 P 0
P -2.20000068 -2.69999968 1 P 0 0 ;3=0,4=0
P -2.37499906 43.52500058 1 P 0 0 ;3=0,4=0
P 0 0 2 P 0 0 ;3=1,4=0
P 0 40.64 2 P 0 0 ;3=1,4=0
P 2.0779994 43.3299997 2 P 0 0 ;3=1,4=0
P 4.39999882 2.00000108 0 P 0 0 ;3=5,4=0
P 4.39999882 38.599999 0 P 0 0 ;3=5,4=0
P 4.8300005 7.63999996 6 P 0 0 ;3=6,4=0
P 4.8300005 7.63999996 4 P 0 0 ;3=3,4=0
P 4.8300005 12.71999996 6 P 0 0 ;3=6,4=0
P 4.8300005 12.71999996 4 P 0 0 ;3=3,4=0
P 4.8300005 17.79999996 6 P 0 0 ;3=6,4=0
P 4.8300005 17.79999996 4 P 0 0 ;3=3,4=0
P 4.8300005 33.03999996 6 P 0 0 ;3=6,4=0
P 4.8300005 33.03999996 4 P 0 0 ;3=3,4=0
P 5.1259994 43.3299997 2 P 0 0 ;3=1,4=0
P 8.1739994 43.3299997 2 P 0 0 ;3=1,4=0
P 11.2219994 43.3299997 2 P 0 0 ;3=1,4=0
P 14.2699994 43.3299997 2 P 0 0 ;3=1,4=0
P 20.24000016 42.13999954 3 P 0 0 ;3=2,4=0
P 20.43999976 -1.26000002 3 P 0 0 ;3=2,4=0
P 35.50000012 -1.00000054 0 P 0 0 ;3=5,4=0
P 36.20000126 40.10000108 0 P 0 0 ;3=5,4=0
P 37.8500005 7.63999996 6 P 0 0 ;3=6,4=0
P 37.8500005 7.63999996 5 P 0 0 ;3=4,4=0
P 37.8500005 12.71999996 6 P 0 0 ;3=6,4=0
P 37.8500005 12.71999996 5 P 0 0 ;3=4,4=0
P 37.8500005 17.79999996 6 P 0 0 ;3=6,4=0
P 37.8500005 17.79999996 5 P 0 0 ;3=4,4=0
P 37.8500005 22.87999996 5 P 0 0 ;3=4,4=0
P 37.8500005 22.87999996 6 P 0 0 ;3=6,4=0
P 37.8500005 33.03999996 5 P 0 0 ;3=4,4=0
P 37.8500005 33.03999996 6 P 0 0 ;3=6,4=0
P 40.64 0 2 P 0 0 ;3=1,4=0
P 40.64 40.64 2 P 0 0 ;3=1,4=0
P 40.67999992 20.33999996 2 P 0 0 ;3=1,4=0
P 43.12499884 43.52500058 1 P 0 0 ;3=0,4=0
S P 0
OB 23.88042214 44.95700432 I
OS 23.88422198 44.95573686
OS 23.91970832 44.9544694
OS 23.9235107 44.95320194
OS 23.928578 44.95193448
OS 23.93491276 44.94939956
OS 23.9399826 44.9481321
OS 23.9577245 44.94559972
OS 23.97103156 44.94243234
OS 23.9818037 44.93673004
OS 23.988141 44.93419512
OS 23.99637568 44.93102774
OS 24.00081052 44.92785782
OS 24.00714782 44.92405798
OS 24.01348512 44.92152306
OS 24.02172234 44.91835314
OS 24.02362226 44.91645322
OS 24.02615718 44.91518576
OS 24.0400967 44.90884846
OS 24.04896892 44.90377862
OS 24.05530368 44.89997878
OS 24.06163844 44.89744386
OS 24.06670828 44.8961764
OS 24.07367804 44.8904741
OS 24.07811542 44.88603672
OS 24.08065034 44.88476926
OS 24.08635264 44.8790695
OS 24.0876201 44.87653458
OS 24.08952002 44.87463466
OS 24.09205494 44.8733672
OS 24.0990247 44.86639744
OS 24.10029216 44.86386252
OS 24.10219462 44.86196006
OS 24.104727 44.8606926
OS 24.11169676 44.85372284
OS 24.11296422 44.85118792
OS 24.11486414 44.849288
OS 24.11739906 44.84802054
OS 24.12310136 44.84231824
OS 24.12436882 44.83978332
OS 24.1275362 44.8366134
OS 24.13007112 44.83534848
OS 24.1345085 44.8309111
OS 24.13577596 44.82837618
OS 24.14337818 44.8207765
OS 24.1459131 44.8144392
OS 24.14908048 44.80620198
OS 24.1522504 44.80176714
OS 24.1585877 44.79542984
OS 24.16238754 44.78909254
OS 24.16872484 44.78275524
OS 24.17315714 44.77071564
OS 24.1750596 44.7662808
OS 24.1813969 44.7561462
OS 24.18266436 44.74727398
OS 24.18392928 44.74220414
OS 24.18519674 44.73460192
OS 24.19406896 44.71559002
OS 24.19596888 44.70355296
OS 24.20103872 44.6908809
OS 24.20230618 44.68581106
OS 24.20357364 44.67820884
OS 24.2048411 44.65032726
OS 24.20610856 44.61611092
OS 24.20737602 44.54007602
OS 24.20800848 41.48280756
OS 24.20800848 41.4815401
OS 24.20737602 38.81332344
OS 24.20800848 38.80888606
OS 24.20674102 38.80508368
OS 24.20737602 38.7841744
OS 24.20674102 38.76453258
OS 24.20800848 38.7607302
OS 24.20674102 38.7556629
OS 24.20547356 38.74679068
OS 24.20674102 38.74172084
OS 24.20737602 38.73475108
OS 24.20610856 38.72841378
OS 24.2048411 38.72334648
OS 24.20357364 38.6903976
OS 24.20103872 38.6840603
OS 24.19216904 38.67519062
OS 24.18583174 38.6726557
OS 24.15034794 38.67138824
OS 24.1465481 38.67012078
OS 24.14147826 38.66885332
OS 24.12943866 38.67075324
OS 24.12627128 38.67138824
OS 24.1224689 38.67012078
OS 24.11359668 38.66885332
OS 24.10092716 38.67012078
OS 24.08825256 38.66885332
OS 24.06227344 38.66948832
OS 24.05276876 38.66885332
OS 24.04896892 38.67012078
OS 24.04199916 38.67075324
OS 24.0343944 38.66948832
OS 24.02742464 38.66885332
OS 24.02362226 38.67012078
OS 24.01348512 38.6726557
OS 23.9818037 38.67392316
OS 23.97483394 38.67962546
OS 23.9697641 38.6846953
OS 23.96722918 38.6910326
OS 23.96596172 38.72651386
OS 23.96469426 38.73031624
OS 23.9634268 38.73918592
OS 23.96469426 38.7429883
OS 23.96596172 38.75059306
OS 23.96469426 38.75439544
OS 23.9634268 38.76326512
OS 23.96469426 38.76833242
OS 23.9640618 38.7905117
OS 23.96469426 38.80508368
OS 23.9634268 38.80888606
OS 23.9640618 38.8259955
OS 23.96279434 44.54767824
OS 23.96215934 44.55211562
OS 23.9634268 44.555918
OS 23.96215934 44.57746228
OS 23.96089188 44.58126212
OS 23.95962696 44.62181576
OS 23.95709204 44.62815052
OS 23.95328966 44.63702274
OS 23.9520222 44.64209258
OS 23.94695236 44.65095972
OS 23.94188252 44.65602956
OS 23.94061506 44.65856448
OS 23.93491276 44.66553424
OS 23.93237784 44.6668017
OS 23.92667808 44.672504
OS 23.92541062 44.67503892
OS 23.92224324 44.67820884
OS 23.91970832 44.6794763
OS 23.91273856 44.6851786
OS 23.90956864 44.68834598
OS 23.90323388 44.6908809
OS 23.89626158 44.69278082
OS 23.88042214 44.70102058
OS 23.8753523 44.7022855
OS 23.86521516 44.70355296
OS 23.86141278 44.70481788
OS 23.8525431 44.70862026
OS 23.84747326 44.70988772
OS 23.83099882 44.71115518
OS 23.80121986 44.71305764
OS 23.74925908 44.71432256
OS 23.25756334 44.71559002
OS 23.24932612 44.71622502
OS 23.24552374 44.71495756
OS 23.222712 44.71622502
OS 23.21890962 44.71495756
OS 23.20370518 44.71622502
OS 23.1999028 44.71749248
OS 23.16948884 44.71875994
OS 23.16315154 44.72256232
OS 23.15618178 44.72826462
OS 23.15491432 44.73079954
OS 23.1523794 44.7371343
OS 23.1517444 44.75804612
OS 23.1523794 44.76501334
OS 23.15111194 44.76881572
OS 23.14921202 44.77705294
OS 23.14857956 44.78655762
OS 23.14984448 44.79036
OS 23.14921202 44.8138042
OS 23.14984448 44.82457634
OS 23.14857956 44.82837618
OS 23.14921202 44.85942514
OS 23.14857956 44.87019728
OS 23.14984448 44.87399966
OS 23.14921202 44.8961764
OS 23.15047694 44.90124624
OS 23.1517444 44.907581
OS 23.1523794 44.91455076
OS 23.15111194 44.91708568
OS 23.1523794 44.92088806
OS 23.15364686 44.94116488
OS 23.1580817 44.94686718
OS 23.16061662 44.9481321
OS 23.16315154 44.95193448
OS 23.16948884 44.9544694
OS 23.20433764 44.95637186
OS 23.20940748 44.95763932
OS 23.22144454 44.95827178
OS 23.22524692 44.95700432
OS 23.24805866 44.95827178
OS 23.25186104 44.95700432
OS 23.26833548 44.95827178
OS 23.88042214 44.95700432
OE
SE
S P 0
OB 24.62937416 40.45695998 I
OS 24.65915312 40.45505752
OS 24.67182518 40.45379006
OS 24.67816248 40.4525226
OS 24.68449978 40.44998768
OS 24.692737 40.4468203
OS 24.70160922 40.44555538
OS 24.70667652 40.44428792
OS 24.71491374 40.44112054
OS 24.72251596 40.4360507
OS 24.73645802 40.43098086
OS 24.74089286 40.42781348
OS 24.74723016 40.42147618
OS 24.74976254 40.42020872
OS 24.76813944 40.40183436
OS 24.76940436 40.39929944
OS 24.7738392 40.39612952
OS 24.7808115 40.38915976
OS 24.78207896 40.38662484
OS 24.7865138 40.38346
OS 24.80488816 40.3650831
OS 24.80615562 40.36254818
OS 24.81249292 40.35621342
OS 24.81376038 40.3536785
OS 24.8162953 40.3473412
OS 24.81946268 40.33910398
OS 24.82516752 40.3295993
OS 24.8276999 40.31946216
OS 24.82959982 40.30869002
OS 24.83213474 40.30235526
OS 24.83530212 40.2941155
OS 24.83656958 40.28524582
OS 24.83783704 40.26877138
OS 24.8391045 40.25609932
OS 24.84037196 40.2244179
OS 24.8391045 40.22061552
OS 24.83783704 40.18513172
OS 24.83656958 40.18132934
OS 24.83530212 40.16865728
OS 24.83023228 40.15725268
OS 24.8276999 40.147113
OS 24.82643244 40.13824332
OS 24.82136514 40.12937364
OS 24.8162953 40.1179665
OS 24.81312792 40.10972928
OS 24.80488816 40.10149206
OS 24.80362324 40.09895714
OS 24.79918586 40.09325484
OS 24.79665094 40.09198738
OS 24.77827658 40.07361302
OS 24.77700912 40.0710781
OS 24.77510666 40.06917818
OS 24.77257174 40.06791072
OS 24.76687198 40.06220842
OS 24.76560452 40.0596735
OS 24.76243714 40.05650612
OS 24.75990222 40.05523866
OS 24.75293246 40.04953382
OS 24.74976254 40.04636644
OS 24.74342778 40.04383152
OS 24.73519056 40.04066414
OS 24.73075318 40.03749422
OS 24.71427874 40.029892
OS 24.692737 40.01975486
OS 24.6813324 40.0184874
OS 24.67753002 40.01721994
OS 24.6686578 40.0134201
OS 24.65978812 40.01088518
OS 24.6509159 40.00961772
OS 24.62620678 40.00771526
OS 24.60529496 40.0070828
OS 24.60149258 40.00835026
OS 24.57298108 40.01025018
OS 24.56664378 40.01151764
OS 24.55650664 40.01532002
OS 24.5457345 40.0184874
OS 24.54066466 40.01975486
OS 24.53115998 40.02165732
OS 24.51532054 40.029892
OS 24.50708332 40.03305938
OS 24.50264848 40.03496184
OS 24.49947856 40.03812922
OS 24.4988461 40.04002914
OS 24.49631118 40.0412966
OS 24.49377626 40.04383152
OS 24.49124134 40.04509898
OS 24.48553904 40.05080128
OS 24.48427158 40.0533362
OS 24.48237166 40.05523866
OS 24.47983674 40.05650612
OS 24.4741319 40.06220842
OS 24.47286444 40.06474334
OS 24.46969706 40.06791072
OS 24.46716468 40.06917818
OS 24.46272984 40.07361302
OS 24.46146238 40.07614794
OS 24.458295 40.07931786
OS 24.45576008 40.08058278
OS 24.45005524 40.08628508
OS 24.44879032 40.08882
OS 24.4456204 40.09198738
OS 24.44308548 40.09325484
OS 24.43865064 40.09768968
OS 24.43738318 40.1002246
OS 24.42977842 40.10782936
OS 24.42851096 40.11036428
OS 24.42597858 40.11669904
OS 24.42280866 40.1249388
OS 24.42090874 40.12683872
OS 24.41964128 40.12937364
OS 24.41710636 40.13190856
OS 24.41267152 40.14394816
OS 24.4101366 40.15028038
OS 24.4044343 40.15978506
OS 24.40190192 40.16865728
OS 24.39999946 40.18069688
OS 24.3930297 40.19780632
OS 24.38922732 40.2358225
OS 24.39049478 40.23962488
OS 24.39239724 40.26306908
OS 24.39366216 40.26813638
OS 24.39746454 40.27827606
OS 24.40063446 40.28651328
OS 24.40253438 40.29855288
OS 24.40380184 40.30362018
OS 24.41330398 40.32199708
OS 24.4164739 40.33023176
OS 24.42090874 40.33720406
OS 24.42724604 40.35114358
OS 24.4335808 40.36254818
OS 24.43865064 40.37395532
OS 24.44372048 40.382825
OS 24.44879032 40.3878923
OS 24.45005524 40.39042722
OS 24.45322516 40.39486206
OS 24.45576008 40.39612952
OS 24.458295 40.39866444
OS 24.46082738 40.3999319
OS 24.46589722 40.40753666
OS 24.46843214 40.40880412
OS 24.47539936 40.41450642
OS 24.47983674 40.41894126
OS 24.49567618 40.4246461
OS 24.4988461 40.42781348
OS 24.50138102 40.42908094
OS 24.50201348 40.4297134
OS 24.50264848 40.4303484
OS 24.51468808 40.43478324
OS 24.52102284 40.43731816
OS 24.5286276 40.442388
OS 24.53559482 40.44428792
OS 24.54446704 40.44555538
OS 24.55650664 40.44998768
OS 24.56727878 40.4531576
OS 24.57234608 40.45442506
OS 24.59959266 40.45632498
OS 24.61479964 40.45759244
OS 24.62557178 40.45822744
OS 24.62937416 40.45695998
OE
SE
S P 0
OB 24.63190908 41.19830724 I
OS 24.65788566 41.19640732
OS 24.66422296 41.19513986
OS 24.6743601 41.19133748
OS 24.68513224 41.1881701
OS 24.69020208 41.18690264
OS 24.69780684 41.18563518
OS 24.70667652 41.18056534
OS 24.71808112 41.1754955
OS 24.72441842 41.17296058
OS 24.72695334 41.17169312
OS 24.73582302 41.1653609
OS 24.74089286 41.16409344
OS 24.74913008 41.16092352
OS 24.75609984 41.15395376
OS 24.75863476 41.1526863
OS 24.76116968 41.15015138
OS 24.7637046 41.14888392
OS 24.76813944 41.14444908
OS 24.76940436 41.14191416
OS 24.77257174 41.13874678
OS 24.77510666 41.13747932
OS 24.77954404 41.13304448
OS 24.7808115 41.13050956
OS 24.78524634 41.12607218
OS 24.78778126 41.12480726
OS 24.79094864 41.12163734
OS 24.7922161 41.11910242
OS 24.79475102 41.1165675
OS 24.79601848 41.11403512
OS 24.80108832 41.10896528
OS 24.80362324 41.10263052
OS 24.80488816 41.09756068
OS 24.810593 41.09059092
OS 24.81502784 41.08615608
OS 24.82009768 41.07728386
OS 24.82516752 41.07221402
OS 24.8276999 41.06334434
OS 24.82896482 41.0519372
OS 24.83403466 41.04053514
OS 24.83530212 41.0354653
OS 24.83656958 41.02659308
OS 24.83783704 41.01392102
OS 24.8391045 40.98984182
OS 24.84037196 40.96956754
OS 24.8391045 40.95689548
OS 24.83720458 40.92711144
OS 24.83593712 40.91570938
OS 24.83466966 40.91063954
OS 24.83213474 40.90430224
OS 24.82896482 40.89606502
OS 24.8276999 40.89099772
OS 24.8276999 40.88973026
OS 24.82643244 40.87959058
OS 24.82073014 40.87262082
OS 24.81122546 40.8593163
OS 24.80742308 40.85551392
OS 24.80615562 40.852979
OS 24.80108832 40.84030694
OS 24.79538348 40.83333718
OS 24.7922161 40.83016726
OS 24.79094864 40.82763234
OS 24.78524634 40.82193004
OS 24.78271142 40.82066258
OS 24.77954404 40.8174952
OS 24.77827658 40.81496028
OS 24.77257174 40.80925798
OS 24.77003936 40.80799052
OS 24.76687198 40.80482314
OS 24.76560452 40.80229076
OS 24.76116968 40.79785338
OS 24.75863476 40.79658592
OS 24.75103 40.7889837
OS 24.74469524 40.78644878
OS 24.73645802 40.78327886
OS 24.72885326 40.7769441
OS 24.72568588 40.77377418
OS 24.71681366 40.76870688
OS 24.71174382 40.76363704
OS 24.69653938 40.76110212
OS 24.68449978 40.75666728
OS 24.67879748 40.75476482
OS 24.67372764 40.75349736
OS 24.66485542 40.7522299
OS 24.64077876 40.75096244
OS 24.63190908 40.74969498
OS 24.58502068 40.75096244
OS 24.5812183 40.7522299
OS 24.56474386 40.75349736
OS 24.55587164 40.75729974
OS 24.54953434 40.75983466
OS 24.54446704 40.76110212
OS 24.5336949 40.76300204
OS 24.52736014 40.76553696
OS 24.51785546 40.77123926
OS 24.50581586 40.77567664
OS 24.50138102 40.77884402
OS 24.49631118 40.78391386
OS 24.49377626 40.78518132
OS 24.4868065 40.79088362
OS 24.48237166 40.79531846
OS 24.46653222 40.8010233
OS 24.4639973 40.80355568
OS 24.46272984 40.80608806
OS 24.45512508 40.8111579
OS 24.45005524 40.81622774
OS 24.44879032 40.81876266
OS 24.44118556 40.82636488
OS 24.43865064 40.83270218
OS 24.43675072 40.83967194
OS 24.43484826 40.8415744
OS 24.4335808 40.84410932
OS 24.42724604 40.85044408
OS 24.42597858 40.852979
OS 24.42027374 40.85994876
OS 24.4158389 40.86438614
OS 24.4101366 40.88022558
OS 24.4044343 40.88973026
OS 24.40316938 40.89859994
OS 24.40190192 40.90366978
OS 24.39999946 40.91951176
OS 24.398732 40.92457906
OS 24.39556462 40.93154882
OS 24.3930297 40.9404185
OS 24.39176224 40.94929072
OS 24.39049478 40.96196278
OS 24.39176224 40.99110928
OS 24.3930297 40.99491166
OS 24.39429716 41.00251642
OS 24.399367 41.01392102
OS 24.40063446 41.01899086
OS 24.40190192 41.03166292
OS 24.40380184 41.04370252
OS 24.40696922 41.0519372
OS 24.41203652 41.06334434
OS 24.41330398 41.06841418
OS 24.41457144 41.07728386
OS 24.4158389 41.0823537
OS 24.4215412 41.08932346
OS 24.42344366 41.09122592
OS 24.42471112 41.0937583
OS 24.43041342 41.1007306
OS 24.4342158 41.10453044
OS 24.43611572 41.10516544
OS 24.43738318 41.10769782
OS 24.4456204 41.11593504
OS 24.44815532 41.1172025
OS 24.45449262 41.12480726
OS 24.458295 41.1286071
OS 24.46019492 41.1292421
OS 24.46146238 41.13177702
OS 24.46969706 41.14001424
OS 24.47223198 41.1412817
OS 24.47539936 41.14571654
OS 24.4811042 41.15141884
OS 24.48363658 41.1526863
OS 24.49124134 41.16029106
OS 24.49757864 41.16282598
OS 24.50581586 41.16599082
OS 24.5102507 41.16916074
OS 24.51532054 41.17422804
OS 24.51785546 41.1754955
OS 24.52482522 41.18120034
OS 24.53432736 41.18690264
OS 24.54700196 41.1881701
OS 24.5508018 41.18943756
OS 24.55967402 41.1932374
OS 24.56854624 41.19577232
OS 24.57741592 41.19703978
OS 24.60086012 41.19894224
OS 24.6281067 41.1995747
OS 24.63190908 41.19830724
OE
SE
S P 0
OB 24.63824384 41.93965704 I
OS 24.65154836 41.93775458
OS 24.6566182 41.93648712
OS 24.66358796 41.93331974
OS 24.67246018 41.93078482
OS 24.6870347 41.9288849
OS 24.69463692 41.92761744
OS 24.69970676 41.92634998
OS 24.71301128 41.91938022
OS 24.72505088 41.91494284
OS 24.73202064 41.910508
OS 24.73455556 41.90797308
OS 24.75039754 41.90227078
OS 24.75863476 41.89403356
OS 24.76116968 41.8927661
OS 24.76433706 41.89086618
OS 24.76560452 41.88833126
OS 24.7922161 41.86171968
OS 24.79348356 41.85918476
OS 24.80108832 41.85158
OS 24.80552316 41.8395404
OS 24.81186046 41.82940326
OS 24.81502784 41.82243604
OS 24.81819522 41.81419628
OS 24.82453252 41.80405914
OS 24.82896482 41.793287
OS 24.83213474 41.78504978
OS 24.83530212 41.77808002
OS 24.83656958 41.7692078
OS 24.8391045 41.734994
OS 24.84037196 41.70837988
OS 24.8391045 41.70458004
OS 24.83720458 41.66719378
OS 24.83466966 41.6519868
OS 24.83023228 41.6412172
OS 24.8276999 41.63107752
OS 24.82643244 41.62220784
OS 24.82136514 41.61333562
OS 24.8162953 41.60193102
OS 24.81312792 41.59369126
OS 24.80488816 41.58545404
OS 24.80362324 41.58292166
OS 24.7979184 41.5759519
OS 24.79475102 41.57278452
OS 24.79094864 41.5639123
OS 24.78968118 41.55884246
OS 24.78397888 41.5518727
OS 24.78144396 41.55060524
OS 24.77827658 41.54743786
OS 24.77700912 41.54490294
OS 24.77510666 41.54300302
OS 24.7687719 41.5404681
OS 24.76053468 41.53729818
OS 24.75609984 41.5341308
OS 24.74976254 41.5277935
OS 24.74723016 41.52652604
OS 24.74025786 41.52082628
OS 24.73709048 41.5176589
OS 24.7212485 41.5119566
OS 24.71934858 41.51005414
OS 24.70794398 41.5049843
OS 24.70287668 41.50371684
OS 24.69210454 41.50181692
OS 24.68576724 41.499282
OS 24.67753002 41.49611462
OS 24.66485542 41.49484716
OS 24.65978812 41.4935797
OS 24.62493932 41.49167978
OS 24.60656242 41.49104478
OS 24.60276004 41.49231224
OS 24.56854624 41.4935797
OS 24.56474386 41.49484716
OS 24.55206926 41.49611462
OS 24.53812974 41.50245192
OS 24.52989252 41.5056193
OS 24.5229253 41.51005414
OS 24.50898324 41.51639144
OS 24.49757864 41.52272874
OS 24.4861715 41.5277935
OS 24.47730182 41.53286334
OS 24.47223198 41.53793318
OS 24.46969706 41.53920064
OS 24.46272984 41.54490294
OS 24.46146238 41.54743786
OS 24.45576008 41.55314016
OS 24.45322516 41.55440762
OS 24.4513227 41.55631008
OS 24.45005524 41.55884246
OS 24.44435294 41.5645473
OS 24.44181802 41.56581476
OS 24.43865064 41.56898214
OS 24.43738318 41.57151706
OS 24.43168088 41.57848682
OS 24.42851096 41.5816542
OS 24.42597858 41.58798896
OS 24.42471112 41.5930588
OS 24.41964128 41.60193102
OS 24.41457144 41.61333562
OS 24.41203652 41.6285426
OS 24.40316938 41.64755196
OS 24.40190192 41.65642164
OS 24.399367 41.66656132
OS 24.39429716 41.67796592
OS 24.3930297 41.68303576
OS 24.39176224 41.69190544
OS 24.38922732 41.71978448
OS 24.39049478 41.72358686
OS 24.39239724 41.7470336
OS 24.39366216 41.75336836
OS 24.39809954 41.7641405
OS 24.40063446 41.77047526
OS 24.40190192 41.77934748
OS 24.40380184 41.7875847
OS 24.41330398 41.80595906
OS 24.4164739 41.81419628
OS 24.42090874 41.82116858
OS 24.42597858 41.83257064
OS 24.43104588 41.84144286
OS 24.43484826 41.84524524
OS 24.43611572 41.84777762
OS 24.43865064 41.85031254
OS 24.4399181 41.85284746
OS 24.44181802 41.85474992
OS 24.44435294 41.85601738
OS 24.4513227 41.86298714
OS 24.45259016 41.86552206
OS 24.45449262 41.86742198
OS 24.45702754 41.86868944
OS 24.4639973 41.8756592
OS 24.46526476 41.87819412
OS 24.46716468 41.88009404
OS 24.46969706 41.8813615
OS 24.47539936 41.8870638
OS 24.47666682 41.88959872
OS 24.47983674 41.8927661
OS 24.48237166 41.89403356
OS 24.48934142 41.89973586
OS 24.4925088 41.90290578
OS 24.4988461 41.90543816
OS 24.50391594 41.90670562
OS 24.51785546 41.91557784
OS 24.52989252 41.92001268
OS 24.53559482 41.9231826
OS 24.53686228 41.9231826
OS 24.54826942 41.9282499
OS 24.56094148 41.92951736
OS 24.57234608 41.93078482
OS 24.5812183 41.9345872
OS 24.5875556 41.93712212
OS 24.5926229 41.93838958
OS 24.60719488 41.9402895
OS 24.634444 41.9409245
OS 24.63824384 41.93965704
OE
SE
S P 0
OB 24.66739034 42.66959716 I
OS 24.67119272 42.6683297
OS 24.68893462 42.66706224
OS 24.70287668 42.66072748
OS 24.7092089 42.65819256
OS 24.72061604 42.6518578
OS 24.73202064 42.64678796
OS 24.74342778 42.64045066
OS 24.75483238 42.63538336
OS 24.76623952 42.62904606
OS 24.7687719 42.62524368
OS 24.77130682 42.62397622
OS 24.77827658 42.61827392
OS 24.78397888 42.6100367
OS 24.7865138 42.60876924
OS 24.78841372 42.60686678
OS 24.79094864 42.60053456
OS 24.7928511 42.59356226
OS 24.79601848 42.58912742
OS 24.80235578 42.58279012
OS 24.80362324 42.58025774
OS 24.80932554 42.57328544
OS 24.81249292 42.57011806
OS 24.81376038 42.56758314
OS 24.8162953 42.56124584
OS 24.81946268 42.55300862
OS 24.82516752 42.54350648
OS 24.8276999 42.53336934
OS 24.82959982 42.5225972
OS 24.83530212 42.50802268
OS 24.83783704 42.49028078
OS 24.83973696 42.45416452
OS 24.84037196 42.44085746
OS 24.8391045 42.43705508
OS 24.83783704 42.40157382
OS 24.83656958 42.39777144
OS 24.83530212 42.38382938
OS 24.82896482 42.36988986
OS 24.82579998 42.36165518
OS 24.82136514 42.35468542
OS 24.81502784 42.34074336
OS 24.80869054 42.32933876
OS 24.80362324 42.31793162
OS 24.7985534 42.30906194
OS 24.79348356 42.30399464
OS 24.7922161 42.30145972
OS 24.7865138 42.29448996
OS 24.78397888 42.2932225
OS 24.77954404 42.28878766
OS 24.77827658 42.28625274
OS 24.7738392 42.28181536
OS 24.76750698 42.27801552
OS 24.76116968 42.27167822
OS 24.75609984 42.27041076
OS 24.74786262 42.26724338
OS 24.7396254 42.25900362
OS 24.73075318 42.25393632
OS 24.72568588 42.24886648
OS 24.71934858 42.24633156
OS 24.71491374 42.2456991
OS 24.71427874 42.24506664
OS 24.70287668 42.24379918
OS 24.6863997 42.23619442
OS 24.67626256 42.23366204
OS 24.65852066 42.23239458
OS 24.65218336 42.22985966
OS 24.64394868 42.22668974
OS 24.63697892 42.22478982
OS 24.63190908 42.22352236
OS 24.62303686 42.2222549
OS 24.61796702 42.22098744
OS 24.60149258 42.2222549
OS 24.5976902 42.22352236
OS 24.58945298 42.22542228
OS 24.58311822 42.2279572
OS 24.56854624 42.23239458
OS 24.55587164 42.23366204
OS 24.5457345 42.2349295
OS 24.52419276 42.24506664
OS 24.515953 42.24823148
OS 24.51405308 42.25013394
OS 24.51151816 42.2514014
OS 24.50391594 42.25647124
OS 24.49694364 42.25837116
OS 24.4925088 42.26027108
OS 24.48553904 42.26597592
OS 24.48237166 42.2691433
OS 24.47983674 42.27041076
OS 24.4741319 42.27611306
OS 24.47286444 42.27864798
OS 24.46969706 42.28181536
OS 24.46716468 42.28308282
OS 24.46272984 42.2875202
OS 24.46146238 42.29005512
OS 24.458295 42.2932225
OS 24.45576008 42.29448996
OS 24.45005524 42.30019226
OS 24.44879032 42.30272718
OS 24.4456204 42.30589202
OS 24.44308548 42.30715948
OS 24.43865064 42.31159686
OS 24.43738318 42.31413178
OS 24.42977842 42.321734
OS 24.42851096 42.32426892
OS 24.42597858 42.33060622
OS 24.42471112 42.33567606
OS 24.4158389 42.34834812
OS 24.41393898 42.35531788
OS 24.41140406 42.36165518
OS 24.40570176 42.37242478
OS 24.40316938 42.38129446
OS 24.398732 42.40854358
OS 24.39683208 42.41297842
OS 24.39429716 42.41931572
OS 24.3930297 42.42438302
OS 24.39176224 42.4332527
OS 24.39049478 42.4459273
OS 24.39176224 42.4750738
OS 24.3930297 42.47887618
OS 24.39429716 42.48774586
OS 24.40063446 42.50168538
OS 24.40190192 42.51815982
OS 24.4050693 42.53146688
OS 24.41203652 42.54477394
OS 24.41520644 42.55300862
OS 24.41773882 42.55934592
OS 24.42090874 42.5625133
OS 24.4221762 42.56504822
OS 24.42597858 42.57392044
OS 24.42914596 42.58215766
OS 24.43738318 42.59039488
OS 24.43865064 42.5929298
OS 24.45702754 42.61130416
OS 24.45956246 42.61257162
OS 24.46146238 42.61447154
OS 24.46272984 42.61700646
OS 24.48237166 42.63664828
OS 24.48490404 42.63791574
OS 24.49124134 42.64425304
OS 24.49757864 42.64678796
OS 24.50581586 42.64995534
OS 24.51912292 42.65692764
OS 24.52925752 42.65946002
OS 24.5387622 42.66136248
OS 24.54953434 42.66579478
OS 24.55460418 42.66706224
OS 24.56727878 42.6683297
OS 24.58375322 42.66959716
OS 24.61163226 42.67086462
OS 24.66739034 42.66959716
OE
SE
S P 0
OB 31.31417664 44.95700432 I
OS 31.31797902 44.95573686
OS 31.35219536 44.9544694
OS 31.35599774 44.95320194
OS 31.36233504 44.95193448
OS 31.3686698 44.94939956
OS 31.3737371 44.9481321
OS 31.39148154 44.94559972
OS 31.40478606 44.94243234
OS 31.42062804 44.93546258
OS 31.42949772 44.93419512
OS 31.43456756 44.93292766
OS 31.44280478 44.92976028
OS 31.4447047 44.92785782
OS 31.44723962 44.92659036
OS 31.45611184 44.92279052
OS 31.46434906 44.9196206
OS 31.47131882 44.91518576
OS 31.4852558 44.90884846
OS 31.4915931 44.90504608
OS 31.49666294 44.89997878
OS 31.49919786 44.89871132
OS 31.50870254 44.89174156
OS 31.509335 44.8898391
OS 31.51186992 44.88857164
OS 31.52454452 44.88350434
OS 31.5270769 44.88223688
OS 31.53468166 44.87463466
OS 31.53721658 44.8733672
OS 31.54165142 44.87019728
OS 31.54291888 44.8676649
OS 31.54545126 44.86512998
OS 31.54608626 44.86322752
OS 31.54861864 44.86196006
OS 31.60501172 44.80556698
OS 31.60627918 44.80303206
OS 31.61388394 44.79542984
OS 31.61641886 44.78909254
OS 31.61768632 44.7840227
OS 31.626556 44.77008318
OS 31.62782346 44.76501334
OS 31.63669568 44.74854144
OS 31.64049806 44.73966922
OS 31.64303298 44.73333446
OS 31.64810028 44.72446224
OS 31.65190266 44.71559002
OS 31.65380512 44.70355296
OS 31.6576075 44.69341582
OS 31.66077488 44.68644606
OS 31.66204234 44.68137622
OS 31.6633098 44.672504
OS 31.66457726 44.6674367
OS 31.66647464 44.64525742
OS 31.6677421 44.64019012
OS 31.6734444 44.62181576
OS 31.67534686 44.60597378
OS 31.67661432 44.58316458
OS 31.67724678 44.57999466
OS 31.67597932 44.57619482
OS 31.67471186 44.54704578
OS 31.6734444 44.5432434
OS 31.67217694 44.53437372
OS 31.66964456 44.52803642
OS 31.66710964 44.51916674
OS 31.66584218 44.5140969
OS 31.66394226 44.49192016
OS 31.6626748 44.4843154
OS 31.66140734 44.47798064
OS 31.65887242 44.47164334
OS 31.65570504 44.46467358
OS 31.65317012 44.4558039
OS 31.6512702 44.44503176
OS 31.64873528 44.43869446
OS 31.64683536 44.43679454
OS 31.64049806 44.42285502
OS 31.63732814 44.41461526
OS 31.6328933 44.40891296
OS 31.63162584 44.40637804
OS 31.62909092 44.40004582
OS 31.62592354 44.39180606
OS 31.61895378 44.3848363
OS 31.61768632 44.38230138
OS 31.6088141 44.37089678
OS 31.60627918 44.36836186
OS 31.60184688 44.35632226
OS 31.5986795 44.35188742
OS 31.59360966 44.34681758
OS 31.5923422 44.34428266
OS 31.58980728 44.34175028
OS 31.58917482 44.33985036
OS 31.5866399 44.3385829
OS 31.52327706 44.27522006
OS 31.52074214 44.2739526
OS 31.51440484 44.2676153
OS 31.50806754 44.26508038
OS 31.49983032 44.261913
OS 31.49412802 44.2562107
OS 31.4915931 44.25494324
OS 31.48905818 44.25240832
OS 31.48272342 44.24860594
OS 31.47638866 44.24226864
OS 31.46054668 44.23656634
OS 31.45864422 44.23466642
OS 31.45611184 44.23339896
OS 31.44723962 44.22959658
OS 31.4383674 44.22832912
OS 31.4333001 44.22706166
OS 31.42506288 44.22389428
OS 31.41682566 44.21945944
OS 31.40795598 44.21692452
OS 31.39908376 44.21565706
OS 31.38704416 44.21122222
OS 31.38134186 44.2093223
OS 31.37246964 44.20805484
OS 31.32431632 44.20551992
OS 31.22420222 44.20425246
OS 30.54495034 44.202985
OS 30.54114796 44.20171754
OS 30.4993294 44.20045008
OS 30.49552702 44.19918262
OS 30.48538734 44.19791516
OS 30.47651766 44.19411278
OS 30.46637798 44.19157786
OS 30.45877576 44.19031294
OS 30.44230132 44.18270818
OS 30.43343164 44.18017326
OS 30.42455942 44.1789058
OS 30.4163222 44.17573842
OS 30.40681752 44.17003358
OS 30.39478046 44.16559874
OS 30.3878107 44.16116644
OS 30.37386864 44.15482914
OS 30.36246404 44.14849184
OS 30.3510569 44.14342454
OS 30.34218976 44.1383547
OS 30.33965484 44.13581978
OS 30.33711992 44.13455232
OS 30.33331754 44.13074994
OS 30.33078262 44.12948248
OS 30.32634778 44.12504764
OS 30.32508032 44.12251272
OS 30.32191294 44.11934534
OS 30.31937802 44.11807788
OS 30.31367572 44.11237558
OS 30.31240826 44.10984066
OS 30.3105058 44.1079382
OS 30.30797088 44.10667074
OS 30.30226858 44.10097098
OS 30.30100112 44.09843606
OS 30.29783374 44.09526868
OS 30.29529882 44.09400122
OS 30.28959652 44.08829892
OS 30.28832906 44.085764
OS 30.28516168 44.08259408
OS 30.28262676 44.08132662
OS 30.27819192 44.07689178
OS 30.27692446 44.07435686
OS 30.27312208 44.07055448
OS 30.27185462 44.0680221
OS 30.26805478 44.06421972
OS 30.2636174 44.05218012
OS 30.25918256 44.04521036
OS 30.25284526 44.03127084
OS 30.25031034 44.02493354
OS 30.24397558 44.01606386
OS 30.2395382 44.00402426
OS 30.23320344 43.99388458
OS 30.23003352 43.98691482
OS 30.22686614 43.97868014
OS 30.22433376 43.97234284
OS 30.22243384 43.97044292
OS 30.22116638 43.967908
OS 30.21863146 43.9615707
OS 30.217364 43.95270102
OS 30.21609654 43.94763118
OS 30.21292916 43.93939396
OS 30.20975924 43.92862182
OS 30.20849178 43.91594976
OS 30.20722432 43.89947532
OS 30.2053244 43.87603112
OS 30.2046894 43.8627266
OS 30.20595686 43.85892422
OS 30.20785932 43.82914272
OS 30.20912678 43.81520066
OS 30.21039424 43.80759844
OS 30.21419408 43.7974613
OS 30.21609654 43.79049154
OS 30.217364 43.7854217
OS 30.21926392 43.77591702
OS 30.22179884 43.76957972
OS 30.22876606 43.75374028
OS 30.23130098 43.7385333
OS 30.23637082 43.72966362
OS 30.2401732 43.7207914
OS 30.24270812 43.7144541
OS 30.2465105 43.70811934
OS 30.25284526 43.70178204
OS 30.25664764 43.69544474
OS 30.26298494 43.68910998
OS 30.26551986 43.68277522
OS 30.26868724 43.674538
OS 30.27185462 43.67010062
OS 30.27692446 43.66503332
OS 30.27819192 43.6624984
OS 30.29656628 43.6441215
OS 30.2991012 43.64285404
OS 30.30100112 43.64095412
OS 30.30226858 43.6384192
OS 30.30923834 43.63144944
OS 30.31177326 43.63018198
OS 30.31367572 43.62827952
OS 30.31494064 43.6257446
OS 30.32191294 43.61877738
OS 30.32444786 43.61750992
OS 30.32634778 43.61561
OS 30.32761524 43.61307508
OS 30.33331754 43.60737278
OS 30.33585246 43.60610532
OS 30.34218976 43.59976802
OS 30.34472468 43.59850056
OS 30.3510569 43.59596564
OS 30.35612674 43.59469818
OS 30.3630965 43.58899588
OS 30.36753388 43.58456104
OS 30.3700688 43.58329358
OS 30.37703856 43.57759128
OS 30.38020594 43.57442136
OS 30.38654324 43.57188644
OS 30.39858284 43.5674516
OS 30.40048276 43.56555168
OS 30.40301768 43.56428676
OS 30.41188736 43.56048438
OS 30.42075704 43.55921692
OS 30.4277268 43.557317
OS 30.4340641 43.55478208
OS 30.44990608 43.54780978
OS 30.46194568 43.54590986
OS 30.48032004 43.54020756
OS 30.4929921 43.5389401
OS 30.5278409 43.53703764
OS 30.57853422 43.53577272
OS 34.741485 43.53450526
OS 34.79090832 43.5332378
OS 34.81372006 43.53197034
OS 34.83843172 43.53006788
OS 34.84476648 43.52753296
OS 34.8536387 43.52500058
OS 34.86250838 43.52373312
OS 34.88215274 43.52183066
OS 34.8897575 43.5205632
OS 34.8948248 43.51929574
OS 34.9011621 43.51676082
OS 34.90812932 43.51359344
OS 34.918269 43.51105852
OS 34.92777368 43.5091586
OS 34.93411098 43.50662368
OS 34.9360109 43.50472122
OS 34.94995042 43.498389
OS 34.95818764 43.49521908
OS 34.9600901 43.49331916
OS 34.96262502 43.4920517
OS 34.976562 43.4857144
OS 34.98796914 43.47937964
OS 34.99050406 43.47684472
OS 34.99747382 43.47494226
OS 35.00380858 43.47240734
OS 35.00824596 43.46923996
OS 35.01331326 43.46417012
OS 35.01584818 43.46290266
OS 35.0183831 43.46036774
OS 35.02091802 43.45910028
OS 35.0240854 43.45466544
OS 35.0297877 43.44896314
OS 35.03232262 43.44769568
OS 35.03865738 43.44136092
OS 35.0411923 43.44009346
OS 35.0475296 43.43755854
OS 35.05259944 43.43629108
OS 35.0595692 43.43058878
OS 35.06400404 43.42615394
OS 35.06653896 43.42488648
OS 35.07224126 43.41918418
OS 35.07350872 43.41664926
OS 35.07667864 43.41221442
OS 35.07921102 43.41094696
OS 35.08238094 43.40524212
OS 35.08681324 43.39320252
OS 35.093783 43.38623276
OS 35.09505046 43.38370038
OS 35.10328768 43.37546316
OS 35.1058226 43.3741957
OS 35.11089244 43.36659348
OS 35.1178622 43.35962118
OS 35.12356704 43.34378174
OS 35.12673442 43.34061182
OS 35.12800188 43.3380769
OS 35.13307172 43.3266723
OS 35.1356041 43.32033754
OS 35.1419414 43.31146786
OS 35.14320632 43.30639802
OS 35.14574124 43.30006072
OS 35.15461346 43.28105136
OS 35.15714838 43.263312
OS 35.1590483 43.25253986
OS 35.16348314 43.23796534
OS 35.1647506 43.22909312
OS 35.16665306 43.20564892
OS 35.16792052 43.17270004
OS 35.16855298 43.1340514
OS 35.16728552 43.13024902
OS 35.16601806 43.08716046
OS 35.1647506 43.08336062
OS 35.16348314 43.0630838
OS 35.16094822 43.0567465
OS 35.1584133 43.04787428
OS 35.15588092 43.03013238
OS 35.15397846 43.02063024
OS 35.15144354 43.01429294
OS 35.14954362 43.01239302
OS 35.14447378 42.99972096
OS 35.14130894 42.99148374
OS 35.13940648 42.98958128
OS 35.13813902 42.98704636
OS 35.1356041 42.98451144
OS 35.12926934 42.968037
OS 35.12166458 42.96043478
OS 35.12039712 42.95789986
OS 35.11469482 42.9509301
OS 35.1127949 42.94903018
OS 35.11152744 42.94649526
OS 35.10772506 42.93762304
OS 35.10265522 42.92875336
OS 35.09631792 42.92241606
OS 35.09505046 42.91988114
OS 35.07541118 42.90024186
OS 35.07350872 42.89960686
OS 35.07224126 42.89707194
OS 35.06400404 42.88883472
OS 35.06210412 42.88820226
OS 35.06083666 42.88566734
OS 35.03992484 42.86475552
OS 35.03738992 42.86348806
OS 35.03422254 42.85905322
OS 35.02852024 42.85335092
OS 35.02598532 42.85208346
OS 35.0183831 42.84448124
OS 35.01204834 42.84194632
OS 35.00380858 42.83877894
OS 34.99620636 42.8337091
OS 34.9892366 42.83054172
OS 34.98099684 42.8273718
OS 34.97402708 42.82293696
OS 34.96262502 42.81786712
OS 34.94868296 42.8102649
OS 34.93474344 42.8039276
OS 34.91573408 42.79505538
OS 34.89799472 42.79252046
OS 34.88722258 42.79062054
OS 34.87264806 42.7861857
OS 34.86757822 42.78491824
OS 34.83399688 42.78301832
OS 34.78203864 42.78175086
OS 32.13219634 42.7804834
OS 32.13156134 42.77985094
OS 32.12775896 42.7811184
OS 32.10748214 42.77985094
OS 32.0441193 42.77858348
OS 32.04031692 42.77731602
OS 32.01117296 42.77604856
OS 32.00737058 42.7747811
OS 32.00103328 42.77224618
OS 31.99216106 42.76971126
OS 31.979489 42.76844634
OS 31.97441916 42.76717888
OS 31.96428456 42.76591142
OS 31.94780758 42.75830666
OS 31.94274028 42.7570392
OS 31.93196814 42.75513928
OS 31.92373092 42.75196936
OS 31.90978886 42.7456346
OS 31.90472156 42.74436714
OS 31.89458442 42.74309968
OS 31.88317728 42.73676238
OS 31.8743076 42.73296
OS 31.86607038 42.72979262
OS 31.85846562 42.72345786
OS 31.8565657 42.72155794
OS 31.85403078 42.72029048
OS 31.85149586 42.71775556
OS 31.8495934 42.71712056
OS 31.84832594 42.71458564
OS 31.84009126 42.70634842
OS 31.83755634 42.70508096
OS 31.83122158 42.6987462
OS 31.82488428 42.69621128
OS 31.81664706 42.69304136
OS 31.81221222 42.68987398
OS 31.80587492 42.68353668
OS 31.80334 42.68226922
OS 31.79637024 42.67529946
OS 31.79510278 42.67276454
OS 31.79066794 42.66959716
OS 31.78623056 42.66516232
OS 31.7849631 42.66262994
OS 31.78116326 42.65882756
OS 31.7805308 42.65692764
OS 31.77863088 42.65629264
OS 31.77736342 42.65375772
OS 31.7748285 42.64742042
OS 31.77165858 42.6391832
OS 31.76342136 42.63094598
OS 31.7621539 42.62841106
OS 31.7564516 42.6214413
OS 31.75328422 42.61827392
OS 31.7507493 42.61193662
OS 31.74758192 42.60370194
OS 31.74251208 42.59609718
OS 31.73680978 42.58279012
OS 31.73173994 42.57392044
OS 31.72413772 42.557446
OS 31.71780042 42.54350648
OS 31.71653296 42.53843664
OS 31.71463304 42.5225972
OS 31.71209812 42.49725054
OS 31.71083066 42.48964578
OS 31.7095632 42.48331102
OS 31.70829574 42.47824372
OS 31.70639582 42.47127142
OS 31.70512836 42.46620412
OS 31.70259344 42.4509946
OS 31.70132598 42.43832254
OS 31.70259344 42.42945032
OS 31.70449336 42.41741326
OS 31.70576082 42.4110785
OS 31.70702828 42.40600866
OS 31.7101982 42.39523652
OS 31.71146566 42.39016668
OS 31.71273312 42.38129446
OS 31.71399804 42.3686224
OS 31.7159005 42.35658534
OS 31.71716796 42.3515155
OS 31.72097034 42.34137836
OS 31.72413772 42.33314114
OS 31.72540264 42.3280713
OS 31.72730256 42.31729916
OS 31.72983748 42.31096186
OS 31.73173994 42.30906194
OS 31.73554232 42.30019226
OS 31.7387097 42.29195504
OS 31.74060962 42.2875202
OS 31.74694692 42.2811829
OS 31.74821438 42.27864798
OS 31.7507493 42.27611306
OS 31.75455168 42.26977576
OS 31.7564516 42.26787584
OS 31.75835406 42.26724338
OS 31.75961898 42.26470846
OS 31.7621539 42.25837116
OS 31.76532382 42.25013394
OS 31.77229358 42.24316672
OS 31.77356104 42.2406318
OS 31.78876548 42.22542228
OS 31.78940048 42.22352236
OS 31.7919354 42.2222549
OS 31.81284468 42.20134562
OS 31.81347968 42.19944316
OS 31.81601206 42.1981757
OS 31.83122158 42.18297126
OS 31.8337565 42.1817038
OS 31.84009126 42.1753665
OS 31.85403078 42.17029666
OS 31.861633 42.16269444
OS 31.86416792 42.16142698
OS 31.87557506 42.15255476
OS 31.88697966 42.14748746
OS 31.8983868 42.14115016
OS 31.90092172 42.13861524
OS 31.90598648 42.13734778
OS 31.91232378 42.13481286
OS 31.93386806 42.12467572
OS 31.9452752 42.1234108
OS 31.95160996 42.12087588
OS 31.96428456 42.1170735
OS 31.96935186 42.11580604
OS 32.0099055 42.11453858
OS 32.01370534 42.11327112
OS 32.0561589 42.11263866
OS 32.05932628 42.11327112
OS 32.06312866 42.11200366
OS 33.01357634 42.1107362
OS 33.01737618 42.10946874
OS 33.0553949 42.10820128
OS 33.05919474 42.10693382
OS 33.06616704 42.1050339
OS 33.07440426 42.10186652
OS 33.09214616 42.0993316
OS 33.1022833 42.09806414
OS 33.10861806 42.09552922
OS 33.12256012 42.08919192
OS 33.1314298 42.08792446
OS 33.13966702 42.08602454
OS 33.14600432 42.08348962
OS 33.14790424 42.08158716
OS 33.15043916 42.08032224
OS 33.1618463 42.0752524
OS 33.17008098 42.07208248
OS 33.1719809 42.07018256
OS 33.17451582 42.0689151
OS 33.18085312 42.06511526
OS 33.18909034 42.06194788
OS 33.19542764 42.05941296
OS 33.19859502 42.05624558
OS 33.20112994 42.05497812
OS 33.21000216 42.05117574
OS 33.21633692 42.04864082
OS 33.22330922 42.04293852
OS 33.22647406 42.0397686
OS 33.22900898 42.03850114
OS 33.23471128 42.03279884
OS 33.23597874 42.03026392
OS 33.23914612 42.02709654
OS 33.24168104 42.02582908
OS 33.2486508 42.02012678
OS 33.25182072 42.01695686
OS 33.26576024 42.01188956
OS 33.28160222 41.99605012
OS 33.28350214 41.98908036
OS 33.28603452 41.98274306
OS 33.29300428 41.9757733
OS 33.29427174 41.97323838
OS 33.29997658 41.96626862
OS 33.3025115 41.96500116
OS 33.30948126 41.9580314
OS 33.31011372 41.95612894
OS 33.31264864 41.95486148
OS 33.3196184 41.94789172
OS 33.32088586 41.9453568
OS 33.32849062 41.93775458
OS 33.33102554 41.93141982
OS 33.33419292 41.9231826
OS 33.3373603 41.91874522
OS 33.3436976 41.91241046
OS 33.34749744 41.90607316
OS 33.35319974 41.8991034
OS 33.3551022 41.89339856
OS 33.35636966 41.88453142
OS 33.35763712 41.87692666
OS 33.36397188 41.86805698
OS 33.3671418 41.85981722
OS 33.37094164 41.84968008
OS 33.37347656 41.84334278
OS 33.37537902 41.83764048
OS 33.37664648 41.83257064
OS 33.3785464 41.79772184
OS 33.38044632 41.7223194
OS 33.3791814 41.71851702
OS 33.3785464 41.68493568
OS 33.3791814 41.67289608
OS 33.37791394 41.66909624
OS 33.37601148 41.63424744
OS 33.37474402 41.62791014
OS 33.3722091 41.62157284
OS 33.36904172 41.6108007
OS 33.36777426 41.60573086
OS 33.3665068 41.59686118
OS 33.36143696 41.58798896
OS 33.35636966 41.5765869
OS 33.3487649 41.56264484
OS 33.3436976 41.55124024
OS 33.33609284 41.53729818
OS 33.332293 41.5284285
OS 33.3259557 41.5170239
OS 33.3196184 41.51068914
OS 33.31835094 41.50815422
OS 33.31138118 41.50118446
OS 33.30884626 41.499917
OS 33.30567888 41.49547962
OS 33.30124404 41.49104478
OS 33.29870912 41.48977732
OS 33.2955392 41.48660994
OS 33.29427174 41.48407502
OS 33.28856944 41.47837272
OS 33.28603452 41.47710526
OS 33.2841346 41.4752028
OS 33.28286968 41.47266788
OS 33.27589992 41.46569812
OS 33.273365 41.4644332
OS 33.27146254 41.46253328
OS 33.27019508 41.45999836
OS 33.25182072 41.44162146
OS 33.2492858 41.440354
OS 33.24738334 41.43845408
OS 33.24611842 41.43591916
OS 33.24041358 41.43021686
OS 33.23787866 41.4289494
OS 33.23027644 41.42134464
OS 33.22394168 41.41880972
OS 33.21570446 41.41564234
OS 33.21126962 41.41247496
OS 33.21000216 41.40994004
OS 33.20746724 41.40867258
OS 33.1960601 41.3998029
OS 33.19225772 41.39600052
OS 33.17641828 41.39029822
OS 33.17451582 41.3883983
OS 33.16311376 41.38332846
OS 33.15804392 41.382061
OS 33.14600432 41.38016108
OS 33.12762742 41.37065386
OS 33.11495536 41.36558656
OS 33.10355076 41.36051672
OS 33.08771132 41.3586168
OS 33.07376926 41.35734934
OS 33.06236466 41.35608188
OS 33.04589022 41.35354696
OS 33.04082292 41.3522795
OS 33.03512062 41.35037704
OS 33.02244602 41.34910958
OS 32.97429016 41.3465772
OS 32.92803422 41.3459422
OS 32.92613176 41.3465772
OS 32.92233446 41.34531228
OS 31.37183718 41.34467728
OS 31.3686698 41.34531228
OS 31.36486996 41.34404482
OS 31.3091068 41.34277736
OS 31.30530442 41.3415099
OS 31.27996284 41.34024244
OS 31.2685557 41.3351726
OS 31.2622184 41.33263768
OS 31.2508138 41.32630038
OS 31.2394092 41.32123308
OS 31.22546968 41.31362832
OS 31.21406508 41.30855848
OS 31.20012302 41.30095626
OS 31.19125334 41.29715388
OS 31.17984874 41.29081658
OS 31.1747789 41.28574674
OS 31.17224398 41.28448182
OS 31.16780914 41.28131444
OS 31.16654168 41.27877952
OS 31.15957192 41.27180976
OS 31.157037 41.2705423
OS 31.14943224 41.26293754
OS 31.14309748 41.26040262
OS 31.13486026 41.25723524
OS 31.12409066 41.2464631
OS 31.1221882 41.24583064
OS 31.12092074 41.24329572
OS 31.11711836 41.2344235
OS 31.11205106 41.22555382
OS 31.10571376 41.21921906
OS 31.10191138 41.21288176
OS 31.09557408 41.20654446
OS 31.09050678 41.19260494
OS 31.0860694 41.18690264
OS 31.08416948 41.18626764
OS 31.08290202 41.18373272
OS 31.0740298 41.17232812
OS 31.07149488 41.1697932
OS 31.0689625 41.16345844
OS 31.06579258 41.15522122
OS 31.05882536 41.14191416
OS 31.0575579 41.13684432
OS 31.05629044 41.12797464
OS 31.0518556 41.11593504
OS 31.0461533 41.10263052
OS 31.04425084 41.08552108
OS 31.04298338 41.07791886
OS 31.04171592 41.07284902
OS 31.03791354 41.06270934
OS 31.03664608 41.05764204
OS 31.03538116 41.05003728
OS 31.03284624 41.01962332
OS 31.03221124 41.01518848
OS 31.0334787 41.0113861
OS 31.03538116 40.98414206
OS 31.03664608 40.9765373
OS 31.03791354 40.97146746
OS 31.04044846 40.9651327
OS 31.04235092 40.95816294
OS 31.04361838 40.9530931
OS 31.04488584 40.9404185
OS 31.0461533 40.9353512
OS 31.04741822 40.92647898
OS 31.05502298 40.91000708
OS 31.05945782 40.89036272
OS 31.06769504 40.87452074
OS 31.07086242 40.86628352
OS 31.0740298 40.86185122
OS 31.07656472 40.8593163
OS 31.07783218 40.85678138
OS 31.0803671 40.85424646
OS 31.08163456 40.85171154
OS 31.08416948 40.84917662
OS 31.08543694 40.84664424
OS 31.09177424 40.84030694
OS 31.09367416 40.83333718
OS 31.09620908 40.82699988
OS 31.10317884 40.82003012
OS 31.1044463 40.8174952
OS 31.10698122 40.81496028
OS 31.10824868 40.81242536
OS 31.11268352 40.80925798
OS 31.11965328 40.80229076
OS 31.12028828 40.8003883
OS 31.1228232 40.79912084
OS 31.14372994 40.77821156
OS 31.1449974 40.77567664
OS 31.14943224 40.77250672
OS 31.15640454 40.76553696
OS 31.157037 40.76363704
OS 31.15957192 40.76236958
OS 31.16780914 40.75413236
OS 31.16844414 40.7522299
OS 31.17097652 40.75096244
OS 31.1747789 40.7471626
OS 31.17731382 40.74589514
OS 31.18365112 40.73956038
OS 31.19949056 40.73385808
OS 31.20139048 40.73195562
OS 31.2039254 40.73068816
OS 31.20646032 40.72815324
OS 31.21153016 40.72688578
OS 31.22039984 40.72308594
OS 31.23307444 40.71548118
OS 31.2394092 40.71294626
OS 31.24764642 40.70977888
OS 31.26095094 40.70280912
OS 31.26602078 40.70154166
OS 31.27679292 40.6996392
OS 31.2869326 40.69583682
OS 31.30150712 40.69140198
OS 31.31037426 40.69013452
OS 31.33825584 40.68886706
OS 31.34205822 40.6875996
OS 31.36043258 40.68570222
OS 31.3680348 40.68443476
OS 31.37817448 40.68189984
OS 31.392114 40.68063238
OS 31.44850708 40.677465
OS 31.56763054 40.67619754
OS 32.4851268 40.67493008
OS 32.48892918 40.67366262
OS 32.52314552 40.67239516
OS 32.52948028 40.66986024
OS 32.5383525 40.66605786
OS 32.54722218 40.6647904
OS 32.55229202 40.66352294
OS 32.55926178 40.66162302
OS 32.57383376 40.65465326
OS 32.58270598 40.65211834
OS 32.59284312 40.65085088
OS 32.60171534 40.64578104
OS 32.61565486 40.63944374
OS 32.62199216 40.63691136
OS 32.63086184 40.63057406
OS 32.64290144 40.62613922
OS 32.6492362 40.62233938
OS 32.65050366 40.61980446
OS 32.6562085 40.61536708
OS 32.65874088 40.61409962
OS 32.66317826 40.60966478
OS 32.66444572 40.60712986
OS 32.6676131 40.60396248
OS 32.67014802 40.60269502
OS 32.67711778 40.59699272
OS 32.68155262 40.59255534
OS 32.6910573 40.59065542
OS 32.69549214 40.5887555
OS 32.69739206 40.58685304
OS 32.69865952 40.5817832
OS 32.70056198 40.57354598
OS 32.70372936 40.56911114
OS 32.71069912 40.56721122
OS 32.71703642 40.5659463
OS 32.72147126 40.56277638
OS 32.72400618 40.5539067
OS 32.72527364 40.54883686
OS 32.7328784 40.5412321
OS 32.73414586 40.53869718
OS 32.73984816 40.53172742
OS 32.74681538 40.52602512
OS 32.75251768 40.5177879
OS 32.7550526 40.51652044
OS 32.75695506 40.51462052
OS 32.75948744 40.50828322
OS 32.7607549 40.50321592
OS 32.76582474 40.4943437
OS 32.76835966 40.49180878
OS 32.77089458 40.48547402
OS 32.77406196 40.4772368
OS 32.78039926 40.46709712
OS 32.78356664 40.46012736
OS 32.78800402 40.44808776
OS 32.78990394 40.44618784
OS 32.79497378 40.43478324
OS 32.79624124 40.42591102
OS 32.7975087 40.42084372
OS 32.80384346 40.40436674
OS 32.80510838 40.39929944
OS 32.80701084 40.38219254
OS 32.8082783 40.37205286
OS 32.80954576 40.35431096
OS 32.81081322 40.33910398
OS 32.81208068 40.33276668
OS 32.81588052 40.32263208
OS 32.81841544 40.31629478
OS 32.8203179 40.30932502
OS 32.81905044 40.29538296
OS 32.8139806 40.28397836
OS 32.81017822 40.26877138
OS 32.8082783 40.23898988
OS 32.80574338 40.21871306
OS 32.80447592 40.20730846
OS 32.7975087 40.19020156
OS 32.79624124 40.18132934
OS 32.79497378 40.17626204
OS 32.79180386 40.16802482
OS 32.7848341 40.15218284
OS 32.78293418 40.14014578
OS 32.78039926 40.13380848
OS 32.77469696 40.1243038
OS 32.76962712 40.11036428
OS 32.76392482 40.10339452
OS 32.7607549 40.1002246
OS 32.75948744 40.09768968
OS 32.75378514 40.09071992
OS 32.75061776 40.08755254
OS 32.74808284 40.08121778
OS 32.74491546 40.07298056
OS 32.73667824 40.06474334
OS 32.7328784 40.05840604
OS 32.73097594 40.05650612
OS 32.72844102 40.05523866
OS 32.72273872 40.04953382
OS 32.72147126 40.04700144
OS 32.71957134 40.04509898
OS 32.71703642 40.04383152
OS 32.7087992 40.0355943
OS 32.7081642 40.03369438
OS 32.70562928 40.03242692
OS 32.6961246 40.02292478
OS 32.69549214 40.02102232
OS 32.69295722 40.01975486
OS 32.68598746 40.0127851
OS 32.68472 40.01025018
OS 32.68282008 40.00835026
OS 32.68028516 40.0070828
OS 32.67458286 40.0013805
OS 32.6733154 39.99884558
OS 32.67014802 39.99567566
OS 32.6676131 39.9944082
OS 32.6619108 39.9887059
OS 32.66064334 39.98617098
OS 32.65747596 39.9830036
OS 32.65494104 39.98173614
OS 32.64796874 39.97603384
OS 32.64480136 39.97286392
OS 32.63276176 39.96842908
OS 32.62832692 39.96652916
OS 32.625792 39.96399678
OS 32.62325962 39.96272932
OS 32.6143874 39.95892694
OS 32.60805264 39.95639202
OS 32.59918042 39.95132218
OS 32.59031074 39.94752234
OS 32.58143852 39.94625488
OS 32.57446876 39.94435242
OS 32.56813146 39.9418175
OS 32.5624317 39.93991758
OS 32.55736186 39.93865012
OS 32.54088742 39.93738266
OS 32.50160378 39.9361152
OS 32.46991982 39.93484774
OS 28.73213202 39.93421528
OS 28.72642972 39.93484774
OS 28.72262988 39.93358028
OS 28.70171806 39.93421528
OS 28.67954132 39.93358028
OS 28.6770064 39.93484774
OS 28.67320402 39.93358028
OS 28.6237807 39.9297779
OS 28.61617594 39.92851044
OS 28.60857372 39.92344314
OS 28.60604134 39.92217568
OS 28.59907158 39.91647084
OS 28.59146682 39.89999894
OS 28.5895669 39.87021744
OS 28.58829944 39.85247554
OS 28.58766444 39.83283372
OS 28.5889319 39.8302988
OS 28.58766444 39.82649642
OS 28.58703198 39.76503604
OS 28.58766444 39.5134846
OS 28.58639698 39.50968222
OS 28.58512952 39.40323336
OS 28.58386206 39.39943098
OS 28.5825946 39.36774702
OS 28.57625984 39.35381004
OS 28.57308992 39.34557282
OS 28.57055754 39.34050298
OS 28.56802262 39.33923552
OS 28.56105032 39.33226576
OS 28.5597854 39.32973084
OS 28.5528131 39.32656092
OS 28.54077604 39.32212608
OS 28.53380628 39.3189587
OS 28.5249366 39.31769124
OS 28.49008526 39.31578878
OS 28.43812702 39.31452386
OS 27.58082622 39.31388886
OS 27.57702384 39.31515632
OS 27.50859116 39.31642378
OS 27.50478878 39.31769124
OS 27.4832445 39.3189587
OS 27.46930498 39.325296
OS 27.4610703 39.32846338
OS 27.45410054 39.33543314
OS 27.45156562 39.3367006
OS 27.44459586 39.3424029
OS 27.43952602 39.35000766
OS 27.43825856 39.35254258
OS 27.43445618 39.36141226
OS 27.43382372 39.38105408
OS 27.43445618 39.39055876
OS 27.43318872 39.39436114
OS 27.43192126 39.39943098
OS 27.43255626 39.4190728
OS 27.4306538 39.43237732
OS 27.43192126 39.4361797
OS 27.4312888 39.45835898
OS 27.43192126 39.47419842
OS 27.4306538 39.4780008
OS 27.43192126 39.49700762
OS 27.4306538 39.50081
OS 27.42938634 39.6427452
OS 27.42811888 39.64654758
OS 27.42685142 39.6832963
OS 27.42178412 39.6947009
OS 27.4192492 39.7010382
OS 27.41798174 39.70610804
OS 27.41164444 39.71497772
OS 27.4021423 39.72448494
OS 27.39707246 39.72574986
OS 27.39390508 39.72638486
OS 27.38883524 39.7251174
OS 27.38123302 39.7187801
OS 27.37362826 39.71117788
OS 27.37109334 39.70484058
OS 27.3666585 39.69280098
OS 27.36348858 39.68456376
OS 27.36222112 39.67949392
OS 27.36095366 39.64021028
OS 27.35968874 39.6364079
OS 27.35842128 39.5362938
OS 27.35778628 39.4368147
OS 27.35842128 39.42604256
OS 27.35715382 39.42224272
OS 27.35778628 39.4013309
OS 27.35651882 39.3949936
OS 27.35525136 39.37471678
OS 27.3539839 39.35824488
OS 27.34448176 39.3424029
OS 27.34004692 39.33796806
OS 27.337512 39.3367006
OS 27.32990724 39.32909584
OS 27.32357248 39.32656092
OS 27.31153288 39.32212608
OS 27.30456058 39.3189587
OS 27.29949328 39.31769124
OS 27.25957464 39.31578878
OS 27.20888386 39.31452386
OS 26.86355562 39.31388886
OS 26.85975324 39.31515632
OS 26.79005564 39.31642378
OS 26.78625326 39.31769124
OS 26.76597644 39.3189587
OS 26.7545693 39.32402854
OS 26.74633462 39.32719592
OS 26.73936486 39.33163076
OS 26.73429502 39.3367006
OS 26.7317601 39.33796806
OS 26.72479034 39.34493782
OS 26.72352288 39.34747274
OS 26.71845304 39.3550775
OS 26.71718558 39.3601448
OS 26.71528566 39.39372614
OS 26.7140182 39.40006344
OS 26.71338574 39.40956812
OS 26.7146532 39.4133705
OS 26.71338574 39.4361797
OS 26.7146532 39.43998208
OS 26.71338574 39.4602589
OS 26.71275074 39.77263826
OS 26.71338574 39.78721024
OS 26.71211828 39.79101262
OS 26.71338574 39.8125569
OS 26.71211828 39.81635928
OS 26.71085082 39.8252315
OS 26.70894836 39.86134522
OS 26.7076809 39.86894998
OS 26.70451352 39.87591974
OS 26.69881122 39.89176172
OS 26.69690876 39.89366164
OS 26.6956413 39.89619656
OS 26.68930654 39.90253386
OS 26.68803908 39.90506878
OS 26.68233678 39.91076854
OS 26.67600202 39.91457092
OS 26.67219964 39.9183733
OS 26.66586234 39.92090822
OS 26.64748798 39.9240756
OS 26.6430506 39.92724298
OS 26.631646 39.93231282
OS 26.6202414 39.93104536
OS 26.61137172 39.9247106
OS 26.60503442 39.92217568
OS 26.5967972 39.91900576
OS 26.5910949 39.91330346
OS 26.58855998 39.912036
OS 26.58602506 39.90950108
OS 26.58349014 39.90823362
OS 26.5790553 39.90380132
OS 26.57778784 39.9012664
OS 26.57461792 39.89809902
OS 26.572083 39.89683156
OS 26.5676507 39.89239418
OS 26.56258086 39.8835245
OS 26.56004594 39.8771872
OS 26.55878102 39.87211736
OS 26.56004594 39.86705006
OS 26.55878102 39.85437546
OS 26.5562461 39.82269658
OS 26.55497864 39.8188942
OS 26.5562461 39.81002198
OS 26.5556111 39.7891127
OS 26.5562461 39.77454072
OS 26.55497864 39.77073834
OS 26.5556111 39.75489636
OS 26.55434364 39.67252416
OS 26.55371118 39.66808932
OS 26.55497864 39.66428948
OS 26.55371118 39.6478125
OS 26.55180872 39.59775672
OS 26.55054126 39.58761958
OS 26.54800888 39.58128228
OS 26.5435715 39.57051014
OS 26.54230404 39.5654403
OS 26.53660174 39.55847054
OS 26.53343436 39.55530316
OS 26.5321669 39.55276824
OS 26.5264646 39.54580102
OS 26.51505746 39.5369288
OS 26.49224826 39.52678912
OS 26.48210858 39.52425674
OS 26.44092502 39.52235428
OS 26.43649018 39.52172182
OS 26.4326878 39.52298928
OS 26.41621082 39.52172182
OS 26.28568276 39.52045436
OS 26.25400388 39.52172182
OS 26.21281524 39.52235428
OS 26.20711548 39.52172182
OS 26.2033131 39.52298928
OS 26.16212446 39.5248892
OS 26.15705716 39.52615666
OS 26.14375264 39.53185896
OS 26.13551542 39.53502888
OS 26.13361296 39.5369288
OS 26.13107804 39.53819626
OS 26.12474328 39.54453356
OS 26.12220836 39.54580102
OS 26.11650352 39.55150078
OS 26.1152386 39.5540357
OS 26.1089013 39.56037046
OS 26.10763384 39.56290538
OS 26.10383146 39.5717776
OS 26.10066408 39.58001482
OS 26.09749416 39.58698458
OS 26.0962267 39.59965918
OS 26.09369432 39.68456376
OS 26.09242686 39.80368722
OS 26.0911594 39.91647084
OS 26.08672456 39.92090822
OS 26.07848734 39.92280814
OS 26.0683502 39.92661052
OS 26.0613779 39.9297779
OS 26.02779656 39.93168036
OS 26.00751974 39.93294782
OS 25.93021738 39.93421528
OS 25.3922657 39.93484774
OS 25.38846332 39.93358028
OS 25.29468652 39.93231282
OS 25.29088414 39.93104536
OS 25.25983518 39.92914544
OS 25.25349788 39.92661052
OS 25.24653066 39.92344314
OS 25.23829344 39.92154068
OS 25.2338586 39.91964076
OS 25.23068868 39.91647084
OS 25.22942122 39.90760116
OS 25.22878876 39.54959832
OS 25.22942122 39.53376142
OS 25.22815376 39.52995904
OS 25.22942122 39.51094968
OS 25.22815376 39.5071473
OS 25.22878876 39.48623802
OS 25.2275213 39.48116818
OS 25.22625384 39.47356596
OS 25.22562138 39.46786366
OS 25.2268863 39.46532874
OS 25.22562138 39.46152636
OS 25.22435392 39.44124954
OS 25.21864908 39.43427978
OS 25.21358178 39.42920994
OS 25.20470956 39.42667502
OS 25.17239568 39.42477764
OS 25.16605838 39.42351018
OS 25.16035608 39.42287518
OS 25.1565537 39.42414264
OS 25.14831648 39.42477764
OS 25.13817934 39.42351018
OS 25.13627688 39.42287518
OS 25.1324745 39.42414264
OS 25.10903284 39.42351018
OS 25.0919234 39.42414264
OS 25.08812102 39.42287518
OS 25.07164658 39.42414264
OS 25.06784674 39.42287518
OS 24.51468808 39.42351018
OS 24.50391594 39.42287518
OS 24.50011356 39.42414264
OS 24.47920174 39.42351018
OS 24.45956246 39.42414264
OS 24.45702754 39.42287518
OS 24.45322516 39.42414264
OS 24.44498794 39.42477764
OS 24.43484826 39.42351018
OS 24.42914596 39.42287518
OS 24.42534358 39.42414264
OS 24.4164739 39.4254101
OS 24.3866924 39.42730748
OS 24.38035764 39.4298424
OS 24.37148542 39.43871462
OS 24.3689505 39.44505192
OS 24.36768304 39.48053572
OS 24.36641558 39.4843381
OS 24.36514812 39.4894054
OS 24.36641558 39.50587984
OS 24.36514812 39.5185519
OS 24.36641558 39.52742412
OS 24.36514812 39.54389856
OS 24.36641558 39.5540357
OS 24.36514812 39.55783808
OS 24.36514812 39.73398708
OS 24.36514812 39.73525454
OS 24.36578312 39.82079412
OS 24.36514812 39.83536864
OS 24.36641558 39.83917102
OS 24.36514812 39.8594453
OS 24.36641558 39.86324768
OS 24.36578312 39.88415696
OS 24.36705058 39.8892268
OS 24.36831804 39.8955641
OS 24.3695855 39.92724298
OS 24.37592026 39.93738266
OS 24.38035764 39.94435242
OS 24.38225756 39.94625488
OS 24.39112978 39.95132218
OS 24.39999946 39.95512456
OS 24.4221762 39.95575956
OS 24.42661104 39.95512456
OS 24.43041342 39.95639202
OS 24.4399181 39.95829448
OS 24.44942278 39.95892694
OS 24.45322516 39.95765948
OS 24.47603436 39.95892694
OS 24.47983674 39.95765948
OS 24.50011356 39.95892694
OS 24.50708332 39.95829448
OS 24.8923302 39.9595594
OS 24.89676504 39.96146186
OS 24.89866496 39.96336178
OS 24.89993242 39.96842908
OS 24.90119988 39.9773013
OS 24.89993242 40.51081814
OS 24.89549758 40.51652044
OS 24.8866279 40.5177879
OS 24.51722046 40.51842036
OS 24.50264848 40.5177879
OS 24.4988461 40.51905536
OS 24.47793428 40.51842036
OS 24.46209484 40.51905536
OS 24.458295 40.5177879
OS 24.44942278 40.51905536
OS 24.42851096 40.51842036
OS 24.4221762 40.51968782
OS 24.40063446 40.52095528
OS 24.38542494 40.52222274
OS 24.37845518 40.52665758
OS 24.37021796 40.53489734
OS 24.3689505 40.54376702
OS 24.36641558 40.58051828
OS 24.36514812 40.58431812
OS 24.36641558 40.60966478
OS 24.36514812 40.61346716
OS 24.36641558 40.63374144
OS 24.36768304 40.63754382
OS 24.3695855 40.66986024
OS 24.37275288 40.67429508
OS 24.3746528 40.677465
OS 24.37718772 40.67873246
OS 24.3809901 40.6825323
OS 24.3873274 40.68506722
OS 24.42090874 40.68696714
OS 24.42597858 40.6882346
OS 24.43675072 40.68886706
OS 24.44055056 40.6875996
OS 24.46272984 40.6882346
OS 24.4747669 40.6875996
OS 24.47856928 40.68886706
OS 24.49060888 40.6882346
OS 24.4925088 40.68886706
OS 24.49377626 40.6875996
OS 24.49757864 40.68886706
OS 24.89423012 40.69013452
OS 24.89866496 40.6933019
OS 24.90119988 40.70344158
OS 24.89993242 41.2407608
OS 24.89549758 41.2464631
OS 24.8866279 41.24773056
OS 24.50074602 41.24836302
OS 24.48870642 41.24773056
OS 24.48490404 41.24899802
OS 24.46526476 41.24836302
OS 24.45766 41.24963048
OS 24.45702754 41.25026548
OS 24.45322516 41.24899802
OS 24.44055056 41.24773056
OS 24.43675072 41.24899802
OS 24.42661104 41.25153294
OS 24.39492962 41.2528004
OS 24.39239724 41.25533532
OS 24.38986232 41.25660278
OS 24.37909018 41.26357254
OS 24.37782272 41.26610746
OS 24.37148542 41.27497714
OS 24.3689505 41.28131444
OS 24.36705058 41.31489578
OS 24.36578312 41.32250054
OS 24.36514812 41.33833998
OS 24.36641558 41.34214236
OS 24.36514812 41.36748648
OS 24.36641558 41.37128886
OS 24.36768304 41.3877633
OS 24.37021796 41.41437488
OS 24.3809901 41.42514702
OS 24.39112978 41.42768194
OS 24.39809954 41.42704694
OS 24.41964128 41.4283144
OS 24.42471112 41.42958186
OS 24.4392831 41.43021686
OS 24.44308548 41.4289494
OS 24.45956246 41.43021686
OS 24.89296266 41.43148432
OS 24.89866496 41.43591916
OS 24.89993242 41.440989
OS 24.90119988 41.44985868
OS 24.89993242 41.98337552
OS 24.8973975 41.98591044
OS 24.89676504 41.9878129
OS 24.88789536 41.99034782
OS 24.47920174 41.99098028
OS 24.4633623 41.99034782
OS 24.45956246 41.99161274
OS 24.43801818 41.99034782
OS 24.43168088 41.9928802
OS 24.39619708 41.99414766
OS 24.3873274 42.00048496
OS 24.3809901 42.00428734
OS 24.37782272 42.00745218
OS 24.37655526 42.0099871
OS 24.37021796 42.02012678
OS 24.3689505 42.02519662
OS 24.36705058 42.05117574
OS 24.36578312 42.0638478
OS 24.36514812 42.09109438
OS 24.36641558 42.09489422
OS 24.36768304 42.1278431
OS 24.3689505 42.13164548
OS 24.37021796 42.14431754
OS 24.37655526 42.1582596
OS 24.37845518 42.16649682
OS 24.38035764 42.16839674
OS 24.3809901 42.17029666
OS 24.3873274 42.17283158
OS 24.89549758 42.17409904
OS 24.89866496 42.17726896
OS 24.89993242 42.18233626
OS 24.90119988 42.19120594
OS 24.89993242 42.72472532
OS 24.89549758 42.73042508
OS 24.89042774 42.73169254
OS 24.4868065 42.73232754
OS 24.47856928 42.73169254
OS 24.4747669 42.73296
OS 24.45385762 42.73232754
OS 24.44752286 42.733595
OS 24.44308548 42.73422746
OS 24.4392831 42.73296
OS 24.43041342 42.73169254
OS 24.41520644 42.73549492
OS 24.38225756 42.73676238
OS 24.37021796 42.74880198
OS 24.3689505 42.7576742
OS 24.36768304 42.78935308
OS 24.36641558 42.79315546
OS 24.36514812 42.7982253
OS 24.36641558 42.81469974
OS 24.36514812 42.8273718
OS 24.36641558 42.83624402
OS 24.36514812 42.85271592
OS 24.36641558 42.86412306
OS 24.36514812 42.86792544
OS 24.36641558 44.88033696
OS 24.36768304 44.8841368
OS 24.3695855 44.9253229
OS 24.37085296 44.93039274
OS 24.3752878 44.94116488
OS 24.37782272 44.95003456
OS 24.3816251 44.95637186
OS 24.38859486 44.95827178
OS 31.31417664 44.95700432
OE
OB 27.74937046 44.47164334 H
OS 27.74557062 44.47037588
OS 27.71135174 44.46910842
OS 27.70754936 44.46784096
OS 27.6784054 44.4665735
OS 27.67460302 44.46530604
OS 27.66953318 44.46403858
OS 27.65305874 44.46277366
OS 27.6479889 44.4615062
OS 27.62074486 44.45960628
OS 27.61630748 44.45897128
OS 27.61250764 44.46023874
OS 27.6074378 44.45897128
OS 27.57385646 44.45707136
OS 27.55611456 44.4558039
OS 27.5485098 44.45453644
OS 27.5421725 44.45326898
OS 27.5371052 44.45200152
OS 27.5199983 44.4501016
OS 27.51492846 44.44883414
OS 27.48768188 44.44566676
OS 27.46993998 44.4443993
OS 27.46360522 44.44313184
OS 27.45853538 44.44186438
OS 27.45156562 44.43996192
OS 27.44649578 44.43869446
OS 27.41988166 44.43489462
OS 27.40340976 44.43362716
OS 27.39960738 44.4323597
OS 27.38756778 44.43045724
OS 27.38249794 44.42918978
OS 27.3717258 44.4260224
OS 27.35842128 44.42412248
OS 27.34131438 44.42222002
OS 27.3197701 44.4196851
OS 27.31280034 44.41778518
OS 27.29822582 44.41208288
OS 27.29315598 44.41081542
OS 27.27985146 44.4076455
OS 27.2728817 44.40447812
OS 27.2665444 44.40194574
OS 27.25830718 44.40004582
OS 27.25196988 44.39877836
OS 27.2367629 44.39624344
OS 27.23169306 44.39497598
OS 27.22155846 44.3911736
OS 27.21332124 44.38800622
OS 27.20064664 44.38673876
OS 27.19177696 44.3854713
OS 27.18670712 44.38420384
OS 27.1784699 44.38103392
OS 27.1721326 44.37850154
OS 27.16389792 44.37533162
OS 27.15882808 44.37406416
OS 27.1493234 44.37216424
OS 27.1429861 44.36962932
OS 27.13601634 44.36646194
OS 27.12967904 44.36392702
OS 27.12461174 44.36265956
OS 27.11130468 44.35948964
OS 27.10496992 44.35695726
OS 27.09166286 44.35125242
OS 27.08659302 44.34998496
OS 27.07708834 44.34808504
OS 27.06441628 44.34301774
OS 27.05744652 44.33985036
OS 27.0485743 44.33731544
OS 27.0378047 44.33541298
OS 27.02449764 44.32844322
OS 27.01562542 44.32464084
OS 26.99408114 44.3145037
OS 26.985214 44.31323624
OS 26.97824424 44.31133632
OS 26.95226258 44.29929672
OS 26.9433929 44.29422688
OS 26.92945084 44.28788958
OS 26.91804878 44.28155482
OS 26.90410672 44.27522006
OS 26.88256244 44.26508038
OS 26.87052538 44.26318046
OS 26.86419062 44.26064554
OS 26.85341848 44.25494324
OS 26.84708118 44.25240832
OS 26.80526262 44.23086404
OS 26.79258802 44.2257942
OS 26.78561826 44.22009444
OS 26.78245088 44.21692452
OS 26.77991596 44.21565706
OS 26.76470898 44.20551992
OS 26.75963914 44.20425246
OS 26.74760208 44.20235
OS 26.74063232 44.19791516
OS 26.73682994 44.19411278
OS 26.72795772 44.18904548
OS 26.72289042 44.18397564
OS 26.7203555 44.18270818
OS 26.70894836 44.17763834
OS 26.69754376 44.17130104
OS 26.68613916 44.16623374
OS 26.6798044 44.1624339
OS 26.67473456 44.15736406
OS 26.67219964 44.1560966
OS 26.66966472 44.15356168
OS 26.6671298 44.15229422
OS 26.66332742 44.14849184
OS 26.6607925 44.14722438
OS 26.65826012 44.144692
OS 26.65319028 44.14342454
OS 26.64178314 44.13708724
OS 26.63671584 44.1320174
OS 26.63418092 44.13074994
OS 26.63037854 44.12694756
OS 26.62784362 44.1256801
OS 26.62404378 44.12188026
OS 26.62150886 44.1206128
OS 26.61517156 44.11807788
OS 26.61010426 44.11681042
OS 26.6024995 44.10920566
OS 26.59996458 44.1079382
OS 26.58855998 44.09907106
OS 26.58602506 44.09653614
OS 26.57968776 44.09400122
OS 26.57461792 44.09273376
OS 26.5676507 44.08703146
OS 26.56448332 44.08386154
OS 26.5619484 44.08259408
OS 26.54547396 44.06611964
OS 26.54293904 44.06485218
OS 26.53913666 44.0610498
OS 26.53279936 44.05851488
OS 26.52456214 44.0553475
OS 26.52139476 44.05218012
OS 26.51885984 44.05091266
OS 26.51379 44.04584282
OS 26.51125508 44.04457536
OS 26.50745524 44.04077552
OS 26.50492032 44.03950806
OS 26.50112048 44.03570568
OS 26.48717842 44.03063838
OS 26.4795762 44.02303362
OS 26.47704128 44.02176616
OS 26.47007152 44.01606386
OS 26.46880406 44.01352894
OS 26.46309922 44.00782664
OS 26.4605643 44.00655918
OS 26.45739692 44.00212434
OS 26.45042716 43.99515204
OS 26.44789224 43.99388458
OS 26.44282494 43.98881728
OS 26.44029002 43.98754982
OS 26.43395526 43.9850149
OS 26.42571804 43.98184752
OS 26.41747828 43.9736103
OS 26.4149459 43.97234284
OS 26.41177598 43.97044292
OS 26.41050852 43.967908
OS 26.37249234 43.92988928
OS 26.37122488 43.92735436
OS 26.3680575 43.92418698
OS 26.36552258 43.92292206
OS 26.35855282 43.91721722
OS 26.3553829 43.91404984
OS 26.34144338 43.90898
OS 26.33637354 43.90391016
OS 26.33383862 43.9026427
OS 26.3313037 43.90011032
OS 26.32876878 43.89884286
OS 26.32433648 43.89440548
OS 26.32306902 43.89187056
OS 26.31863418 43.88743572
OS 26.31609926 43.88616826
OS 26.31166442 43.88173342
OS 26.31039696 43.8791985
OS 26.30722704 43.87603112
OS 26.30469212 43.87476366
OS 26.29898982 43.86906136
OS 26.29772236 43.86652644
OS 26.29455498 43.86335906
OS 26.29202006 43.8620916
OS 26.28758522 43.85765676
OS 26.28631776 43.85512184
OS 26.28314784 43.85195446
OS 26.28061546 43.850687
OS 26.27491062 43.8449847
OS 26.27364316 43.84244978
OS 26.27047578 43.83927986
OS 26.26794086 43.8380124
OS 26.26350856 43.83357756
OS 26.2622411 43.83104264
OS 26.25907372 43.82787526
OS 26.2565388 43.8266078
OS 26.25083396 43.8209055
OS 26.2495665 43.81837058
OS 26.24639912 43.81520066
OS 26.2438642 43.81393574
OS 26.2381619 43.8082309
OS 26.23689444 43.80569598
OS 26.23435952 43.8031636
OS 26.23309206 43.80063122
OS 26.22928968 43.79682884
OS 26.22485484 43.78478924
OS 26.22168746 43.78035186
OS 26.21661762 43.77528456
OS 26.21535016 43.77274964
OS 26.21218278 43.7683148
OS 26.20964786 43.76704734
OS 26.20014572 43.75754266
OS 26.19951072 43.7556402
OS 26.1969758 43.75437274
OS 26.17479906 43.73219854
OS 26.1735316 43.72966362
OS 26.17099668 43.72332632
OS 26.17416406 43.71889148
OS 26.18303628 43.71762402
OS 26.19317342 43.71889148
OS 26.20014572 43.72459378
OS 26.20204564 43.7264937
OS 26.21091532 43.73156354
OS 26.2140827 43.73473346
OS 26.21535016 43.73726584
OS 26.22105246 43.74297068
OS 26.22358738 43.74423814
OS 26.2267573 43.74740298
OS 26.22802222 43.7499379
OS 26.23372706 43.75690766
OS 26.23689444 43.76007504
OS 26.23879436 43.76704734
OS 26.24132928 43.7733821
OS 26.24830158 43.78035186
OS 26.2495665 43.78288678
OS 26.25527134 43.78985908
OS 26.25780626 43.791124
OS 26.26477602 43.7980963
OS 26.26604348 43.80063122
OS 26.27047578 43.8037986
OS 26.27744554 43.81076582
OS 26.27808054 43.81266828
OS 26.28061546 43.81393574
OS 26.28885268 43.82217296
OS 26.29012014 43.82470788
OS 26.29202006 43.8266078
OS 26.29455498 43.82787526
OS 26.30025728 43.83357756
OS 26.30152474 43.83611248
OS 26.3034272 43.8380124
OS 26.30595958 43.83927986
OS 26.31293188 43.84625216
OS 26.31419934 43.84878454
OS 26.31609926 43.850687
OS 26.31863418 43.85195446
OS 26.32560394 43.85892422
OS 26.3262364 43.86082414
OS 26.32876878 43.8620916
OS 26.33827346 43.87159374
OS 26.33890846 43.8734962
OS 26.34144338 43.87476366
OS 26.3496806 43.88300088
OS 26.35094806 43.8855358
OS 26.35284798 43.88743572
OS 26.3553829 43.88870318
OS 26.35791782 43.8912381
OS 26.36045274 43.89250556
OS 26.36552258 43.8975754
OS 26.37185734 43.90011032
OS 26.3800971 43.9032777
OS 26.3857994 43.90898
OS 26.38833178 43.91024746
OS 26.3908667 43.91278238
OS 26.39340162 43.91404984
OS 26.396569 43.91721722
OS 26.39783646 43.91975214
OS 26.4022713 43.92418698
OS 26.40480622 43.92545444
OS 26.40924106 43.92988928
OS 26.41050852 43.9324242
OS 26.4149459 43.93685904
OS 26.41747828 43.9381265
OS 26.4206482 43.94129388
OS 26.42191566 43.9438288
OS 26.42761796 43.9495311
OS 26.43015288 43.95079856
OS 26.43332026 43.95396848
OS 26.43458772 43.9565034
OS 26.44029002 43.9622057
OS 26.44219248 43.96283816
OS 26.44282494 43.96474062
OS 26.4447274 43.96537308
OS 26.44599486 43.967908
OS 26.45296208 43.97487776
OS 26.455497 43.97614522
OS 26.4605643 43.98121506
OS 26.46309922 43.98248252
OS 26.47577382 43.98754982
OS 26.48274358 43.99325212
OS 26.48591096 43.9964195
OS 26.48844588 43.99768696
OS 26.51759238 44.026836
OS 26.5201273 44.02810346
OS 26.52266222 44.03063838
OS 26.52519714 44.03190584
OS 26.5315319 44.03444076
OS 26.54040412 44.03950806
OS 26.54293904 44.04204298
OS 26.54547396 44.04331044
OS 26.5492738 44.04711028
OS 26.55180872 44.04837774
OS 26.5556111 44.05218012
OS 26.55814602 44.05344758
OS 26.56068094 44.0559825
OS 26.56701824 44.05851488
OS 26.572083 44.05978234
OS 26.5790553 44.06548718
OS 26.58222268 44.06865456
OS 26.5847576 44.06992202
OS 26.58729252 44.07245694
OS 26.58982744 44.0737244
OS 26.59489474 44.07879424
OS 26.59742966 44.08005916
OS 26.61010426 44.085129
OS 26.61263918 44.08766392
OS 26.61517156 44.08893138
OS 26.6202414 44.09400122
OS 26.62277632 44.09526868
OS 26.62974354 44.10223844
OS 26.631011 44.10477082
OS 26.63418092 44.1079382
OS 26.63671584 44.10920566
OS 26.64051568 44.11300804
OS 26.6430506 44.1142755
OS 26.64558552 44.11681042
OS 26.65192282 44.11934534
OS 26.66016004 44.12251272
OS 26.6677648 44.12758256
OS 26.67473456 44.13074994
OS 26.68297178 44.13391986
OS 26.690574 44.14025462
OS 26.69374138 44.14342454
OS 26.6962763 44.144692
OS 26.70324606 44.1503943
OS 26.70514598 44.15229422
OS 26.7140182 44.1560966
OS 26.73049264 44.16496628
OS 26.73936486 44.16876866
OS 26.74570216 44.17130104
OS 26.7545693 44.17763834
OS 26.7609066 44.18017326
OS 26.76597644 44.18144072
OS 26.77484612 44.18651056
OS 26.78878818 44.19284532
OS 26.79512294 44.1966477
OS 26.80019278 44.20171754
OS 26.8027277 44.202985
OS 26.80526262 44.20551992
OS 26.807795 44.20678738
OS 26.81286484 44.21185722
OS 26.81539976 44.21312214
OS 26.82680436 44.21819198
OS 26.83567658 44.22326182
OS 26.85215102 44.23086404
OS 26.87115784 44.23973372
OS 26.87622768 44.24100118
OS 26.88573236 44.24290364
OS 26.89206966 44.24543856
OS 26.90030688 44.2498734
OS 26.91297894 44.25494324
OS 26.91551386 44.2562107
OS 26.925651 44.26254546
OS 26.93198576 44.26508038
OS 26.99408114 44.29549434
OS 27.00041844 44.29929672
OS 27.00548828 44.30056418
OS 27.0143605 44.30183164
OS 27.0194278 44.30309656
OS 27.03590478 44.31070132
OS 27.04477446 44.31323624
OS 27.05807898 44.31640362
OS 27.0720185 44.32274092
OS 27.08279064 44.3259083
OS 27.09229786 44.32781076
OS 27.09863262 44.33034568
OS 27.11193714 44.33604798
OS 27.12207682 44.3385829
OS 27.13031404 44.34048282
OS 27.14425356 44.34681758
OS 27.1550257 44.34998496
OS 27.16833022 44.35315488
OS 27.17529998 44.35632226
OS 27.1841722 44.36012464
OS 27.19430934 44.36265956
OS 27.2025491 44.36455948
OS 27.20888386 44.3670944
OS 27.21712108 44.37026178
OS 27.22726076 44.3727967
OS 27.24183274 44.37469916
OS 27.26591194 44.37850154
OS 27.27604908 44.38230138
OS 27.28301884 44.38420384
OS 27.29315598 44.38673876
OS 27.30899796 44.38863868
OS 27.3140678 44.38990614
OS 27.32040256 44.39244106
OS 27.32863978 44.39560844
OS 27.33877946 44.39814336
OS 27.35651882 44.40067828
OS 27.36158866 44.40194574
OS 27.37362826 44.40637804
OS 27.37996556 44.4076455
OS 27.39137016 44.40891296
OS 27.39770746 44.41018042
OS 27.40784206 44.41144788
OS 27.42051666 44.41271534
OS 27.43572364 44.41525026
OS 27.44206094 44.41651772
OS 27.45283308 44.4196851
OS 27.4775422 44.42158756
OS 27.49781902 44.42412248
OS 27.51556092 44.4253874
OS 27.53266782 44.42728986
OS 27.5428075 44.42982478
OS 27.55547956 44.43109224
OS 27.571954 44.4323597
OS 27.63531938 44.43489462
OS 27.69931468 44.43552708
OS 27.83301012 44.43489462
OS 27.8368125 44.43615954
OS 27.9065101 44.43489462
OS 27.95783588 44.43299216
OS 27.98064762 44.4317247
OS 27.99838952 44.43045724
OS 28.00472428 44.42918978
OS 28.01486142 44.42665486
OS 28.04907776 44.42285502
OS 28.06935458 44.4203201
OS 28.0832941 44.41905264
OS 28.0889964 44.41715018
OS 28.09786862 44.41461526
OS 28.10800576 44.41208288
OS 28.12701258 44.41081542
OS 28.13081496 44.40954796
OS 28.13841972 44.4082805
OS 28.1422221 44.40701304
OS 28.15616162 44.4032132
OS 28.16503384 44.40067828
OS 28.18150828 44.39941082
OS 28.19037796 44.39814336
OS 28.19861518 44.39624344
OS 28.20368502 44.39497598
OS 28.21382216 44.3911736
OS 28.22079192 44.38927368
OS 28.22586176 44.38800622
OS 28.24170374 44.38610376
OS 28.25183834 44.38356884
OS 28.25817564 44.38103392
OS 28.26894778 44.37786654
OS 28.27401762 44.37659908
OS 28.2898596 44.37469916
OS 28.29746182 44.3734317
OS 28.30759896 44.37216424
OS 28.3126688 44.37089678
OS 28.32280594 44.3670944
OS 28.33104316 44.36392702
OS 28.336113 44.36265956
OS 28.34561768 44.3607571
OS 28.35195498 44.35822472
OS 28.36526204 44.35251988
OS 28.37032934 44.35125242
OS 28.37983402 44.3493525
OS 28.38997116 44.34555012
OS 28.40327822 44.33985036
OS 28.40834806 44.3385829
OS 28.41785274 44.33668044
OS 28.42419004 44.33414806
OS 28.4412944 44.32717576
OS 28.45016662 44.3259083
OS 28.46220622 44.32147346
OS 28.47551328 44.31577116
OS 28.48058312 44.3145037
OS 28.4938851 44.31133632
OS 28.51986676 44.29929672
OS 28.53887612 44.2904245
OS 28.55091318 44.28852458
OS 28.55725048 44.28598966
OS 28.56802262 44.28028736
OS 28.5768923 44.27648752
OS 28.59843658 44.26634784
OS 28.60350642 44.26508038
OS 28.61364356 44.26381292
OS 28.63518784 44.25367578
OS 28.64912736 44.24607102
OS 28.66306688 44.23973372
OS 28.6656018 44.23846626
OS 28.67256902 44.23276396
OS 28.6770064 44.22959658
OS 28.68397616 44.22389428
OS 28.68714354 44.2207269
OS 28.68967846 44.21945944
OS 28.69855068 44.21565706
OS 28.7067879 44.21248968
OS 28.71439012 44.20741984
OS 28.72136242 44.20551992
OS 28.72642972 44.20425246
OS 28.7352994 44.202985
OS 28.75684368 44.19284532
OS 28.7657159 44.18777802
OS 28.77268566 44.18207318
OS 28.77458558 44.18017326
OS 28.7771205 44.1789058
OS 28.78409026 44.1732035
OS 28.78725764 44.17003358
OS 28.80119716 44.16496628
OS 28.80880192 44.15989898
OS 28.8176716 44.1560966
OS 28.82907874 44.1497593
OS 28.83414858 44.144692
OS 28.83668096 44.14342454
OS 28.84365326 44.1377197
OS 28.8468181 44.13455232
OS 28.8531554 44.1320174
OS 28.86139262 44.12885002
OS 28.86329254 44.12694756
OS 28.87976952 44.11934534
OS 28.8886392 44.1142755
OS 28.89117412 44.11174058
OS 28.89370904 44.11047312
OS 28.91018094 44.09400122
OS 28.91271586 44.09273376
OS 28.92032062 44.085129
OS 28.93236022 44.08069416
OS 28.93679506 44.07752678
OS 28.94376482 44.07182194
OS 28.95136958 44.06675464
OS 28.95707188 44.0610498
OS 28.96340918 44.05851488
OS 28.96847648 44.05724996
OS 28.97988108 44.04837774
OS 28.98685084 44.04267798
OS 28.9887533 44.04077552
OS 28.99128822 44.03950806
OS 28.99508806 44.03570568
OS 29.00206036 44.03380576
OS 29.0121975 44.02746846
OS 29.01536488 44.02430108
OS 29.0178998 44.02303362
OS 29.04451138 43.9964195
OS 29.0470463 43.99515204
OS 29.05465106 43.98754982
OS 29.06352074 43.9850149
OS 29.06985804 43.98121506
OS 29.0768278 43.97551276
OS 29.08126264 43.97234284
OS 29.08696494 43.96664054
OS 29.0882324 43.96410562
OS 29.09139978 43.96093824
OS 29.0939347 43.95967078
OS 29.09710208 43.9565034
OS 29.09836954 43.95396848
OS 29.10407184 43.94826364
OS 29.10660676 43.94699872
OS 29.11357906 43.94129388
OS 29.11674644 43.9381265
OS 29.12498366 43.93622658
OS 29.13195342 43.9317892
OS 29.1357558 43.92798682
OS 29.13829072 43.92671936
OS 29.14082564 43.92418698
OS 29.14336056 43.92292206
OS 29.14526048 43.9210196
OS 29.1465254 43.91848468
OS 29.16870468 43.89630794
OS 29.1706046 43.89567294
OS 29.17187206 43.89313802
OS 29.22826514 43.83674494
OS 29.23016506 43.83611248
OS 29.23143252 43.83357756
OS 29.276421 43.78859162
OS 29.27832092 43.78795662
OS 29.27958838 43.7854217
OS 29.29923274 43.76577988
OS 29.30176766 43.76451242
OS 29.30493504 43.7613425
OS 29.3062025 43.75880758
OS 29.3119048 43.75310528
OS 29.31443972 43.75183782
OS 29.3176071 43.74867044
OS 29.31887456 43.74613552
OS 29.3245794 43.7391683
OS 29.32647678 43.73726584
OS 29.3290117 43.73093108
OS 29.33217908 43.72269386
OS 29.33788138 43.71698902
OS 29.33914884 43.7144541
OS 29.34168376 43.71192172
OS 29.34295122 43.7093868
OS 29.3473886 43.70494942
OS 29.34992098 43.70368196
OS 29.35435836 43.69924712
OS 29.35562582 43.6967122
OS 29.36006066 43.69227736
OS 29.36259558 43.6910099
OS 29.36703042 43.68657506
OS 29.36829788 43.68404268
OS 29.37210026 43.6802403
OS 29.37336772 43.67770538
OS 29.37590264 43.67517046
OS 29.38033748 43.66313086
OS 29.38350486 43.65869602
OS 29.38857216 43.65362618
OS 29.38983962 43.65109126
OS 29.41645374 43.62447968
OS 29.4177212 43.6219473
OS 29.42279104 43.61687746
OS 29.4240585 43.61434254
OS 29.42659088 43.60800524
OS 29.43166072 43.59913556
OS 29.43736302 43.59216326
OS 29.43926548 43.59026334
OS 29.44053294 43.58772842
OS 29.44433532 43.58392604
OS 29.44560278 43.58139112
OS 29.44940008 43.57759128
OS 29.45130254 43.57061898
OS 29.45383746 43.56428676
OS 29.46080722 43.557317
OS 29.46207468 43.55478208
OS 29.47094436 43.54337494
OS 29.47347928 43.54084002
OS 29.47474674 43.53577272
OS 29.48108404 43.52436558
OS 29.48615388 43.51929574
OS 29.48742134 43.51676082
OS 29.49692602 43.50725614
OS 29.49882594 43.50662368
OS 29.5000934 43.5040913
OS 29.50389578 43.50028892
OS 29.50516324 43.497754
OS 29.50896308 43.49395162
OS 29.511498 43.48761686
OS 29.51466538 43.47937964
OS 29.51973522 43.47177488
OS 29.52417006 43.46100274
OS 29.5292399 43.45213052
OS 29.53430974 43.44706322
OS 29.5355772 43.4445283
OS 29.53810958 43.44199592
OS 29.53937704 43.439461
OS 29.54444688 43.43439116
OS 29.54571434 43.43185624
OS 29.54951672 43.42298656
OS 29.55712148 43.4090445
OS 29.56092132 43.40017482
OS 29.56599116 43.3913026
OS 29.57105846 43.38623276
OS 29.57232592 43.38370038
OS 29.57802822 43.37673062
OS 29.58119814 43.37229578
OS 29.58373052 43.36976086
OS 29.58690044 43.36152364
OS 29.58943536 43.35518634
OS 29.59513766 43.34568166
OS 29.59830504 43.33744444
OS 29.6002075 43.3330096
OS 29.6052748 43.32540484
OS 29.60907718 43.31653516
OS 29.6116121 43.3102004
OS 29.6179494 43.30006072
OS 29.62175178 43.29119104
OS 29.64329352 43.24936994
OS 29.6470959 43.24050026
OS 29.65026328 43.23226304
OS 29.6521632 43.23036058
OS 29.65596558 43.2214909
OS 29.65723304 43.21261868
OS 29.6585005 43.20754884
OS 29.66166788 43.19931416
OS 29.66737272 43.18980948
OS 29.66864018 43.18473964
OS 29.69271684 43.13531886
OS 29.69398176 43.13024902
OS 29.69524922 43.12010934
OS 29.70412144 43.10109998
OS 29.70665636 43.09096284
OS 29.70792382 43.08336062
OS 29.71299366 43.07195348
OS 29.7167935 43.0630838
OS 29.71932842 43.05294412
OS 29.72059588 43.0453419
OS 29.72693318 43.03139984
OS 29.7294681 43.02506508
OS 29.73073556 43.01999778
OS 29.73263548 43.00922564
OS 29.73897278 42.99528358
OS 29.74214016 42.98704636
OS 29.74340762 42.98197652
OS 29.74467508 42.97310684
OS 29.75100984 42.95916732
OS 29.75354476 42.95283256
OS 29.75671214 42.93825804
OS 29.76051452 42.92811836
OS 29.7636819 42.91988114
OS 29.76494936 42.9148113
OS 29.76685182 42.90024186
OS 29.76938674 42.87996504
OS 29.77191912 42.86982536
OS 29.77508904 42.86158814
OS 29.77889142 42.84891354
OS 29.78079134 42.83307664
OS 29.7820588 42.82673934
OS 29.78586118 42.81659966
OS 29.78966356 42.80266014
OS 29.79093102 42.79505538
OS 29.7934634 42.77224618
OS 29.79599832 42.76210904
OS 29.79916824 42.7513369
OS 29.80170316 42.74119722
OS 29.80296808 42.73232754
OS 29.80423554 42.7272577
OS 29.805503 42.70951834
OS 29.80676792 42.70571596
OS 29.81183776 42.68797406
OS 29.81500768 42.65692764
OS 29.8162726 42.64678796
OS 29.81754006 42.62651114
OS 29.81944252 42.6094017
OS 29.8226099 42.59482972
OS 29.82451236 42.57772282
OS 29.82641228 42.5454064
OS 29.82767974 42.49725054
OS 29.8289472 42.42375056
OS 29.83211458 42.41931572
OS 29.83401704 42.41741326
OS 29.83908434 42.4161458
OS 29.85809624 42.41741326
OS 29.86253108 42.42185064
OS 29.86379854 42.4269154
OS 29.86253108 42.44339238
OS 29.85746124 42.45479698
OS 29.85619378 42.4636692
OS 29.85429386 42.48837832
OS 29.8530264 42.50232038
OS 29.85049148 42.55554354
OS 29.84922402 42.57708782
OS 29.84795656 42.59482972
OS 29.8466891 42.60496686
OS 29.84542164 42.61130416
OS 29.84415418 42.61637146
OS 29.84288672 42.62270876
OS 29.8403518 42.63791574
OS 29.83781688 42.6632624
OS 29.8352845 42.67846938
OS 29.83401704 42.68353668
OS 29.83211458 42.68924152
OS 29.83084712 42.69430882
OS 29.82957966 42.70698342
OS 29.8283122 42.71205326
OS 29.82577982 42.73739484
OS 29.82451236 42.74246468
OS 29.8232449 42.75260436
OS 29.82070998 42.75893912
OS 29.8169076 42.77414864
OS 29.81564014 42.78681816
OS 29.81437268 42.791888
OS 29.81310522 42.80456006
OS 29.81183776 42.80836244
OS 29.8105703 42.81343228
OS 29.80676792 42.82610434
OS 29.805503 42.83117418
OS 29.80296808 42.84891354
OS 29.80106816 42.86475552
OS 29.7998007 42.86982536
OS 29.79599832 42.87996504
OS 29.79283094 42.88820226
OS 29.79029602 42.8983394
OS 29.78902856 42.90594162
OS 29.78269126 42.91988114
OS 29.78015888 42.92875336
OS 29.77825642 42.94459534
OS 29.77698896 42.9509301
OS 29.77191912 42.96486962
OS 29.76875174 42.97310684
OS 29.76621682 42.98324398
OS 29.7643169 42.99021628
OS 29.76114698 42.9984535
OS 29.75734714 43.00732318
OS 29.75481222 43.0161954
OS 29.7516423 43.02949992
OS 29.74467508 43.0453419
OS 29.74214016 43.05547904
OS 29.74024024 43.0624488
OS 29.73643786 43.07258848
OS 29.73200302 43.08336062
OS 29.7294681 43.09349522
OS 29.72820064 43.10109998
OS 29.72186334 43.11123966
OS 29.72059588 43.11630696
OS 29.70665636 43.14545346
OS 29.7053889 43.15812806
OS 29.69271684 43.18473964
OS 29.68637954 43.19614678
OS 29.68004478 43.21008376
OS 29.67370748 43.2214909
OS 29.66737272 43.23543042
OS 29.6585005 43.25443978
OS 29.65660058 43.26647684
OS 29.65406566 43.27281414
OS 29.63758868 43.30576302
OS 29.62555162 43.33047468
OS 29.61414702 43.35201896
OS 29.60907718 43.3570888
OS 29.60780972 43.35962118
OS 29.60210742 43.36659348
OS 29.59767258 43.3748307
OS 29.59640512 43.38370038
OS 29.59513766 43.3913026
OS 29.59133528 43.3976399
OS 29.5875329 43.40144228
OS 29.58626544 43.40397466
OS 29.57739576 43.4153818
OS 29.57232592 43.42298656
OS 29.570426 43.42995632
OS 29.56409124 43.44009346
OS 29.56092132 43.44706322
OS 29.55775394 43.45530044
OS 29.55141664 43.46290266
OS 29.54951672 43.46480512
OS 29.54824926 43.46734004
OS 29.54254696 43.4743098
OS 29.53937704 43.47747718
OS 29.53810958 43.4800121
OS 29.5355772 43.4863494
OS 29.5292399 43.497754
OS 29.5229026 43.5040913
OS 29.52163514 43.50662368
OS 29.51783276 43.51042606
OS 29.5165653 43.51296098
OS 29.51403292 43.51549336
OS 29.511498 43.52183066
OS 29.50832808 43.53006788
OS 29.50136086 43.53703764
OS 29.5000934 43.53957256
OS 29.4943911 43.54654486
OS 29.49122372 43.54971224
OS 29.48742134 43.557317
OS 29.48742134 43.55858192
OS 29.48108404 43.56998652
OS 29.4760142 43.57505636
OS 29.47474674 43.57759128
OS 29.4582723 43.59406572
OS 29.45700484 43.59660064
OS 29.45320246 43.60040302
OS 29.45066754 43.60673778
OS 29.44750016 43.614975
OS 29.4418004 43.62067984
OS 29.44053294 43.62321476
OS 29.43673056 43.62701206
OS 29.4354631 43.62954698
OS 29.43102826 43.6327169
OS 29.42532596 43.6384192
OS 29.4240585 43.64095412
OS 29.42025612 43.6447565
OS 29.41898866 43.64728888
OS 29.41645374 43.6498238
OS 29.41391882 43.6561611
OS 29.41075144 43.66439832
OS 29.40378168 43.67136808
OS 29.40251422 43.673903
OS 29.3873047 43.68910998
OS 29.38603978 43.6916449
OS 29.38096994 43.6967122
OS 29.37970502 43.69924712
OS 29.3771701 43.70558442
OS 29.37590264 43.71065426
OS 29.3701978 43.71762402
OS 29.36703042 43.7207914
OS 29.36576296 43.72332632
OS 29.35752574 43.73156354
OS 29.35499082 43.732831
OS 29.35182344 43.73726584
OS 29.33598146 43.75310528
OS 29.33344654 43.75437274
OS 29.33027916 43.75754266
OS 29.3290117 43.76007504
OS 29.32331194 43.76577988
OS 29.32077702 43.76704734
OS 29.3176071 43.77021472
OS 29.31633964 43.77274964
OS 29.3125398 43.77655202
OS 29.31127234 43.77908694
OS 29.3062025 43.78415424
OS 29.30366758 43.79302646
OS 29.2998652 43.79936376
OS 29.29479536 43.80442852
OS 29.2935279 43.80696344
OS 29.2878256 43.81393574
OS 29.28085584 43.81963804
OS 29.27958838 43.82217296
OS 29.27515354 43.8266078
OS 29.27261862 43.82787526
OS 29.26818378 43.8323101
OS 29.26691632 43.83484502
OS 29.26248148 43.83927986
OS 29.25994656 43.84054732
OS 29.25677918 43.84371724
OS 29.25551172 43.84625216
OS 29.25107688 43.850687
OS 29.24854196 43.85195446
OS 29.24410712 43.8563893
OS 29.24283966 43.85892422
OS 29.23840228 43.86335906
OS 29.2358699 43.86462398
OS 29.23143252 43.86906136
OS 29.23016506 43.87159374
OS 29.22573022 43.87603112
OS 29.2231953 43.87729858
OS 29.22002792 43.88046596
OS 29.21876046 43.88300088
OS 29.21432562 43.88743572
OS 29.2117907 43.88870318
OS 29.20482094 43.89440548
OS 29.20165356 43.8975754
OS 29.18771404 43.9026427
OS 29.1826442 43.90771254
OS 29.18010928 43.90898
OS 29.17757436 43.91151492
OS 29.17503944 43.91278238
OS 29.1706046 43.91721722
OS 29.16933714 43.91975214
OS 29.16616976 43.92292206
OS 29.16363484 43.92418698
OS 29.1592 43.92862182
OS 29.15793254 43.93115674
OS 29.15349516 43.93559158
OS 29.15096024 43.93685904
OS 29.14526048 43.94256134
OS 29.14399302 43.94509626
OS 29.12815104 43.96093824
OS 29.12561612 43.9622057
OS 29.1237162 43.96410562
OS 29.12244874 43.96664054
OS 29.11547898 43.9736103
OS 29.11294406 43.97487776
OS 29.10660676 43.98121506
OS 29.10407184 43.98248252
OS 29.09773708 43.9850149
OS 29.09266724 43.98628236
OS 29.08570002 43.99198466
OS 29.0825301 43.99515204
OS 29.07999772 43.9964195
OS 29.0647882 44.01162902
OS 29.06225328 44.01289648
OS 29.05591852 44.01923124
OS 29.05084868 44.0204987
OS 29.04261146 44.02366862
OS 29.03690916 44.02937092
OS 29.03437424 44.03063838
OS 29.03183932 44.0331733
OS 29.0293044 44.03444076
OS 29.02233718 44.04141052
OS 29.02106972 44.04394544
OS 29.01663234 44.04711028
OS 29.0128325 44.05091266
OS 29.01029758 44.05218012
OS 29.00776266 44.05471504
OS 29.00522774 44.0559825
OS 28.99889044 44.05851488
OS 28.99002076 44.06358472
OS 28.98748584 44.06611964
OS 28.98495092 44.0673871
OS 28.96974394 44.08259408
OS 28.96720902 44.08386154
OS 28.9596068 44.0914663
OS 28.9532695 44.09400122
OS 28.94819966 44.09526868
OS 28.92539046 44.11300804
OS 28.92158808 44.11681042
OS 28.91651824 44.11807788
OS 28.90828102 44.12124526
OS 28.90511364 44.12441518
OS 28.90258126 44.1256801
OS 28.89751142 44.13074994
OS 28.8949765 44.1320174
OS 28.8886392 44.1383547
OS 28.88610428 44.13962216
OS 28.8772346 44.14342454
OS 28.86836238 44.14849184
OS 28.86329254 44.15356168
OS 28.86075762 44.15482914
OS 28.85822524 44.15736406
OS 28.85569032 44.15863152
OS 28.84935302 44.16496628
OS 28.84301826 44.1675012
OS 28.83478104 44.17066858
OS 28.82527636 44.17637088
OS 28.81893906 44.1789058
OS 28.80753446 44.1852431
OS 28.80373208 44.18904548
OS 28.80119716 44.19031294
OS 28.7942274 44.19601524
OS 28.78979256 44.20045008
OS 28.7834578 44.202985
OS 28.77522058 44.20615238
OS 28.76761582 44.21122222
OS 28.76064606 44.2143896
OS 28.75177384 44.21819198
OS 28.74923892 44.21945944
OS 28.7416367 44.22452674
OS 28.73276448 44.22832912
OS 28.7245298 44.2314965
OS 28.72262988 44.23339896
OS 28.72009496 44.23466642
OS 28.7061529 44.24100118
OS 28.6947483 44.24733848
OS 28.68080878 44.25367578
OS 28.6592645 44.26381292
OS 28.6541972 44.26508038
OS 28.64405752 44.26634784
OS 28.63518784 44.27141768
OS 28.62631562 44.27522006
OS 28.6180784 44.27838744
OS 28.61047364 44.28345728
OS 28.58829944 44.29422688
OS 28.55408056 44.31070132
OS 28.54521342 44.31323624
OS 28.5363412 44.3145037
OS 28.50972708 44.32717576
OS 28.49071772 44.33604798
OS 28.48184804 44.33731544
OS 28.46981098 44.34175028
OS 28.46347368 44.34428266
OS 28.45650392 44.34745258
OS 28.45143408 44.3487175
OS 28.43812702 44.35188742
OS 28.43178972 44.35442234
OS 28.4248225 44.35758972
OS 28.4184852 44.36012464
OS 28.4134179 44.3613921
OS 28.40391068 44.36329202
OS 28.39377354 44.3670944
OS 28.38680378 44.37026178
OS 28.38046648 44.3727967
OS 28.37159426 44.37406416
OS 28.3595572 44.37850154
OS 28.35131998 44.38166892
OS 28.34498522 44.38420384
OS 28.336113 44.3854713
OS 28.33104316 44.38673876
OS 28.31710364 44.38800622
OS 28.30569904 44.39307352
OS 28.29936428 44.39560844
OS 28.2892246 44.39814336
OS 28.28161984 44.39941082
OS 28.27021524 44.40447812
OS 28.26387794 44.40701304
OS 28.25500826 44.40954796
OS 28.23916882 44.41144788
OS 28.23283152 44.41271534
OS 28.22269438 44.41651772
OS 28.21572208 44.41841764
OS 28.21065478 44.4196851
OS 28.1948128 44.42158756
OS 28.18087328 44.42285502
OS 28.15806408 44.42665486
OS 28.15299424 44.42792232
OS 28.14602448 44.42982478
OS 28.14095464 44.43109224
OS 28.12321528 44.43362716
OS 28.10610584 44.43552708
OS 28.09850108 44.43679454
OS 28.08836394 44.438062
OS 28.08202664 44.43932946
OS 28.0769568 44.44059692
OS 28.06998704 44.44249684
OS 28.0547826 44.44503176
OS 28.02246618 44.44819914
OS 28.00535928 44.4501016
OS 27.99648706 44.45136906
OS 27.9895173 44.45326898
OS 27.98318 44.45453644
OS 27.9660731 44.4564389
OS 27.94199644 44.45770382
OS 27.925522 44.45897128
OS 27.91601478 44.45960628
OS 27.91031248 44.45897128
OS 27.9065101 44.46023874
OS 27.88053352 44.4621412
OS 27.86786146 44.46340866
OS 27.8539194 44.46594104
OS 27.84378226 44.4672085
OS 27.82097306 44.46847596
OS 27.807031 44.46974342
OS 27.7829518 44.47100834
OS 27.74937046 44.47164334
OE
OB 27.45790292 43.58329358 H
OS 26.72732526 43.58265858
OS 26.71275074 43.58329358
OS 26.70894836 43.58202612
OS 26.6962763 43.58075866
OS 26.66016004 43.57885874
OS 26.6557252 43.57695628
OS 26.64622052 43.5674516
OS 26.64495306 43.5623843
OS 26.6430506 43.52373312
OS 26.64115068 43.50662368
OS 26.64051568 42.4630342
OS 26.64178314 42.44782722
OS 26.64495306 42.44339238
OS 26.64685298 42.44148992
OS 26.65192282 42.44022246
OS 26.90157434 42.44148992
OS 26.90600918 42.4459273
OS 26.90727664 42.4509946
OS 26.9079091 42.52639704
OS 26.90727664 42.53083442
OS 26.9085441 42.5346368
OS 26.90727664 42.54730632
OS 26.9085441 42.5865925
OS 26.9079091 43.31083286
OS 26.90917656 43.32224
OS 26.91171148 43.3260373
OS 26.91804878 43.32857222
OS 27.12080936 43.32730476
OS 27.1252442 43.32413992
OS 27.12651166 43.31907008
OS 27.12714412 43.31210032
OS 27.12651166 43.30513056
OS 27.12777912 43.30132818
OS 27.12714412 43.23986526
OS 27.12777912 43.2328955
OS 27.12651166 43.22909312
OS 27.12714412 43.20691638
OS 27.12651166 43.19361186
OS 27.12777912 43.18980948
OS 27.12714412 43.17143258
OS 27.12777912 42.55364362
OS 27.12777912 42.55237616
OS 27.12904658 42.50041792
OS 27.13031404 42.49661554
OS 27.1315815 42.45986682
OS 27.13791626 42.4509946
OS 27.14108618 42.44782722
OS 27.1436211 42.44655976
OS 27.14995586 42.44402484
OS 27.19304442 42.44275738
OS 27.19684426 42.44148992
OS 27.20571648 42.44022246
OS 27.22472584 42.44148992
OS 27.22852568 42.44022246
OS 27.36285612 42.44148992
OS 27.36855842 42.4459273
OS 27.36982588 42.4509946
OS 27.37109334 43.321605
OS 27.37552818 43.32730476
OS 27.3844004 43.32857222
OS 27.43509118 43.32983968
OS 27.43889102 43.33110714
OS 27.4490307 43.3323746
OS 27.45156562 43.33490952
OS 27.45410054 43.33617698
OS 27.45980284 43.34187928
OS 27.4610703 43.3444142
OS 27.46360522 43.3507515
OS 27.46550514 43.39320252
OS 27.4667726 43.39953982
OS 27.46740506 43.4153818
OS 27.46614014 43.41918418
OS 27.46740506 43.43185624
OS 27.46614014 43.57759128
OS 27.46423768 43.58075866
OS 27.45790292 43.58329358
OE
OB 28.81640414 43.58329358 H
OS 28.8126043 43.58202612
OS 28.7999297 43.58329358
OS 28.26007556 43.58202612
OS 28.25627572 43.58075866
OS 28.21762454 43.57885874
OS 28.20748486 43.57505636
OS 28.19354534 43.56998652
OS 28.1891105 43.56681914
OS 28.18657812 43.56428676
OS 28.1840432 43.5630193
OS 28.18150828 43.56048438
OS 28.17897336 43.55921692
OS 28.17327106 43.55351462
OS 28.1720036 43.5509797
OS 28.16883622 43.54780978
OS 28.1663013 43.54654486
OS 28.159329 43.53957256
OS 28.15806408 43.53703764
OS 28.15616162 43.53513772
OS 28.1536267 43.53387026
OS 28.1479244 43.52816796
OS 28.14665694 43.52563304
OS 28.14475702 43.52373312
OS 28.1422221 43.52246566
OS 28.13525234 43.51549336
OS 28.13398488 43.51296098
OS 28.1295475 43.50979106
OS 28.12384774 43.5040913
OS 28.12258028 43.50155638
OS 28.12068036 43.49965646
OS 28.11814544 43.498389
OS 28.11244314 43.49268416
OS 28.11117568 43.49015178
OS 28.10800576 43.48698186
OS 28.10547084 43.4857144
OS 28.09850108 43.47874464
OS 28.09723362 43.47620972
OS 28.0953337 43.4743098
OS 28.09279878 43.47304234
OS 28.08709648 43.46734004
OS 28.08582902 43.46480512
OS 28.08392656 43.46290266
OS 28.08139418 43.4616352
OS 28.07568934 43.4559329
OS 28.07442188 43.45339798
OS 28.0712545 43.4502306
OS 28.06871958 43.44896314
OS 28.06301982 43.44326338
OS 28.06175236 43.44072846
OS 28.0598499 43.438826
OS 28.05731752 43.43755854
OS 28.05161268 43.43185624
OS 28.05034522 43.42932132
OS 28.042743 43.41791672
OS 28.04020808 43.40777704
OS 28.03894062 43.3913026
OS 28.03767316 43.38750022
OS 28.0364057 43.38243292
OS 28.03387078 43.37609816
OS 28.03260332 43.37102832
OS 28.03133586 43.35835372
OS 28.02943594 43.3260373
OS 28.02816848 43.28802112
OS 28.02753348 42.72345786
OS 28.02880094 42.71965548
OS 28.0300684 42.66769724
OS 28.03133586 42.6638974
OS 28.03260332 42.63855074
OS 28.03767316 42.6271436
OS 28.03957308 42.61890638
OS 28.04147554 42.60686678
OS 28.04781284 42.59673218
OS 28.05034522 42.59039488
OS 28.0541476 42.58025774
OS 28.0598499 42.57328544
OS 28.06301982 42.57011806
OS 28.06428728 42.56758314
OS 28.0712545 42.56061338
OS 28.07378942 42.55934592
OS 28.08012672 42.55300862
OS 28.08646148 42.5504737
OS 28.0946987 42.54730632
OS 28.09913608 42.54414148
OS 28.10230346 42.5397041
OS 28.10547084 42.53653672
OS 28.10800576 42.53526926
OS 28.10990822 42.53336934
OS 28.11244314 42.52703204
OS 28.11434306 42.52006228
OS 28.11624298 42.51815982
OS 28.11751044 42.5156249
OS 28.12068036 42.51245752
OS 28.12321528 42.51119006
OS 28.12638266 42.50675522
OS 28.1295475 42.5035853
OS 28.14538948 42.497883
OS 28.1479244 42.49534808
OS 28.14919186 42.49281316
OS 28.1536267 42.48837832
OS 28.15616162 42.48711086
OS 28.15806408 42.48521094
OS 28.16059646 42.47887618
OS 28.16376638 42.47063896
OS 28.16693376 42.46620412
OS 28.1713686 42.4630342
OS 28.17327106 42.46113428
OS 28.17453852 42.45859936
OS 28.1777059 42.45543198
OS 28.1840432 42.45289706
OS 28.19608026 42.44845968
OS 28.20431748 42.4452923
OS 28.22079192 42.44402484
OS 28.2531058 42.44212492
OS 28.30633404 42.44085746
OS 28.66306688 42.44022246
OS 28.66433434 42.44022246
OS 28.89751142 42.44148992
OS 28.9006788 42.44465984
OS 28.90321372 42.45479698
OS 28.90194626 42.66516232
OS 28.89751142 42.66959716
OS 28.89244158 42.67086462
OS 28.44699924 42.67149708
OS 28.43115726 42.67086462
OS 28.42735488 42.67213208
OS 28.4064456 42.67149708
OS 28.39187362 42.67213208
OS 28.38807124 42.67086462
OS 28.37603164 42.67276454
OS 28.37286172 42.67339954
OS 28.36906188 42.67213208
OS 28.35892474 42.67086462
OS 28.35512236 42.67213208
OS 28.34498522 42.674667
OS 28.3120338 42.67593446
OS 28.29999674 42.68797406
OS 28.29872928 42.69304136
OS 28.29746182 42.70191358
OS 28.29619436 42.73106008
OS 28.2949269 42.73486246
OS 28.29619436 42.75640674
OS 28.2949269 42.76020658
OS 28.2955619 42.84067886
OS 28.2949269 42.85398338
OS 28.29619436 42.85778576
OS 28.29746182 42.86665798
OS 28.29872928 42.89453702
OS 28.30506658 42.90340924
OS 28.31076634 42.909109
OS 28.32090602 42.91164392
OS 28.35258744 42.91291138
OS 28.35638982 42.91417884
OS 28.3772991 42.91354638
OS 28.80436454 42.9148113
OS 28.8119693 42.91607876
OS 28.81577168 42.91988114
OS 28.8183066 42.92875336
OS 28.8176716 43.0218977
OS 28.8183066 43.03393476
OS 28.81703914 43.03773714
OS 28.81577168 43.05421158
OS 28.81450422 43.06688618
OS 28.81387176 43.08145816
OS 28.81450422 43.085893
OS 28.81323676 43.08969538
OS 28.80943438 43.09603014
OS 28.80246462 43.10300244
OS 28.7935924 43.10553482
OS 28.75177384 43.10680228
OS 28.747974 43.10806974
OS 28.73910178 43.1093372
OS 28.72262988 43.10806974
OS 28.71375766 43.1093372
OS 28.69791568 43.10870474
OS 28.30253166 43.1099722
OS 28.29809682 43.11187212
OS 28.2949269 43.11884188
OS 28.2955619 43.2512724
OS 28.2949269 43.26584438
OS 28.29619436 43.26964676
OS 28.2955619 43.29055604
OS 28.29682936 43.29689334
OS 28.29809682 43.31843762
OS 28.29936428 43.33490952
OS 28.3012642 43.33680944
OS 28.30253166 43.33934436
OS 28.30949888 43.34631666
OS 28.3120338 43.34758158
OS 28.31583618 43.34884904
OS 28.35068752 43.3507515
OS 28.35575736 43.35201896
OS 28.36779442 43.35265142
OS 28.37159426 43.35138396
OS 28.394406 43.35265142
OS 28.39820838 43.35138396
OS 28.41088298 43.35265142
OS 28.89624396 43.35391888
OS 28.9006788 43.3570888
OS 28.90321372 43.36595848
OS 28.90258126 43.47050742
OS 28.90321372 43.48508194
OS 28.90194626 43.48888432
OS 28.90321372 43.51042606
OS 28.90194626 43.51422844
OS 28.9006788 43.51929574
OS 28.89877888 43.5630193
OS 28.89687642 43.5674516
OS 28.8943415 43.56998652
OS 28.89307404 43.57252144
OS 28.89117412 43.57442136
OS 28.8886392 43.57568882
OS 28.88610428 43.57822374
OS 28.88103698 43.5794912
OS 28.83858342 43.58139112
OS 28.83224612 43.58265858
OS 28.81640414 43.58329358
OE
OB 26.01829188 43.58329358 H
OS 26.01449204 43.58202612
OS 26.00181744 43.58329358
OS 25.23512606 43.58202612
OS 25.23068868 43.57759128
OS 25.22942122 43.56871906
OS 25.23005622 43.4147468
OS 25.22942122 43.40144228
OS 25.23068868 43.3976399
OS 25.23195614 43.38876768
OS 25.2338586 43.34884904
OS 25.23575852 43.3444142
OS 25.24082836 43.33934436
OS 25.24146082 43.33744444
OS 25.24399574 43.33617698
OS 25.24653066 43.33364206
OS 25.25540034 43.3323746
OS 25.29405152 43.33047468
OS 25.30038882 43.32920722
OS 25.31622826 43.32857222
OS 25.32003064 43.32983968
OS 25.3327027 43.32857222
OS 25.41064006 43.32793976
OS 25.4214122 43.32857222
OS 25.42521458 43.32730476
OS 25.44612386 43.32793976
OS 25.4619633 43.32730476
OS 25.46576568 43.32857222
OS 25.47653782 43.3266723
OS 25.51645646 43.32350746
OS 25.52849606 43.31146786
OS 25.52976352 43.30639802
OS 25.52976352 43.29499088
OS 25.52976352 43.29372342
OS 25.53103098 43.28485374
OS 25.53229844 43.26584438
OS 25.5335659 43.26204454
OS 25.53229844 43.24936994
OS 25.5335659 43.23036058
OS 25.53229844 43.2265582
OS 25.5335659 43.20501392
OS 25.53229844 43.20121662
OS 25.5335659 43.18854202
OS 25.53483336 42.4459273
OS 25.53800074 42.44275738
OS 25.54307058 42.44148992
OS 25.55193772 42.44022246
OS 25.68817062 42.44085746
OS 25.70274514 42.44022246
OS 25.70654498 42.44148992
OS 25.7268218 42.44022246
OS 25.73062164 42.44148992
OS 25.73949386 42.44275738
OS 25.77941504 42.44465984
OS 25.7857498 42.44719476
OS 25.79461948 42.45606444
OS 25.7971544 42.46493666
OS 25.79842186 42.50548776
OS 25.79968932 42.50929014
OS 25.80095678 42.5219622
OS 25.79968932 42.5346368
OS 25.80095678 42.54350648
OS 25.80032178 42.55934592
OS 25.80158924 43.2208559
OS 25.80222424 43.22782566
OS 25.80095678 43.23162804
OS 25.80222424 43.25443978
OS 25.80095678 43.25824216
OS 25.80222424 43.27217914
OS 25.8034917 43.27598152
OS 25.80412416 43.30069572
OS 25.8034917 43.30132818
OS 25.80475916 43.30513056
OS 25.80602408 43.31146786
OS 25.81806368 43.32350746
OS 25.8269359 43.32477238
OS 25.84658026 43.32540484
OS 25.8497451 43.32477238
OS 25.85354748 43.3260373
OS 25.86431962 43.32793976
OS 25.87128938 43.32857222
OS 25.87509176 43.32730476
OS 25.89853596 43.32793976
OS 25.91057302 43.32730476
OS 25.9143754 43.32857222
OS 25.93148484 43.32793976
OS 25.9973826 43.32920722
OS 26.00435236 43.32983968
OS 26.00815474 43.32857222
OS 26.0271641 43.32983968
OS 26.03096394 43.33110714
OS 26.0734175 43.3330096
OS 26.08925694 43.34251428
OS 26.09242686 43.34568166
OS 26.09749416 43.35455388
OS 26.10129654 43.36342356
OS 26.103199 43.40714458
OS 26.10446646 43.41348188
OS 26.10509892 43.42551894
OS 26.10383146 43.42932132
OS 26.10509892 43.45466544
OS 26.10383146 43.45846782
OS 26.10509892 43.47494226
OS 26.10383146 43.497754
OS 26.10509892 43.50155638
OS 26.10383146 43.51549336
OS 26.102564 43.51929574
OS 26.10066408 43.5630193
OS 26.09876162 43.5674516
OS 26.09305932 43.57442136
OS 26.0854571 43.5794912
OS 26.04046862 43.58139112
OS 26.03413132 43.58265858
OS 26.01829188 43.58329358
OE
OB 26.455497 43.58329358 H
OS 26.24893404 43.58329358
OS 26.22105246 43.58202612
OS 26.21661762 43.57885874
OS 26.21535016 43.5737889
OS 26.2147177 43.56935406
OS 26.21535016 43.56111684
OS 26.2140827 43.557317
OS 26.21535016 43.54844478
OS 26.21661762 42.4459273
OS 26.22105246 42.44148992
OS 26.23372706 42.44022246
OS 26.46309922 42.44148992
OS 26.4675366 42.44465984
OS 26.47007152 42.45352952
OS 26.46880406 43.57759128
OS 26.46436668 43.58202612
OS 26.455497 43.58329358
OE
OB 29.68321216 42.29448996 H
OS 29.67941232 42.2932225
OS 29.66040042 42.29448996
OS 29.65660058 42.2932225
OS 29.63568876 42.29385496
OS 29.628084 42.2925875
OS 29.61034464 42.29132004
OS 29.6059098 42.29068758
OS 29.60464234 42.29068758
OS 29.59006782 42.29005512
OS 29.58309806 42.29068758
OS 29.57929568 42.28942012
OS 29.57676076 42.28815266
OS 29.57295838 42.28435028
OS 29.570426 42.28308282
OS 29.56852354 42.2811829
OS 29.56725608 42.27864798
OS 29.5647237 42.27231068
OS 29.56282378 42.2349295
OS 29.56155632 42.22478982
OS 29.56028886 41.17929788
OS 29.55965386 41.17106066
OS 29.56092132 41.16725828
OS 29.56218878 41.15585622
OS 29.5653587 41.1526863
OS 29.57422584 41.15141884
OS 30.2870616 41.15205384
OS 30.3041685 41.15141884
OS 30.30797088 41.1526863
OS 30.32064548 41.15395376
OS 30.35676174 41.15585622
OS 30.36626642 41.16155852
OS 30.36880134 41.16282598
OS 30.37323618 41.16599082
OS 30.37450364 41.16852574
OS 30.49742694 41.29145158
OS 30.4986944 41.29398396
OS 30.50629916 41.30158872
OS 30.50883408 41.30792602
OS 30.51326892 41.31996562
OS 30.51516884 41.32566792
OS 30.5164363 41.33073776
OS 30.51833876 41.36051672
OS 30.52023868 41.39790298
OS 30.52150614 41.50942168
OS 30.52087368 42.02709654
OS 30.52150614 42.03533376
OS 30.52023868 42.03913614
OS 30.52087368 42.06131288
OS 30.51960622 42.06764764
OS 30.5170713 42.10186652
OS 30.5164363 42.10756882
OS 30.51770376 42.1113712
OS 30.5164363 42.1164385
OS 30.51010154 42.1278431
OS 30.5043967 42.13481286
OS 30.49742694 42.14051516
OS 30.49615948 42.14305008
OS 30.49045718 42.14875238
OS 30.48792226 42.15001984
OS 30.48475488 42.15318976
OS 30.48348742 42.15572468
OS 30.47778512 42.16142698
OS 30.4752502 42.16269444
OS 30.47334774 42.16459436
OS 30.47208028 42.16712928
OS 30.46637798 42.17283158
OS 30.4638456 42.17409904
OS 30.46067822 42.17726896
OS 30.45941076 42.17980388
OS 30.45370846 42.18550364
OS 30.45117354 42.1867711
OS 30.44927108 42.18867102
OS 30.44800362 42.19120594
OS 30.44230132 42.19690824
OS 30.4397664 42.1981757
OS 30.43659902 42.20134562
OS 30.43533156 42.203878
OS 30.42962926 42.20958284
OS 30.42709434 42.2108503
OS 30.42392696 42.21401768
OS 30.4226595 42.2165526
OS 30.41695466 42.2222549
OS 30.41442228 42.22352236
OS 30.41251982 42.22542228
OS 30.41125236 42.2279572
OS 30.4055526 42.23366204
OS 30.40301768 42.2349295
OS 30.3998503 42.23809688
OS 30.39858284 42.2406318
OS 30.392878 42.24633156
OS 30.39034562 42.24759902
OS 30.38844316 42.24949894
OS 30.3871757 42.25203386
OS 30.3814734 42.2577387
OS 30.37893848 42.25900362
OS 30.3757711 42.26217354
OS 30.37450364 42.26470846
OS 30.36880134 42.27041076
OS 30.36626642 42.27167822
OS 30.35992912 42.27801552
OS 30.3573942 42.27928298
OS 30.34852452 42.28308282
OS 30.3402873 42.28625274
OS 30.33395254 42.28878766
OS 30.32634778 42.29005512
OS 30.3231804 42.29068758
OS 30.31937802 42.28942012
OS 30.31557564 42.29068758
OS 30.28072684 42.2925875
OS 30.22496622 42.29385496
OS 29.68321216 42.29448996
OE
OB 27.03336986 42.29448996 H
OS 27.02956748 42.2932225
OS 27.00485328 42.29385496
OS 27.00422082 42.2932225
OS 26.96873956 42.29448996
OS 26.48084366 42.2932225
OS 26.47704128 42.29195504
OS 26.44092502 42.29005512
OS 26.42698296 42.28878766
OS 26.4206482 42.28625274
OS 26.41050852 42.28245036
OS 26.40417376 42.27991544
OS 26.39973638 42.27674806
OS 26.395934 42.27294568
OS 26.39340162 42.27167822
OS 26.3908667 42.2691433
OS 26.38833178 42.26787584
OS 26.38643186 42.26597592
OS 26.3851644 42.263441
OS 26.3794621 42.2577387
OS 26.37692718 42.25647124
OS 26.3737598 42.25330132
OS 26.37249234 42.2507664
OS 26.36679004 42.24506664
OS 26.36425512 42.24379918
OS 26.3610852 42.2406318
OS 26.35981774 42.23809688
OS 26.35411544 42.23239458
OS 26.35158052 42.23112712
OS 26.3496806 42.22922466
OS 26.34841314 42.22668974
OS 26.34144338 42.21971998
OS 26.33890846 42.21845252
OS 26.33700854 42.2165526
OS 26.33574108 42.21401768
OS 26.33003624 42.20831538
OS 26.32750386 42.20704792
OS 26.32433648 42.203878
OS 26.32306902 42.20134562
OS 26.31736672 42.19564078
OS 26.3148318 42.19437332
OS 26.31293188 42.1924734
OS 26.31166442 42.18993848
OS 26.30595958 42.18423872
OS 26.3034272 42.18297126
OS 26.30025728 42.17980388
OS 26.29898982 42.17726896
OS 26.29455498 42.17283158
OS 26.29202006 42.17156412
OS 26.28885268 42.16839674
OS 26.28758522 42.16586182
OS 26.28188292 42.16015952
OS 26.279348 42.15889206
OS 26.27617808 42.15572468
OS 26.27491062 42.15318976
OS 26.27047578 42.14875238
OS 26.26794086 42.14748746
OS 26.26350856 42.14305008
OS 26.25970618 42.13671532
OS 26.25336888 42.1278431
OS 26.25210142 42.1227758
OS 26.2502015 42.1107362
OS 26.24639912 42.10059906
OS 26.2444992 42.09362676
OS 26.24323174 42.08855946
OS 26.24132928 42.0524432
OS 26.24006182 42.01695686
OS 26.23942936 41.4169098
OS 26.24069682 41.41310742
OS 26.24196428 41.35988172
OS 26.24323174 41.35608188
OS 26.2444992 41.33707252
OS 26.25083396 41.323133
OS 26.25210142 41.31806316
OS 26.25843872 41.30919348
OS 26.2622411 41.3053911
OS 26.26350856 41.30285618
OS 26.27047578 41.29588642
OS 26.2730107 41.29461896
OS 26.27491062 41.29271904
OS 26.27617808 41.29018412
OS 26.28314784 41.28321436
OS 26.28568276 41.2819469
OS 26.28885268 41.27751206
OS 26.29455498 41.27180976
OS 26.2970899 41.2705423
OS 26.29898982 41.26864238
OS 26.30025728 41.26610746
OS 26.30722704 41.25913516
OS 26.30976196 41.25787024
OS 26.31166442 41.25596778
OS 26.31293188 41.25343286
OS 26.31990164 41.2464631
OS 26.32243656 41.24519564
OS 26.32560394 41.2407608
OS 26.3313037 41.2350585
OS 26.33383862 41.23379104
OS 26.33700854 41.22935366
OS 26.3439783 41.22238644
OS 26.34651322 41.22111898
OS 26.3496806 41.21668414
OS 26.3553829 41.21098184
OS 26.35791782 41.20971438
OS 26.35981774 41.20781192
OS 26.3610852 41.205277
OS 26.3680575 41.19830724
OS 26.37058988 41.19703978
OS 26.37249234 41.19513986
OS 26.3737598 41.19260494
OS 26.38072956 41.18563518
OS 26.38326448 41.18436772
OS 26.38643186 41.17993288
OS 26.39213416 41.17422804
OS 26.39466654 41.17296058
OS 26.396569 41.17106066
OS 26.39783646 41.16852574
OS 26.39973638 41.1653609
OS 26.4022713 41.16409344
OS 26.41621082 41.15522122
OS 26.45993184 41.1533213
OS 26.4675366 41.15205384
OS 26.4846435 41.15141884
OS 26.48844588 41.1526863
OS 26.4973181 41.15141884
OS 27.10940222 41.1526863
OS 27.11257214 41.15585622
OS 27.11510706 41.16599082
OS 27.11447206 41.2819469
OS 27.11510706 41.29271904
OS 27.1138396 41.29651888
OS 27.11447206 41.31869816
OS 27.1132046 41.32630038
OS 27.11193714 41.34404482
OS 27.11066968 41.36051672
OS 27.11003722 41.36495156
OS 27.11130468 41.36875394
OS 27.11003722 41.37382378
OS 27.10876976 41.37762616
OS 27.10307 41.38459592
OS 27.10053508 41.38713084
OS 27.09419778 41.38966576
OS 27.05300914 41.39156568
OS 27.03590478 41.3934656
OS 27.02133026 41.39283314
OS 26.67790194 41.3941006
OS 26.6031345 41.39536806
OS 26.56891562 41.39663552
OS 26.54103658 41.39790298
OS 26.53596928 41.39917044
OS 26.52963198 41.40170536
OS 26.52139476 41.40487274
OS 26.51632492 41.40613766
OS 26.5080877 41.4105725
OS 26.50682278 41.41564234
OS 26.50745524 41.9637337
OS 26.50682278 41.97830822
OS 26.5080877 41.98210806
OS 26.50935516 41.9871779
OS 26.51062262 42.02012678
OS 26.51632492 42.02709654
OS 26.52266222 42.03343384
OS 26.53279936 42.03596876
OS 26.56575078 42.03723368
OS 26.56955062 42.03850114
OS 26.5904599 42.03786868
OS 26.93262076 42.03913614
OS 27.0073882 42.0404036
OS 27.0606139 42.04420598
OS 27.06568374 42.04547344
OS 27.07645588 42.04864082
OS 27.08152572 42.04990828
OS 27.09419778 42.05117574
OS 27.10940222 42.0524432
OS 27.11257214 42.05561058
OS 27.11510706 42.06574772
OS 27.11447206 42.1817038
OS 27.11510706 42.19374086
OS 27.1138396 42.19754324
OS 27.11447206 42.21971998
OS 27.1132046 42.22605728
OS 27.11066968 42.26153854
OS 27.11003722 42.26597592
OS 27.11130468 42.26977576
OS 27.11003722 42.2748456
OS 27.10876976 42.27738052
OS 27.10307 42.28435028
OS 27.09926762 42.28815266
OS 27.0903954 42.29068758
OS 27.08152572 42.28942012
OS 27.07772334 42.29068758
OS 27.04667692 42.2925875
OS 27.03907216 42.29385496
OS 27.03336986 42.29448996
OE
OB 28.02816848 42.29448996 H
OS 28.0243661 42.2932225
OS 28.01486142 42.29132004
OS 27.99838952 42.29005512
OS 27.99395214 42.28815266
OS 27.99141976 42.28561774
OS 27.98888484 42.28435028
OS 27.98001262 42.27801552
OS 27.97367532 42.27041076
OS 27.96797302 42.26597592
OS 27.96670556 42.263441
OS 27.9597358 42.25647124
OS 27.95720088 42.25520378
OS 27.95530096 42.25330132
OS 27.9540335 42.2507664
OS 27.9483312 42.24506664
OS 27.94579882 42.24379918
OS 27.9426289 42.2406318
OS 27.94136144 42.23809688
OS 27.93565914 42.23239458
OS 27.93312422 42.23112712
OS 27.9312243 42.22922466
OS 27.92995684 42.22668974
OS 27.92298708 42.21971998
OS 27.92045216 42.21845252
OS 27.9185497 42.2165526
OS 27.91728224 42.21401768
OS 27.91157994 42.20831538
OS 27.90904502 42.20704792
OS 27.9071451 42.20514546
OS 27.90587764 42.20261308
OS 27.89890788 42.19564078
OS 27.89637296 42.19437332
OS 27.8944705 42.1924734
OS 27.89320558 42.18993848
OS 27.88750074 42.18423872
OS 27.88496836 42.18297126
OS 27.88180098 42.17980388
OS 27.88053352 42.17726896
OS 27.87483122 42.17156412
OS 27.8722963 42.17029666
OS 27.87039384 42.16839674
OS 27.86912892 42.16586182
OS 27.86215662 42.15889206
OS 27.8596217 42.1576246
OS 27.85772178 42.15572468
OS 27.85645432 42.15318976
OS 27.85075202 42.14748746
OS 27.8482171 42.14622
OS 27.84631718 42.14431754
OS 27.84504972 42.14178262
OS 27.83807742 42.13481286
OS 27.83554504 42.1335454
OS 27.83364258 42.13164548
OS 27.83237512 42.12911056
OS 27.82667536 42.1234108
OS 27.82414044 42.12214334
OS 27.82097306 42.11897342
OS 27.8197056 42.1164385
OS 27.8140033 42.1107362
OS 27.81146838 42.10946874
OS 27.80956592 42.10756882
OS 27.80829846 42.1050339
OS 27.8013287 42.09806414
OS 27.79879378 42.09679668
OS 27.79689386 42.09489422
OS 27.7956264 42.0923593
OS 27.78865664 42.08538954
OS 27.78612172 42.08412208
OS 27.77661704 42.07081502
OS 27.77978442 42.06511526
OS 27.78865664 42.0638478
OS 27.79816132 42.06321534
OS 27.84441472 42.0638478
OS 27.8482171 42.06258034
OS 27.86469154 42.0638478
OS 27.91221494 42.06194788
OS 27.92235208 42.06321534
OS 27.925522 42.0638478
OS 27.92932184 42.06258034
OS 27.94199644 42.06131288
OS 27.97050794 42.05941296
OS 27.9774777 42.05497812
OS 27.98571492 42.0467409
OS 27.98698238 42.04167106
OS 27.98888484 42.00681972
OS 27.9901523 42.00175242
OS 27.99078476 41.98971282
OS 27.9895173 41.98591044
OS 27.99078476 41.9630987
OS 27.9895173 41.95929632
OS 27.99078476 41.95042664
OS 27.9901523 41.83574056
OS 27.99078476 41.81990112
OS 27.9895173 41.81609874
OS 27.99078476 41.79582192
OS 27.98824984 41.78948462
OS 27.98634992 41.75336836
OS 27.98001262 41.74323122
OS 27.97494278 41.73562646
OS 27.97240786 41.734359
OS 27.96227072 41.7280217
OS 27.9533985 41.72548932
OS 27.94643128 41.72612178
OS 27.92361954 41.72485432
OS 27.9185497 41.72358686
OS 27.90397772 41.7229544
OS 27.90017534 41.72422186
OS 27.88750074 41.7229544
OS 27.62834708 41.72358686
OS 27.61250764 41.7229544
OS 27.60617034 41.72548932
OS 27.58272614 41.72612178
OS 27.57575638 41.72548932
OS 27.571954 41.72675424
OS 27.56942162 41.7280217
OS 27.56181686 41.73309154
OS 27.55928194 41.734359
OS 27.55357964 41.73879384
OS 27.55231218 41.74132876
OS 27.54597488 41.75020098
OS 27.5421725 41.75907066
OS 27.54090504 41.78314732
OS 27.53963758 41.79835684
OS 27.53520274 41.80279168
OS 27.5301329 41.80152422
OS 27.52759798 41.7989893
OS 27.52506814 41.79772184
OS 27.50985862 41.78251486
OS 27.5073237 41.7812474
OS 27.50542378 41.77934748
OS 27.50415632 41.77681256
OS 27.49718656 41.7698428
OS 27.49465164 41.76857534
OS 27.48831434 41.76097312
OS 27.4832445 41.75590328
OS 27.48071212 41.75463582
OS 27.4775422 41.75020098
OS 27.47310736 41.74576614
OS 27.47057244 41.74449868
OS 27.46740506 41.7400613
OS 27.46170276 41.734359
OS 27.45916784 41.73309154
OS 27.45726792 41.73119162
OS 27.45600046 41.7286567
OS 27.4490307 41.72168694
OS 27.44649578 41.72041948
OS 27.44459586 41.71851702
OS 27.4433284 41.7159821
OS 27.43635864 41.70901234
OS 27.43445618 41.70837988
OS 27.43318872 41.70584496
OS 27.4249515 41.69761028
OS 27.42241658 41.69634282
OS 27.4192492 41.6931729
OS 27.41798174 41.69064052
OS 27.41101198 41.68366822
OS 27.40910952 41.68303576
OS 27.40784206 41.68050084
OS 27.39960738 41.67226362
OS 27.39707246 41.67099616
OS 27.39390508 41.66656132
OS 27.38820278 41.66085648
OS 27.38566786 41.65958902
OS 27.3837654 41.6576891
OS 27.38249794 41.65515418
OS 27.37552818 41.64818442
OS 27.37299326 41.64691696
OS 27.37109334 41.64501958
OS 27.36982588 41.64248466
OS 27.36158866 41.63424744
OS 27.35968874 41.63361244
OS 27.35842128 41.63107752
OS 27.35018152 41.6228403
OS 27.34764914 41.62157284
OS 27.34448176 41.617138
OS 27.34004692 41.61270316
OS 27.337512 41.6114357
OS 27.33561208 41.60953324
OS 27.33434462 41.60699832
OS 27.32737232 41.60002856
OS 27.32483994 41.5987611
OS 27.32293748 41.59686118
OS 27.32167002 41.59432626
OS 27.31470026 41.5873565
OS 27.31216534 41.58608904
OS 27.30899796 41.5816542
OS 27.3020282 41.57468444
OS 27.29949328 41.57341698
OS 27.29759082 41.57151706
OS 27.28872114 41.5525077
OS 27.2899886 41.54236802
OS 27.28872114 41.53856564
OS 27.28682122 41.50878668
OS 27.28555376 41.50118446
OS 27.2849213 41.49421216
OS 27.28618876 41.49041232
OS 27.28555376 41.46696558
OS 27.28618876 41.45366106
OS 27.2849213 41.44985868
OS 27.28555376 41.43275178
OS 27.2849213 41.1647259
OS 27.28618876 41.16092352
OS 27.28745368 41.15585622
OS 27.29062106 41.1526863
OS 27.2956909 41.15141884
OS 27.53520274 41.1526863
OS 27.53837012 41.15585622
OS 27.54090504 41.16599082
OS 27.54154004 41.39093322
OS 27.54090504 41.4004379
OS 27.5421725 41.40423774
OS 27.54343996 41.4587309
OS 27.54470742 41.46253328
OS 27.54597488 41.47647026
OS 27.55104472 41.4878774
OS 27.55231218 41.4929447
OS 27.5548471 41.499282
OS 27.55801448 41.50245192
OS 27.56308432 41.50371684
OS 27.57512392 41.50815422
OS 27.58145868 41.51068914
OS 27.58652852 41.5119566
OS 27.61440756 41.51322406
OS 27.64988882 41.51448898
OS 27.72339134 41.51575644
OS 27.807666 41.51639144
OS 27.81146838 41.51512398
OS 27.91664978 41.51385652
OS 27.92045216 41.51258906
OS 27.94959612 41.5113216
OS 27.96353818 41.5049843
OS 27.9717754 41.50308438
OS 27.97621024 41.499917
OS 27.97938016 41.4929447
OS 27.98128008 41.48470748
OS 27.98698238 41.47140042
OS 27.98888484 41.43275178
OS 27.9901523 41.382061
OS 27.99141976 41.16155852
OS 27.99268468 41.15648868
OS 27.99648706 41.1526863
OS 28.0015569 41.15141884
OS 28.24106874 41.1526863
OS 28.24423866 41.15585622
OS 28.24550612 41.16092352
OS 28.24613858 41.23759088
OS 28.24550612 41.24202826
OS 28.24677358 41.24583064
OS 28.24550612 41.25470032
OS 28.24677358 41.3053911
OS 28.24677358 41.96690108
OS 28.24677358 41.96816854
OS 28.24550612 41.9808406
OS 28.24423866 42.06701518
OS 28.2429712 42.07081502
OS 28.24170374 42.1050339
OS 28.2366339 42.1164385
OS 28.23536644 42.12150834
OS 28.23283152 42.1278431
OS 28.23156406 42.13037802
OS 28.2252293 42.13671532
OS 28.22396184 42.1392477
OS 28.218257 42.14622
OS 28.21128724 42.1519223
OS 28.20558494 42.15889206
OS 28.19861518 42.16459436
OS 28.19291288 42.17156412
OS 28.18594312 42.17726896
OS 28.18024082 42.18423872
OS 28.1777059 42.18550364
OS 28.17327106 42.18993848
OS 28.1720036 42.1924734
OS 28.16756876 42.19690824
OS 28.16503384 42.1981757
OS 28.16059646 42.20261308
OS 28.159329 42.20514546
OS 28.15616162 42.20831538
OS 28.1536267 42.20958284
OS 28.14919186 42.21401768
OS 28.1479244 42.2165526
OS 28.14348956 42.22098744
OS 28.14095464 42.2222549
OS 28.1365198 42.22668974
OS 28.13525234 42.22922466
OS 28.13081496 42.23366204
OS 28.12828004 42.2349295
OS 28.12384774 42.23936434
OS 28.12258028 42.24189926
OS 28.1194129 42.24506664
OS 28.11687798 42.24633156
OS 28.11244314 42.2507664
OS 28.11117568 42.25330132
OS 28.1067383 42.2577387
OS 28.10420338 42.25900362
OS 28.09976854 42.263441
OS 28.09850108 42.26597592
OS 28.09406624 42.27041076
OS 28.09153132 42.27167822
OS 28.08836394 42.2748456
OS 28.08709648 42.27738052
OS 28.0826591 42.28181536
OS 28.08012672 42.28308282
OS 28.0712545 42.28942012
OS 28.0661872 42.29068758
OS 28.0484453 42.29195504
OS 28.04464292 42.2932225
OS 28.02816848 42.29448996
OE
OB 27.6137751 44.24100118 H
OS 27.60997272 44.23973372
OS 27.60363542 44.23593388
OS 27.6017355 44.22896158
OS 27.6011005 42.54160656
OS 27.6017355 42.52576458
OS 27.60046804 42.5219622
OS 27.6017355 42.50295284
OS 27.60046804 42.49915046
OS 27.6017355 42.47760872
OS 27.59920058 42.47127142
OS 27.59856558 42.4630342
OS 27.59920058 42.45606444
OS 27.59793312 42.45226206
OS 27.59666566 42.4332527
OS 27.59032836 42.42438302
OS 27.58652852 42.41804826
OS 27.5846286 42.4161458
OS 27.58209368 42.41487834
OS 27.57639138 42.40917604
OS 27.57512392 42.40664112
OS 27.57322146 42.4047412
OS 27.57068654 42.40347374
OS 27.56498424 42.39777144
OS 27.56371678 42.39523652
OS 27.5605494 42.3920666
OS 27.55801448 42.39080168
OS 27.55231218 42.38509684
OS 27.55104472 42.38256192
OS 27.54787734 42.37939454
OS 27.54534242 42.37812708
OS 27.54090504 42.37369224
OS 27.53963758 42.37115732
OS 27.5364702 42.36798994
OS 27.53393528 42.36672248
OS 27.52823298 42.36102018
OS 27.52696806 42.35848526
OS 27.52380068 42.35531788
OS 27.52126576 42.35405042
OS 27.51556092 42.34834812
OS 27.514296 42.3458132
OS 27.51112608 42.34264582
OS 27.50478878 42.33884344
OS 27.49845402 42.33250614
OS 27.4895818 42.32997122
OS 27.4832445 42.32616884
OS 27.4781772 42.32110154
OS 27.47564228 42.31983408
OS 27.46867252 42.31413178
OS 27.46297022 42.30715948
OS 27.45600046 42.30145972
OS 27.454733 42.2989248
OS 27.4490307 42.2932225
OS 27.44649578 42.29195504
OS 27.4433284 42.28878766
OS 27.44206094 42.28625274
OS 27.43762356 42.28181536
OS 27.43509118 42.2805479
OS 27.43192126 42.27738052
OS 27.4306538 42.2748456
OS 27.4249515 42.2691433
OS 27.42241658 42.26787584
OS 27.4192492 42.26470846
OS 27.41798174 42.26217354
OS 27.4135469 42.2577387
OS 27.41101198 42.25647124
OS 27.40784206 42.25330132
OS 27.40657714 42.2507664
OS 27.40087484 42.24506664
OS 27.39833992 42.24379918
OS 27.39517254 42.2406318
OS 27.39390508 42.23809688
OS 27.38947024 42.23366204
OS 27.38693532 42.23239458
OS 27.3837654 42.22922466
OS 27.38249794 42.22668974
OS 27.37679564 42.22098744
OS 27.37426072 42.21971998
OS 27.37109334 42.2165526
OS 27.36982588 42.21401768
OS 27.36539104 42.20958284
OS 27.36285612 42.20831538
OS 27.35842128 42.203878
OS 27.35715382 42.20134562
OS 27.35271644 42.19690824
OS 27.35018152 42.19564078
OS 27.34701668 42.1924734
OS 27.34574922 42.18993848
OS 27.34004692 42.18423872
OS 27.337512 42.18297126
OS 27.33434462 42.17980388
OS 27.33307716 42.17726896
OS 27.32737232 42.17156412
OS 27.32483994 42.17029666
OS 27.32167002 42.16712928
OS 27.32040256 42.16459436
OS 27.31596772 42.16015952
OS 27.3134328 42.15889206
OS 27.31026542 42.15572468
OS 27.30899796 42.15318976
OS 27.30456058 42.14875238
OS 27.3020282 42.14748746
OS 27.29759082 42.14305008
OS 27.29632336 42.14051516
OS 27.29188852 42.13608032
OS 27.2893536 42.13481286
OS 27.28618876 42.13164548
OS 27.2849213 42.12911056
OS 27.279219 42.1234108
OS 27.27668408 42.12214334
OS 27.27351416 42.11897342
OS 27.2722467 42.1164385
OS 27.2665444 42.1107362
OS 27.26400948 42.10946874
OS 27.26210956 42.10756882
OS 27.2608421 42.1050339
OS 27.2551398 42.0993316
OS 27.25260488 42.09806414
OS 27.24817004 42.09362676
OS 27.24690258 42.09109438
OS 27.24373266 42.08792446
OS 27.24119774 42.086657
OS 27.2367629 42.08222216
OS 27.23549544 42.07968724
OS 27.2310606 42.0752524
OS 27.22852568 42.07398494
OS 27.22536084 42.07081502
OS 27.22409338 42.06828264
OS 27.21838854 42.06258034
OS 27.21585362 42.06131288
OS 27.21268624 42.0581455
OS 27.21141878 42.05561058
OS 27.20571648 42.04990828
OS 27.20318156 42.04864082
OS 27.20128164 42.0467409
OS 27.20001418 42.04420598
OS 27.19430934 42.03850114
OS 27.19177696 42.03723368
OS 27.18733958 42.03279884
OS 27.18607212 42.03026392
OS 27.18290474 42.02709654
OS 27.18036982 42.02582908
OS 27.17593498 42.02139424
OS 27.17466752 42.01885932
OS 27.17023268 42.01442448
OS 27.16769776 42.01315702
OS 27.16453038 42.0099871
OS 27.16326292 42.00745218
OS 27.15756062 42.00175242
OS 27.1550257 42.00048496
OS 27.15185832 41.99731758
OS 27.15059086 41.99478266
OS 27.14615602 41.99034782
OS 27.1436211 41.98908036
OS 27.13918372 41.98464298
OS 27.13791626 41.98210806
OS 27.13348142 41.97767322
OS 27.1309465 41.97640576
OS 27.12777912 41.97323838
OS 27.12651166 41.97070346
OS 27.12080936 41.96500116
OS 27.11827444 41.9637337
OS 27.11637198 41.96183124
OS 27.11510706 41.95929632
OS 27.10940222 41.95359402
OS 27.10686984 41.95232656
OS 27.10370246 41.94915918
OS 27.102435 41.94662426
OS 27.0967327 41.9409245
OS 27.09419778 41.93965704
OS 27.0910304 41.93648712
OS 27.08976294 41.93395474
OS 27.0840581 41.9282499
OS 27.08152572 41.92698244
OS 27.07962326 41.92508252
OS 27.0783558 41.9225476
OS 27.0726535 41.9168453
OS 27.07011858 41.91557784
OS 27.0669512 41.91241046
OS 27.06568374 41.90987554
OS 27.05998144 41.9041707
OS 27.05744652 41.90290578
OS 27.0542766 41.89973586
OS 27.05300914 41.89720094
OS 27.04730938 41.89149864
OS 27.04477446 41.89023118
OS 27.04287454 41.88833126
OS 27.04160708 41.88579634
OS 27.03907216 41.88326396
OS 27.0378047 41.88072904
OS 27.03273486 41.8756592
OS 27.0314674 41.87312428
OS 27.02893248 41.86678952
OS 27.02766502 41.86171968
OS 27.02259772 41.85031254
OS 27.02133026 41.83764048
OS 27.0194278 41.80025676
OS 27.01816034 41.75717074
OS 27.01752788 41.72485432
OS 27.01879534 41.72105194
OS 27.0200628 41.66022402
OS 27.02133026 41.65642164
OS 27.02259772 41.63107752
OS 27.02766502 41.61967292
OS 27.02893248 41.61460308
OS 27.03526978 41.60319848
OS 27.04033962 41.59812864
OS 27.04160708 41.59559372
OS 27.04604192 41.58989142
OS 27.0485743 41.58862396
OS 27.05554406 41.5816542
OS 27.05617906 41.57975428
OS 27.05871398 41.57848682
OS 27.06378128 41.57341698
OS 27.0663162 41.57214952
OS 27.06885112 41.5696146
OS 27.07392096 41.56834968
OS 27.07645588 41.57088206
OS 27.0789908 41.57214952
OS 27.08279064 41.5759519
OS 27.08532556 41.57721936
OS 27.08976294 41.5816542
OS 27.0910304 41.58418912
OS 27.09546524 41.58862396
OS 27.09800016 41.58989142
OS 27.102435 41.59432626
OS 27.10370246 41.59686118
OS 27.10813476 41.60129602
OS 27.11066968 41.60256348
OS 27.11510706 41.60699832
OS 27.11637198 41.60953324
OS 27.1195419 41.61270316
OS 27.12207682 41.61397062
OS 27.12651166 41.61840546
OS 27.12777912 41.62094038
OS 27.13221396 41.62537522
OS 27.13474888 41.62664268
OS 27.13918372 41.63107752
OS 27.14045118 41.63361244
OS 27.14488856 41.63804728
OS 27.14742348 41.63931474
OS 27.15059086 41.64248466
OS 27.15185832 41.64501958
OS 27.15629316 41.64945188
OS 27.15882808 41.65071934
OS 27.16326292 41.65515418
OS 27.16453038 41.6576891
OS 27.16896522 41.66212394
OS 27.17150014 41.6633914
OS 27.17593498 41.66782878
OS 27.17720244 41.67036116
OS 27.18036982 41.67353108
OS 27.18290474 41.67479854
OS 27.1898745 41.68050084
OS 27.19304442 41.68366822
OS 27.19937918 41.68620314
OS 27.2076164 41.68937306
OS 27.2145887 41.69634282
OS 27.21712108 41.69761028
OS 27.22409338 41.70331258
OS 27.22536084 41.70584496
OS 27.23232806 41.71281472
OS 27.23486298 41.71408218
OS 27.23803036 41.71851702
OS 27.24373266 41.72422186
OS 27.24626758 41.72548932
OS 27.24817004 41.72738924
OS 27.24943496 41.72992416
OS 27.2551398 41.73562646
OS 27.25767472 41.73689392
OS 27.25957464 41.73879384
OS 27.2608421 41.74132876
OS 27.26781186 41.74829852
OS 27.27034678 41.74956598
OS 27.2722467 41.75146844
OS 27.27351416 41.75400336
OS 27.279219 41.75970566
OS 27.28175138 41.76097312
OS 27.28365384 41.76287304
OS 27.2849213 41.76540542
OS 27.29188852 41.77237518
OS 27.29442344 41.77364264
OS 27.29759082 41.77808002
OS 27.30456058 41.78504978
OS 27.30646304 41.78568224
OS 27.3077305 41.78821716
OS 27.31596772 41.79645438
OS 27.31850264 41.79772184
OS 27.32040256 41.7996243
OS 27.32167002 41.80215922
OS 27.32863978 41.80912898
OS 27.3311747 41.81039644
OS 27.33307716 41.81229636
OS 27.33434462 41.81483128
OS 27.34131438 41.82180104
OS 27.3438493 41.8230685
OS 27.35018152 41.83067072
OS 27.3539839 41.8344731
OS 27.35651882 41.83574056
OS 27.36285612 41.84334278
OS 27.36539104 41.8458777
OS 27.36729096 41.8465127
OS 27.36855842 41.84904508
OS 27.37679564 41.85728484
OS 27.37933056 41.85854976
OS 27.38123302 41.86045222
OS 27.38249794 41.86298714
OS 27.38947024 41.8699569
OS 27.39200516 41.87122436
OS 27.39390508 41.87312428
OS 27.39517254 41.8756592
OS 27.4021423 41.88262896
OS 27.40467722 41.88389642
OS 27.40784206 41.88833126
OS 27.41481436 41.89530102
OS 27.41734674 41.89656848
OS 27.42051666 41.90100332
OS 27.42621896 41.90670562
OS 27.42811888 41.90734062
OS 27.42938634 41.90987554
OS 27.43762356 41.91811276
OS 27.44015848 41.91938022
OS 27.44206094 41.92128014
OS 27.4433284 41.92381506
OS 27.45029816 41.93078482
OS 27.45283308 41.93205228
OS 27.454733 41.93395474
OS 27.45600046 41.93648712
OS 27.46297022 41.94345942
OS 27.46550514 41.94472688
OS 27.46867252 41.94915918
OS 27.47437482 41.95486148
OS 27.47690974 41.95612894
OS 27.47880966 41.9580314
OS 27.48007712 41.96056378
OS 27.48704688 41.96753608
OS 27.4895818 41.96880354
OS 27.4959191 41.97640576
OS 27.49845402 41.97894068
OS 27.50098894 41.98020814
OS 27.50288886 41.98210806
OS 27.50415632 41.98464298
OS 27.51112608 41.99161274
OS 27.513661 41.9928802
OS 27.51556092 41.99478266
OS 27.51682838 41.99731758
OS 27.52380068 42.00428734
OS 27.52633306 42.00555226
OS 27.52950044 42.0099871
OS 27.53520274 42.0156894
OS 27.53773766 42.01695686
OS 27.53963758 42.01885932
OS 27.54090504 42.02139424
OS 27.54787734 42.028364
OS 27.55040972 42.02963146
OS 27.55357964 42.0340663
OS 27.55928194 42.0397686
OS 27.56181686 42.04103606
OS 27.56371678 42.04293852
OS 27.56498424 42.04547344
OS 27.57068654 42.05117574
OS 27.57322146 42.0524432
OS 27.57639138 42.05561058
OS 27.57765884 42.0581455
OS 27.5846286 42.06511526
OS 27.58652852 42.06574772
OS 27.58779344 42.06828264
OS 27.59603066 42.07651986
OS 27.59856558 42.07778732
OS 27.60046804 42.07968724
OS 27.6017355 42.08222216
OS 27.6074378 42.08792446
OS 27.60997272 42.08919192
OS 27.61187264 42.09109438
OS 27.6131401 42.09362676
OS 27.62010986 42.10059906
OS 27.62264478 42.10186652
OS 27.62454724 42.10376644
OS 27.6258147 42.10630136
OS 27.631517 42.11200366
OS 27.63405192 42.11327112
OS 27.6372193 42.1164385
OS 27.63848676 42.11897342
OS 27.64545652 42.12594318
OS 27.6479889 42.1272081
OS 27.64988882 42.12911056
OS 27.65115628 42.13164548
OS 27.65812858 42.13861524
OS 27.6600285 42.1392477
OS 27.66129596 42.14178262
OS 27.66826572 42.14875238
OS 27.67080064 42.15001984
OS 27.67270056 42.1519223
OS 27.67396802 42.15445722
OS 27.68094032 42.16142698
OS 27.6834727 42.16269444
OS 27.68537516 42.16459436
OS 27.68664262 42.16712928
OS 27.69361238 42.17409904
OS 27.6961473 42.1753665
OS 27.69804722 42.17726896
OS 27.69931468 42.17980388
OS 27.70501698 42.18550364
OS 27.70754936 42.1867711
OS 27.70945182 42.18867102
OS 27.71071928 42.19120594
OS 27.71768904 42.1981757
OS 27.72022396 42.19944316
OS 27.72212388 42.20134562
OS 27.72339134 42.203878
OS 27.7303611 42.2108503
OS 27.73289602 42.21211776
OS 27.73606594 42.2165526
OS 27.74176824 42.2222549
OS 27.74430316 42.22352236
OS 27.74620308 42.22542228
OS 27.74747054 42.2279572
OS 27.7544403 42.2349295
OS 27.75697522 42.23619442
OS 27.75887514 42.23809688
OS 27.7601426 42.2406318
OS 27.76584744 42.24633156
OS 27.76837982 42.24759902
OS 27.77027974 42.24949894
OS 27.7715472 42.25203386
OS 27.77851696 42.25900362
OS 27.78105188 42.26027108
OS 27.7829518 42.26217354
OS 27.78421926 42.26470846
OS 27.79119156 42.27167822
OS 27.79372394 42.27294568
OS 27.80006124 42.2805479
OS 27.80259616 42.28308282
OS 27.80513108 42.28435028
OS 27.807031 42.28625274
OS 27.80829846 42.28878766
OS 27.81526822 42.29575742
OS 27.81780314 42.29702488
OS 27.8197056 42.2989248
OS 27.82097306 42.30145972
OS 27.82667536 42.30842694
OS 27.8298402 42.31159686
OS 27.83237512 42.31793162
OS 27.83554504 42.32616884
OS 27.84061234 42.3337736
OS 27.84378226 42.34074336
OS 27.84631718 42.34708066
OS 27.84948456 42.35531788
OS 27.85265194 42.36608748
OS 27.8545544 42.40347374
OS 27.85582186 42.43768754
OS 27.85645432 42.44845968
OS 27.85645432 42.44972714
OS 27.85582186 43.99261712
OS 27.85645432 44.01099402
OS 27.85518686 44.0147964
OS 27.8539194 44.02366862
OS 27.85201948 44.06358472
OS 27.84631718 44.0730894
OS 27.84504972 44.07562432
OS 27.84061234 44.08132662
OS 27.83807742 44.08259408
OS 27.83237512 44.08829892
OS 27.83110766 44.0908313
OS 27.82920774 44.09273376
OS 27.82667536 44.09400122
OS 27.81843814 44.10223844
OS 27.81717068 44.10477082
OS 27.81273584 44.1079382
OS 27.807031 44.11364304
OS 27.80576354 44.11617542
OS 27.80386362 44.11807788
OS 27.8013287 44.11934534
OS 27.79435894 44.1263151
OS 27.79309148 44.12885002
OS 27.78865664 44.1320174
OS 27.7829518 44.1377197
OS 27.78168688 44.14025462
OS 27.77978442 44.14215708
OS 27.7772495 44.14342454
OS 27.77027974 44.1503943
OS 27.76901228 44.15292922
OS 27.76141006 44.15926398
OS 27.75761022 44.16306636
OS 27.75634276 44.16559874
OS 27.748738 44.17193604
OS 27.74620308 44.17447096
OS 27.74493562 44.17700588
OS 27.7430357 44.1789058
OS 27.74050078 44.18017326
OS 27.73353102 44.18714302
OS 27.73226356 44.18967794
OS 27.72782618 44.19284532
OS 27.72212388 44.19855016
OS 27.72085642 44.20108508
OS 27.7189565 44.202985
OS 27.71642158 44.20425246
OS 27.70945182 44.21122222
OS 27.70818436 44.21375714
OS 27.70628444 44.21565706
OS 27.70374952 44.21692452
OS 27.69677976 44.22262936
OS 27.69487984 44.22452674
OS 27.69234492 44.2257942
OS 27.68600762 44.22832912
OS 27.67396802 44.23276396
OS 27.66699826 44.23593388
OS 27.65876104 44.2378338
OS 27.65242374 44.23910126
OS 27.6372193 44.24036872
OS 27.6137751 44.24100118
OE
OB 29.00142536 42.29448996 H
OS 28.41215044 42.2932225
OS 28.4064456 42.28878766
OS 28.40517814 42.28371782
OS 28.4064456 41.15585622
OS 28.40961552 41.1526863
OS 28.41468282 41.15141884
OS 28.58386206 41.15205384
OS 28.6009715 41.15141884
OS 28.60477388 41.1526863
OS 28.6174434 41.15395376
OS 28.65229474 41.15585622
OS 28.65673212 41.15775614
OS 28.6662368 41.16725828
OS 28.66750172 41.17232812
OS 28.66940164 41.21098184
OS 28.67193656 41.23125612
OS 28.67130156 41.2521654
OS 28.67256902 41.25596778
OS 28.67130156 41.25977016
OS 28.67193656 41.28448182
OS 28.6706691 41.37065386
OS 28.66940164 41.38713084
OS 28.66813418 41.40867258
OS 28.66686672 41.42387956
OS 28.6656018 41.4289494
OS 28.66306688 41.4352867
OS 28.6598995 41.44605884
OS 28.66116696 41.4587309
OS 28.67130156 41.48027264
OS 28.67320402 41.49738208
OS 28.6763714 41.50181692
OS 28.68334116 41.50371684
OS 28.81323676 41.50308438
OS 28.82907874 41.50371684
OS 28.83288112 41.50245192
OS 28.85442286 41.50371684
OS 28.86075762 41.50118446
OS 28.89687642 41.499282
OS 28.90448118 41.49421216
OS 28.90764602 41.49104478
OS 28.91018094 41.48977732
OS 28.91335086 41.48660994
OS 28.91588324 41.47773772
OS 28.92095308 41.46886804
OS 28.92729038 41.46253328
OS 28.92855784 41.45999836
OS 28.93426014 41.4530286
OS 28.93742752 41.44985868
OS 28.93996244 41.44352392
OS 28.9412299 41.43845408
OS 28.95010212 41.42451456
OS 28.95453696 41.41247496
OS 28.95770688 41.40803758
OS 28.96277418 41.40297028
OS 28.96404164 41.4004379
OS 28.96974394 41.3934656
OS 28.97417878 41.38903076
OS 28.97988108 41.37318878
OS 28.98304846 41.3700214
OS 28.98431592 41.36748648
OS 28.9881183 41.3586168
OS 28.99128822 41.35037704
OS 28.99952544 41.34214236
OS 29.00332782 41.3358076
OS 29.00966258 41.3294703
OS 29.01346496 41.32059808
OS 29.01473242 41.31552824
OS 29.02106972 41.30665856
OS 29.02233718 41.30412364
OS 29.0248721 41.29778634
OS 29.02803694 41.28954912
OS 29.03310678 41.2819469
OS 29.03627416 41.27497714
OS 29.03944154 41.26673992
OS 29.04261146 41.26230508
OS 29.04894622 41.25596778
OS 29.0527486 41.24963048
OS 29.0590859 41.24329572
OS 29.06352074 41.23125612
OS 29.06985804 41.22111898
OS 29.07302542 41.21288176
OS 29.07936272 41.20147716
OS 29.08443256 41.19640732
OS 29.08570002 41.1938724
OS 29.09139978 41.18690264
OS 29.09456716 41.18373272
OS 29.09583462 41.18120034
OS 29.09836954 41.17486304
OS 29.099637 41.1697932
OS 29.10407184 41.16409344
OS 29.10660676 41.16282598
OS 29.10914168 41.16029106
OS 29.1116766 41.1590236
OS 29.11421152 41.15648868
OS 29.12308374 41.15522122
OS 29.16046492 41.1533213
OS 29.16806968 41.15205384
OS 29.18644658 41.15141884
OS 29.19024896 41.1526863
OS 29.19531626 41.15141884
OS 29.38540732 41.1526863
OS 29.3873047 41.15458876
OS 29.38857216 41.15965606
OS 29.3873047 41.1697932
OS 29.38096994 41.17866542
OS 29.37843756 41.18500018
OS 29.37526764 41.1932374
OS 29.37336772 41.19513986
OS 29.37210026 41.19767478
OS 29.36703042 41.20274462
OS 29.36576296 41.205277
OS 29.36006066 41.2122493
OS 29.35562582 41.21668414
OS 29.35118844 41.2287212
OS 29.34802106 41.23315604
OS 29.34421868 41.23695842
OS 29.34295122 41.23949334
OS 29.33724892 41.24773056
OS 29.335349 41.24836302
OS 29.334714 41.25026548
OS 29.33281408 41.25089794
OS 29.33154662 41.25343286
OS 29.3290117 41.25977016
OS 29.32584432 41.26800738
OS 29.3239444 41.2699073
OS 29.32267694 41.27244222
OS 29.32014202 41.27497714
OS 29.31443972 41.29081658
OS 29.30746996 41.29778634
OS 29.3062025 41.30032126
OS 29.29733028 41.3117284
OS 29.29479536 41.31426332
OS 29.29226298 41.32059808
OS 29.29099552 41.32566792
OS 29.2821233 41.33960744
OS 29.27768846 41.3516445
OS 29.27451854 41.35608188
OS 29.27198362 41.35734934
OS 29.2707187 41.35988172
OS 29.26818378 41.36241664
OS 29.26438394 41.36875394
OS 29.25804664 41.37509124
OS 29.2536118 41.38713084
OS 29.2472745 41.39726798
OS 29.24410712 41.4055052
OS 29.2415722 41.41183996
OS 29.2358699 41.41880972
OS 29.23269998 41.42197964
OS 29.2288976 41.4283144
OS 29.22256284 41.4346517
OS 29.22002792 41.440989
OS 29.216858 41.44922622
OS 29.21369062 41.45366106
OS 29.20862078 41.46126582
OS 29.20672086 41.46823304
OS 29.20418848 41.47457034
OS 29.19848618 41.48534248
OS 29.19595126 41.49421216
OS 29.19721872 41.51955882
OS 29.20355348 41.5284285
OS 29.2060884 41.53096342
OS 29.20988824 41.53729818
OS 29.21305816 41.5404681
OS 29.21495808 41.54110056
OS 29.21559054 41.54173556
OS 29.21876046 41.54490294
OS 29.22002792 41.54743786
OS 29.22573022 41.55314016
OS 29.22826514 41.55440762
OS 29.23143252 41.55757754
OS 29.23269998 41.56010992
OS 29.23840228 41.56581476
OS 29.2409372 41.56708222
OS 29.24283966 41.56898214
OS 29.24410712 41.57151706
OS 29.24980942 41.57721936
OS 29.25234434 41.57848682
OS 29.25551172 41.5816542
OS 29.25677918 41.58418912
OS 29.26248148 41.58989142
OS 29.2650164 41.59115888
OS 29.26691632 41.5930588
OS 29.26818378 41.59559372
OS 29.27388608 41.60129602
OS 29.276421 41.60256348
OS 29.27958838 41.60573086
OS 29.28085584 41.60826578
OS 29.28655814 41.61397062
OS 29.28909306 41.61523554
OS 29.29226298 41.61840546
OS 29.2935279 41.62094038
OS 29.29923274 41.62664268
OS 29.30176766 41.62791014
OS 29.30366758 41.62981006
OS 29.30493504 41.63234498
OS 29.31063734 41.63804728
OS 29.31317226 41.63931474
OS 29.31633964 41.64248466
OS 29.3176071 41.64501958
OS 29.32331194 41.65071934
OS 29.32584432 41.6519868
OS 29.3290117 41.65515418
OS 29.33027916 41.6576891
OS 29.334714 41.66212394
OS 29.33724892 41.6633914
OS 29.34168376 41.66782878
OS 29.34295122 41.67036116
OS 29.34865352 41.67733346
OS 29.35055598 41.67923338
OS 29.3530909 41.68557068
OS 29.35435836 41.69064052
OS 29.35942566 41.70204512
OS 29.36069312 41.70711242
OS 29.36259558 41.73689392
OS 29.3644955 41.77427764
OS 29.3651305 41.8230685
OS 29.3644955 41.8237035
OS 29.36576296 41.8275008
OS 29.3651305 41.98654544
OS 29.36576296 41.99605012
OS 29.3644955 41.9998525
OS 29.36322804 42.07334994
OS 29.36196058 42.07715232
OS 29.36006066 42.10693382
OS 29.35435836 42.12024088
OS 29.35118844 42.12847556
OS 29.3467536 42.13544786
OS 29.34295122 42.1392477
OS 29.34168376 42.14178262
OS 29.334714 42.14875238
OS 29.33217908 42.15001984
OS 29.33027916 42.1519223
OS 29.3290117 42.15445722
OS 29.32204448 42.16142698
OS 29.31950956 42.16269444
OS 29.3176071 42.16459436
OS 29.31633964 42.16712928
OS 29.29669782 42.1867711
OS 29.29479536 42.18740356
OS 29.2935279 42.18993848
OS 29.28529068 42.1981757
OS 29.28275576 42.19944316
OS 29.27958838 42.203878
OS 29.27388608 42.20958284
OS 29.27135116 42.2108503
OS 29.26945124 42.21275022
OS 29.26818378 42.21528514
OS 29.26121402 42.2222549
OS 29.2586791 42.22352236
OS 29.25677918 42.22542228
OS 29.25551172 42.2279572
OS 29.23713482 42.24633156
OS 29.23460244 42.24759902
OS 29.23269998 42.24949894
OS 29.23143252 42.25203386
OS 29.22446276 42.25900362
OS 29.22192784 42.26027108
OS 29.21559054 42.26787584
OS 29.21305816 42.27041076
OS 29.21052324 42.27167822
OS 29.20418848 42.27801552
OS 29.20165356 42.27928298
OS 29.19278134 42.28308282
OS 29.18454412 42.28625274
OS 29.17820936 42.28878766
OS 29.1706046 42.29005512
OS 29.14272556 42.29132004
OS 29.1053393 42.2932225
OS 29.00142536 42.29448996
OE
OB 25.69387292 42.2932225 H
OS 25.68373324 42.29195504
OS 25.68183332 42.29005512
OS 25.6792984 42.28371782
OS 25.68120086 42.1981757
OS 25.68246832 42.17156412
OS 25.68373324 42.15001984
OS 25.6850007 42.1398827
OS 25.68626816 42.13481286
OS 25.68753562 42.12847556
OS 25.68880308 42.12087588
OS 25.69070554 42.10376644
OS 25.691973 42.09489422
OS 25.69324046 42.0746174
OS 25.69640784 42.05624558
OS 25.69830776 42.04927328
OS 25.7033776 42.02899646
OS 25.70464506 42.0163244
OS 25.70591252 42.00238488
OS 25.70844744 41.99605012
OS 25.71224982 41.98210806
OS 25.71351728 41.97704076
OS 25.71604966 41.96183124
OS 25.71795212 41.9459918
OS 25.71921958 41.93965704
OS 25.72048704 41.9345872
OS 25.72492188 41.92001268
OS 25.72618934 41.91494284
OS 25.72872172 41.89720094
OS 25.73062164 41.88262896
OS 25.7318891 41.8762942
OS 25.73569148 41.86615452
OS 25.73759394 41.85918476
OS 25.74012632 41.84904508
OS 25.74139378 41.83637302
OS 25.74329624 41.8281358
OS 25.74773108 41.8173662
OS 25.75153346 41.80849398
OS 25.75280092 41.7996243
OS 25.75406838 41.79455446
OS 25.75723576 41.78631724
OS 25.76293806 41.77301018
OS 25.76547298 41.7641405
OS 25.76674044 41.75527082
OS 25.7743452 41.73879384
OS 25.77688012 41.72992416
OS 25.77941504 41.71851702
OS 25.7857498 41.70458004
OS 25.78828218 41.69570782
OS 25.78954964 41.69064052
OS 25.7914521 41.68240076
OS 25.79778686 41.66846124
OS 25.79968932 41.66275894
OS 25.80222424 41.65261926
OS 25.8034917 41.64501958
OS 25.80982646 41.6348799
OS 25.81299638 41.62664268
OS 25.81933114 41.61270316
OS 25.82503598 41.5993961
OS 25.8269359 41.58862396
OS 25.83010328 41.58038674
OS 25.8389755 41.56137738
OS 25.84911264 41.5398331
OS 25.85037756 41.53096342
OS 25.85228002 41.5239962
OS 25.85798232 41.51322406
OS 25.8617847 41.50435184
OS 25.92388008 41.37889362
OS 25.92768246 41.37255632
OS 25.93401976 41.36621902
OS 25.93528722 41.3636841
OS 25.94098952 41.35671434
OS 25.94288944 41.35481442
OS 25.9441569 41.3522795
OS 25.94922674 41.3408749
OS 25.95429658 41.33200522
OS 25.96063134 41.31806316
OS 25.96696864 41.30665856
OS 25.97203594 41.29525142
OS 25.97710578 41.28638174
OS 25.98344054 41.28004698
OS 25.984708 41.27751206
OS 25.99041284 41.2705423
OS 25.99358022 41.26737492
OS 25.99611514 41.26103762
OS 25.9973826 41.25596778
OS 26.00625228 41.24202826
OS 26.00751974 41.23695842
OS 26.01385704 41.22555382
OS 26.01892688 41.22048652
OS 26.02019434 41.2179516
OS 26.03539878 41.20274462
OS 26.03666624 41.2002097
OS 26.04046862 41.19640732
OS 26.04173608 41.1938724
OS 26.044271 41.1875351
OS 26.05060576 41.1761305
OS 26.05694306 41.1697932
OS 26.05821052 41.16725828
OS 26.0620129 41.16345844
OS 26.06328036 41.16092352
OS 26.06708274 41.15712368
OS 26.07151758 41.14508408
OS 26.07785488 41.13747932
OS 26.08102226 41.13304448
OS 26.08355718 41.13050956
OS 26.08418964 41.1286071
OS 26.08672456 41.12733964
OS 26.09495924 41.11910242
OS 26.0962267 41.1165675
OS 26.10129654 41.1115002
OS 26.102564 41.10896528
OS 26.10636638 41.1000956
OS 26.10763384 41.09629322
OS 26.11333614 41.08932346
OS 26.11650352 41.08615608
OS 26.11777098 41.08362116
OS 26.14565256 41.05573958
OS 26.14692002 41.05320466
OS 26.15071986 41.04940228
OS 26.15198732 41.0468699
OS 26.15705716 41.03419784
OS 26.16339192 41.02786054
OS 26.16465938 41.02532562
OS 26.17036422 41.01835586
OS 26.17733398 41.01265356
OS 26.18303628 41.0056838
OS 26.19000604 40.9999815
OS 26.1912735 40.99744658
OS 26.19570834 40.9930092
OS 26.19824326 40.99174428
OS 26.20394556 40.98603944
OS 26.20521302 40.98350706
OS 26.20711548 40.98160714
OS 26.20964786 40.98033968
OS 26.3737598 40.81622774
OS 26.37502726 40.81369282
OS 26.37692718 40.8117929
OS 26.3794621 40.81052544
OS 26.3851644 40.80482314
OS 26.38643186 40.80229076
OS 26.3908667 40.79785338
OS 26.39340162 40.79658592
OS 26.396569 40.79341854
OS 26.39783646 40.79088362
OS 26.40353876 40.78518132
OS 26.40607368 40.78391386
OS 26.40924106 40.78074648
OS 26.41050852 40.77821156
OS 26.4149459 40.77377418
OS 26.41747828 40.77250672
OS 26.42191566 40.76807188
OS 26.42318312 40.76553696
OS 26.4263505 40.76236958
OS 26.42888542 40.76110212
OS 26.43142034 40.7585672
OS 26.43395526 40.75729974
OS 26.43902256 40.7522299
OS 26.44535986 40.74969498
OS 26.45042716 40.74843006
OS 26.45296208 40.74589514
OS 26.455497 40.74463022
OS 26.45803192 40.7420953
OS 26.4605643 40.74082784
OS 26.47704128 40.7243534
OS 26.4795762 40.72308594
OS 26.48591096 40.71674864
OS 26.48844588 40.71548118
OS 26.49478318 40.71294626
OS 26.49985302 40.7116788
OS 26.50238794 40.70914388
OS 26.50492032 40.70787642
OS 26.50998762 40.70280912
OS 26.51252254 40.70154166
OS 26.52202722 40.69203698
OS 26.52266222 40.69013452
OS 26.52519714 40.68886706
OS 26.5321669 40.6831673
OS 26.53660174 40.67873246
OS 26.5435715 40.67683
OS 26.5499088 40.67429508
OS 26.55307618 40.6711277
OS 26.5556111 40.66986024
OS 26.56068094 40.6647904
OS 26.56321586 40.66352294
OS 26.56828316 40.65845564
OS 26.57081808 40.65718818
OS 26.57335046 40.65465326
OS 26.57968776 40.65211834
OS 26.58792498 40.64894842
OS 26.59236236 40.64451358
OS 26.59489474 40.64324612
OS 26.61137172 40.62677168
OS 26.61390664 40.62550676
OS 26.6202414 40.61916946
OS 26.62911108 40.61536708
OS 26.63418092 40.61409962
OS 26.6430506 40.60776486
OS 26.6493879 40.60522994
OS 26.65762512 40.60206256
OS 26.66522988 40.59572526
OS 26.6671298 40.5938228
OS 26.66966472 40.59255534
OS 26.67663448 40.58685304
OS 26.6798044 40.58368566
OS 26.68233678 40.5824182
OS 26.69120646 40.57861582
OS 26.70514598 40.57101106
OS 26.71655312 40.5659463
OS 26.72795772 40.559609
OS 26.73682994 40.55580662
OS 26.74823454 40.54946932
OS 26.75330184 40.54440202
OS 26.75583676 40.54313456
OS 26.76280652 40.53742972
OS 26.7672439 40.53299488
OS 26.77548112 40.5298275
OS 26.78181588 40.52729258
OS 26.7913231 40.52159028
OS 26.79765786 40.51905536
OS 26.9028418 40.46709712
OS 26.92185116 40.45822744
OS 26.93325322 40.45695998
OS 26.95986734 40.44428792
OS 26.9788767 40.43541824
OS 26.98394654 40.43415078
OS 26.99725106 40.43098086
OS 27.0257651 40.4176738
OS 27.04223954 40.41007158
OS 27.05300914 40.40816912
OS 27.05807898 40.40690166
OS 27.06504874 40.40373428
OS 27.06758366 40.40246682
OS 27.07645588 40.39866444
OS 27.09419778 40.39486206
OS 27.10813476 40.3885273
OS 27.12080936 40.38472746
OS 27.12841158 40.38346
OS 27.13474888 40.38092508
OS 27.1486884 40.37458778
OS 27.15375824 40.37332032
OS 27.16263046 40.37205286
OS 27.16896522 40.36952048
OS 27.18290474 40.36318318
OS 27.19304442 40.36064826
OS 27.2025491 40.35874834
OS 27.219656 40.35177604
OS 27.22979314 40.34924112
OS 27.24436766 40.3473412
OS 27.2545048 40.34480628
OS 27.2608421 40.34227136
OS 27.27161424 40.33910398
OS 27.2893536 40.33656906
OS 27.3013932 40.33466914
OS 27.31153288 40.33340168
OS 27.31660018 40.33213422
OS 27.32483994 40.3289643
OS 27.33307716 40.32706438
OS 27.33941192 40.32579946
OS 27.34701668 40.324532
OS 27.35715382 40.32326454
OS 27.37362826 40.32072962
OS 27.3786981 40.31946216
OS 27.38693532 40.31629478
OS 27.39517254 40.31439232
OS 27.40150984 40.3131274
OS 27.41544682 40.31185994
OS 27.42938634 40.30932502
OS 27.43445618 40.30805756
OS 27.44079348 40.3067901
OS 27.44776324 40.30488764
OS 27.45790292 40.30235526
OS 27.47057244 40.3010878
OS 27.49275172 40.29918534
OS 27.50415632 40.29791788
OS 27.52063076 40.29538296
OS 27.53330282 40.29284804
OS 27.54470742 40.29158312
OS 27.572589 40.29031566
OS 27.5890609 40.2890482
OS 27.65876104 40.28778074
OS 27.87102884 40.28714574
OS 27.87483122 40.2884132
OS 27.95846834 40.28968066
OS 27.96227072 40.29094812
OS 27.99775452 40.29221558
OS 28.0015569 40.29348304
OS 28.00979158 40.29538296
OS 28.03577324 40.29855288
OS 28.04464292 40.29982034
OS 28.06111736 40.3010878
OS 28.07632434 40.30235526
OS 28.08012672 40.30362018
OS 28.08519402 40.30488764
OS 28.09406624 40.30742256
OS 28.101036 40.30932502
OS 28.1073733 40.31059248
OS 28.12448274 40.3124924
OS 28.1365198 40.31439232
OS 28.1415871 40.31565978
OS 28.14855686 40.31756224
OS 28.15489416 40.32009716
OS 28.16376638 40.32136462
OS 28.16883622 40.32263208
OS 28.18467566 40.324532
OS 28.19227788 40.32579946
OS 28.19861518 40.32706438
OS 28.20875232 40.3295993
OS 28.21952446 40.33276668
OS 28.2245943 40.33403414
OS 28.2423362 40.33656906
OS 28.25690818 40.33846898
OS 28.26324548 40.33973644
OS 28.26958278 40.34227136
OS 28.28415476 40.34670874
OS 28.2892246 40.3479762
OS 28.30506658 40.34987612
OS 28.31013388 40.35114358
OS 28.32027102 40.35494596
OS 28.33104316 40.3593808
OS 28.34878506 40.36318318
OS 28.36272712 40.36952048
OS 28.36906188 40.37205286
OS 28.37793156 40.37332032
OS 28.3830014 40.37458778
OS 28.39694092 40.38092508
OS 28.40327822 40.38346
OS 28.41785274 40.38662484
OS 28.42798734 40.39042722
OS 28.43495964 40.3935946
OS 28.4412944 40.39612952
OS 28.45206654 40.39803198
OS 28.45713638 40.39929944
OS 28.46981098 40.4056342
OS 28.47487828 40.40690166
OS 28.48184804 40.40880412
OS 28.49515256 40.4119715
OS 28.50465724 40.4176738
OS 28.512897 40.42084372
OS 28.51986676 40.4240111
OS 28.53887612 40.43288332
OS 28.55154564 40.43415078
OS 28.56295278 40.44048554
OS 28.57435738 40.44555538
OS 28.58069468 40.44808776
OS 28.59970404 40.45695998
OS 28.60857372 40.45822744
OS 28.61554348 40.46012736
OS 28.62885054 40.46709712
OS 28.63518784 40.46963204
OS 28.69981814 40.50258092
OS 28.70868782 40.50638076
OS 28.72516226 40.51525298
OS 28.73403194 40.51905536
OS 28.747974 40.52665758
OS 28.75684368 40.53045996
OS 28.76825082 40.53679726
OS 28.77458558 40.54313456
OS 28.78092288 40.54693694
OS 28.78599272 40.55200424
OS 28.79485986 40.55580662
OS 28.80119716 40.55834154
OS 28.80880192 40.56341138
OS 28.8176716 40.56721122
OS 28.8240089 40.56974614
OS 28.83097866 40.57544844
OS 28.83288112 40.57734836
OS 28.83541604 40.57861582
OS 28.83794842 40.58115074
OS 28.84048334 40.5824182
OS 28.8468181 40.5887555
OS 28.8594927 40.5938228
OS 28.86202508 40.59509026
OS 28.87216476 40.60142756
OS 28.88420436 40.6058624
OS 28.8943415 40.6121997
OS 28.9013138 40.61536708
OS 28.90954848 40.618537
OS 28.9114484 40.62043692
OS 28.91398332 40.62170438
OS 28.92032062 40.62803914
OS 28.92285554 40.6293066
OS 28.93932998 40.64578104
OS 28.9418649 40.6470485
OS 28.94439982 40.64958342
OS 28.95073458 40.65211834
OS 28.9589718 40.65528572
OS 28.9659441 40.66225548
OS 28.96847648 40.66352294
OS 28.97988108 40.67239516
OS 28.982416 40.67493008
OS 28.9944556 40.67936492
OS 28.99889044 40.6825323
OS 29.00396028 40.6875996
OS 29.0064952 40.68886706
OS 29.02170218 40.70407404
OS 29.0242371 40.7053415
OS 29.0293044 40.71041134
OS 29.0356417 40.71294626
OS 29.04387892 40.71611364
OS 29.04577884 40.7180161
OS 29.04831376 40.71928356
OS 29.05465106 40.72561832
OS 29.05718598 40.72688578
OS 29.0654232 40.73512554
OS 29.06669066 40.73765792
OS 29.0711255 40.74082784
OS 29.07429288 40.74399522
OS 29.07556034 40.7465276
OS 29.07873026 40.74969498
OS 29.08126264 40.75096244
OS 29.08506502 40.75476482
OS 29.0875974 40.75603228
OS 29.09139978 40.75983466
OS 29.1053393 40.7649045
OS 29.1116766 40.77123926
OS 29.11421152 40.77250672
OS 29.12118128 40.77821156
OS 29.12244874 40.78074648
OS 29.12815104 40.78644878
OS 29.13068596 40.78771624
OS 29.13385588 40.79088362
OS 29.13512334 40.79341854
OS 29.14082564 40.79912084
OS 29.14336056 40.8003883
OS 29.14526048 40.80229076
OS 29.1465254 40.80482314
OS 29.15349516 40.8117929
OS 29.15603008 40.81306036
OS 29.15983246 40.8168602
OS 29.16236738 40.81812766
OS 29.1649023 40.82066258
OS 29.1769419 40.82509996
OS 29.18137674 40.82826734
OS 29.18644658 40.83333718
OS 29.1889815 40.83460464
OS 29.19595126 40.8415744
OS 29.19721872 40.84410932
OS 29.20355348 40.85044408
OS 29.20482094 40.852979
OS 29.20735332 40.8593163
OS 29.20862078 40.86438614
OS 29.21432562 40.87135336
OS 29.2231953 40.88022558
OS 29.2295326 40.88275796
OS 29.23776982 40.88592788
OS 29.24220466 40.88909526
OS 29.2472745 40.8941651
OS 29.24980942 40.89543256
OS 29.25677918 40.90240232
OS 29.25804664 40.90493724
OS 29.2656514 40.912542
OS 29.26818378 40.92267914
OS 29.27198362 40.9290139
OS 29.27388608 40.93091382
OS 29.27895592 40.93218128
OS 29.28592568 40.93408374
OS 29.2878256 40.93598366
OS 29.29036052 40.93725112
OS 29.29543036 40.94232096
OS 29.29796528 40.94358842
OS 29.3062025 40.95182564
OS 29.30746996 40.95436056
OS 29.31380726 40.96069532
OS 29.31633964 40.96703262
OS 29.31950956 40.97526984
OS 29.3239444 40.98350706
OS 29.32267694 40.98857436
OS 29.31697464 40.99047682
OS 29.30936988 40.98920936
OS 29.30430004 40.98414206
OS 29.30176766 40.9828746
OS 29.29923274 40.98033968
OS 29.29669782 40.97907222
OS 29.2935279 40.97590484
OS 29.29226298 40.97336992
OS 29.28655814 40.96766762
OS 29.28402322 40.96640016
OS 29.28085584 40.96323024
OS 29.27958838 40.96069532
OS 29.27261862 40.95372556
OS 29.2700837 40.9524581
OS 29.26818378 40.95055818
OS 29.26691632 40.94802326
OS 29.24980942 40.93091382
OS 29.24790696 40.93028136
OS 29.24664204 40.92774644
OS 29.23840228 40.91951176
OS 29.2358699 40.9182443
OS 29.23269998 40.91507438
OS 29.23143252 40.912542
OS 29.22446276 40.9055697
OS 29.22192784 40.90430224
OS 29.22002792 40.90240232
OS 29.21876046 40.8998674
OS 29.19024896 40.87135336
OS 29.18771404 40.8700859
OS 29.18454412 40.86691852
OS 29.18327666 40.86438614
OS 29.17757436 40.8586813
OS 29.17503944 40.85741638
OS 29.17187206 40.85424646
OS 29.1706046 40.85171154
OS 29.1649023 40.84600924
OS 29.16236738 40.84474178
OS 29.15983246 40.84220686
OS 29.15729754 40.8409394
OS 29.1522277 40.8358721
OS 29.14336056 40.83333718
OS 29.13702326 40.8295348
OS 29.13068596 40.8231975
OS 29.12815104 40.82193004
OS 29.1237162 40.81876266
OS 29.12244874 40.81622774
OS 29.07175796 40.76553696
OS 29.0711255 40.76363704
OS 29.06859058 40.76236958
OS 29.0647882 40.7585672
OS 29.06225328 40.75729974
OS 29.05718598 40.7522299
OS 29.05465106 40.75096244
OS 29.04831376 40.74843006
OS 29.04324392 40.7471626
OS 29.03944154 40.74336276
OS 29.03754162 40.74272776
OS 29.03690916 40.74082784
OS 29.03437424 40.73956038
OS 29.03183932 40.73702546
OS 29.0293044 40.735758
OS 29.02360464 40.7300557
OS 29.02233718 40.72752078
OS 29.01916726 40.7243534
OS 29.01663234 40.72308594
OS 29.01156504 40.7180161
OS 29.00903012 40.71674864
OS 29.0064952 40.71421372
OS 29.00142536 40.71294626
OS 28.99318814 40.70977888
OS 28.98621838 40.70280912
OS 28.98368346 40.70154166
OS 28.9767137 40.69583682
OS 28.97354378 40.69266944
OS 28.9710114 40.69140198
OS 28.96214172 40.6875996
OS 28.9532695 40.6825323
OS 28.94693474 40.67619754
OS 28.94439982 40.67493008
OS 28.92792284 40.65845564
OS 28.92539046 40.65718818
OS 28.92285554 40.65465326
OS 28.91651824 40.65211834
OS 28.90828102 40.64894842
OS 28.9013138 40.64197866
OS 28.89877888 40.6407112
OS 28.89180912 40.6350089
OS 28.88990666 40.63310898
OS 28.88737174 40.63184152
OS 28.88483682 40.6293066
OS 28.87279722 40.62487176
OS 28.86836238 40.62170438
OS 28.86456 40.617902
OS 28.86202508 40.61663454
OS 28.8594927 40.61409962
OS 28.85695778 40.6128347
OS 28.85062048 40.6064974
OS 28.84808556 40.60522994
OS 28.83921588 40.60142756
OS 28.81513668 40.59002296
OS 28.806267 40.58495312
OS 28.76698336 40.5659463
OS 28.76064606 40.56214392
OS 28.75557622 40.55707408
OS 28.7530413 40.55580662
OS 28.75050638 40.5532717
OS 28.747974 40.55200424
OS 28.74417162 40.54820186
OS 28.7416367 40.54693694
OS 28.73910178 40.54440202
OS 28.73086456 40.5412321
OS 28.7245298 40.53869718
OS 28.71629258 40.53299488
OS 28.70995528 40.53045996
OS 28.70171806 40.52729258
OS 28.6941133 40.52222274
OS 28.68714354 40.51905536
OS 28.67890632 40.51588544
OS 28.66876918 40.50955068
OS 28.66179942 40.50638076
OS 28.65546466 40.50384838
OS 28.64405752 40.49751362
OS 28.63265292 40.49244378
OS 28.61110864 40.4823041
OS 28.59907158 40.48040418
OS 28.59273428 40.47786926
OS 28.5597854 40.46139482
OS 28.54394596 40.45442506
OS 28.5249366 40.44555538
OS 28.51352946 40.44428792
OS 28.49705502 40.43668316
OS 28.49071772 40.43415078
OS 28.48184804 40.43288332
OS 28.4660086 40.42717848
OS 28.45270154 40.42147618
OS 28.44382932 40.42020872
OS 28.43875948 40.41894126
OS 28.42102012 40.41133904
OS 28.41468282 40.40880412
OS 28.40264576 40.40690166
OS 28.39630846 40.40436674
OS 28.38046648 40.39739698
OS 28.36082466 40.39296214
OS 28.35512236 40.38979476
OS 28.34878506 40.38725984
OS 28.33991538 40.38472746
OS 28.33484554 40.38346
OS 28.32787578 40.38155754
OS 28.32153848 40.37902516
OS 28.31456872 40.3771227
OS 28.31393626 40.37649024
OS 28.30696396 40.37458778
OS 28.3018992 40.37332032
OS 28.28542222 40.37205286
OS 28.28035492 40.3707854
OS 28.26831532 40.36888548
OS 28.26324548 40.36761802
OS 28.25690818 40.3650831
OS 28.24613858 40.36191572
OS 28.24106874 40.36064826
OS 28.23219906 40.3593808
OS 28.22015946 40.35748088
OS 28.2062174 40.35241104
OS 28.19924764 40.35050858
OS 28.1891105 40.3479762
OS 28.17073614 40.34480628
OS 28.1656663 40.34353882
OS 28.159329 40.3410039
OS 28.1542617 40.33973644
OS 28.14665694 40.33846898
OS 28.1365198 40.33720406
OS 28.12891504 40.3359366
OS 28.11751044 40.33466914
OS 28.09216632 40.33086676
OS 28.08519402 40.3289643
OS 28.07632434 40.32769684
OS 28.0712545 40.32643192
OS 28.0484453 40.32516446
OS 28.04464292 40.32389954
OS 28.0021919 40.32199708
OS 27.9895173 40.32072962
OS 27.9781127 40.31946216
OS 27.97050794 40.3181947
OS 27.96417064 40.31692724
OS 27.9540335 40.31565978
OS 27.93882652 40.31439232
OS 27.9185497 40.3131274
OS 27.87419622 40.31185994
OS 27.86342408 40.31122494
OS 27.8596217 40.3124924
OS 27.82794028 40.31122494
OS 27.66509834 40.31185994
OS 27.66066096 40.31122494
OS 27.65686112 40.3124924
OS 27.65305874 40.31122494
OS 27.63278446 40.3124924
OS 27.59729812 40.31375986
OS 27.59349828 40.31502732
OS 27.56815416 40.31629478
OS 27.56435178 40.31756224
OS 27.55547956 40.3188297
OS 27.55040972 40.32009716
OS 27.5301329 40.32136462
OS 27.50922616 40.32326454
OS 27.4838795 40.324532
OS 27.47373982 40.32579946
OS 27.45726792 40.32706438
OS 27.4433284 40.3295993
OS 27.43635864 40.33149922
OS 27.40594468 40.3353016
OS 27.37933056 40.33910398
OS 27.37426072 40.34037144
OS 27.36539104 40.34290636
OS 27.35525136 40.34544128
OS 27.3432143 40.3473412
OS 27.32610486 40.34924112
OS 27.31280034 40.35241104
OS 27.30582804 40.35557842
OS 27.29315598 40.3593808
OS 27.2849213 40.36128072
OS 27.27985146 40.36254818
OS 27.2728817 40.3657181
OS 27.2665444 40.36825302
OS 27.25133742 40.3707854
OS 27.23866282 40.37205286
OS 27.22979314 40.37332032
OS 27.22155846 40.37522278
OS 27.2076164 40.38029262
OS 27.19684426 40.38346
OS 27.18860704 40.38535992
OS 27.1835372 40.38662484
OS 27.17656744 40.38979476
OS 27.16516538 40.39486206
OS 27.15312578 40.39676452
OS 27.1429861 40.4005669
OS 27.12967904 40.4062692
OS 27.12461174 40.40753666
OS 27.11130468 40.41070404
OS 27.09736516 40.41704134
OS 27.08659302 40.42020872
OS 27.07708834 40.42211118
OS 27.07075358 40.4246461
OS 27.05744652 40.4303484
OS 27.04730938 40.43288332
OS 27.03970462 40.43415078
OS 27.01055812 40.44808776
OS 26.99408114 40.45569252
OS 26.985214 40.45695998
OS 26.98014416 40.45822744
OS 26.95606496 40.46963204
OS 26.94972766 40.47216696
OS 26.93325322 40.47977172
OS 26.92818338 40.48103664
OS 26.91868124 40.4829391
OS 26.91234648 40.48547402
OS 26.9028418 40.49117632
OS 26.89460204 40.4943437
OS 26.88826728 40.49687862
OS 26.88066252 40.50194846
OS 26.87432522 40.50448338
OS 26.86038824 40.51081814
OS 26.85848832 40.51271806
OS 26.8559534 40.51398552
OS 26.84454626 40.51905536
OS 26.83314166 40.52539266
OS 26.82173452 40.53045996
OS 26.807795 40.53806472
OS 26.7963904 40.54313456
OS 26.79005564 40.54693694
OS 26.78308334 40.55263924
OS 26.77738104 40.55707408
OS 26.77484612 40.55834154
OS 26.76851136 40.56467884
OS 26.76153906 40.56657622
OS 26.75393684 40.5703786
OS 26.7444347 40.5760809
OS 26.7380974 40.57861582
OS 26.70894836 40.59255534
OS 26.70641344 40.5938228
OS 26.70388106 40.59635772
OS 26.70134614 40.59762518
OS 26.6962763 40.60269502
OS 26.69374138 40.60396248
OS 26.68677416 40.60966478
OS 26.68360424 40.6128347
OS 26.67726948 40.61536708
OS 26.67219964 40.61663454
OS 26.66522988 40.62233938
OS 26.66205996 40.62550676
OS 26.65952758 40.62677168
OS 26.65255528 40.63247398
OS 26.6493879 40.6356439
OS 26.64685298 40.63691136
OS 26.63418092 40.64197866
OS 26.631646 40.64324612
OS 26.62277632 40.64958342
OS 26.61770648 40.65085088
OS 26.60630188 40.65718818
OS 26.59933212 40.66289048
OS 26.59489474 40.66605786
OS 26.58982744 40.6711277
OS 26.58729252 40.67239516
OS 26.57588538 40.677465
OS 26.57335046 40.67873246
OS 26.56638324 40.68443476
OS 26.5619484 40.6875996
OS 26.54674142 40.70280912
OS 26.5442065 40.70407404
OS 26.5378692 40.71041134
OS 26.52899698 40.71294626
OS 26.5201273 40.7180161
OS 26.51505746 40.72308594
OS 26.51252254 40.7243534
OS 26.50555532 40.73132316
OS 26.50428786 40.73385808
OS 26.50238794 40.735758
OS 26.49985302 40.73702546
OS 26.4973181 40.73956038
OS 26.49478318 40.74082784
OS 26.48844588 40.7471626
OS 26.4795762 40.74969498
OS 26.4732389 40.75349736
OS 26.46943652 40.75729974
OS 26.4669016 40.7585672
OS 26.46436668 40.76110212
OS 26.46183176 40.76236958
OS 26.45993184 40.7642695
OS 26.45866438 40.76680442
OS 26.4377551 40.78771624
OS 26.43585518 40.7883487
OS 26.43458772 40.79088362
OS 26.4022713 40.8231975
OS 26.39973638 40.82446496
OS 26.39340162 40.83080226
OS 26.3908667 40.83206972
OS 26.38706686 40.83333718
OS 26.37882964 40.83650456
OS 26.37122488 40.84284186
OS 26.36679004 40.84600924
OS 26.23562698 40.9771723
OS 26.23435952 40.97970722
OS 26.22928968 40.98477452
OS 26.2267573 40.99110928
OS 26.22485484 40.99807904
OS 26.22295492 40.9999815
OS 26.22168746 41.00251642
OS 26.21535016 41.00885118
OS 26.2140827 41.0113861
OS 26.18176882 41.04370252
OS 26.1798689 41.04433752
OS 26.17860144 41.0468699
OS 26.161492 41.0639768
OS 26.15895708 41.06524426
OS 26.15325478 41.07094656
OS 26.15198732 41.07348148
OS 26.1494524 41.0760164
OS 26.14818494 41.07855132
OS 26.1443851 41.0823537
OS 26.14311764 41.08488862
OS 26.14058272 41.09122592
OS 26.13931526 41.09629322
OS 26.13171304 41.10389798
OS 26.13044558 41.10643036
OS 26.12474328 41.11340012
OS 26.12220836 41.11466758
OS 26.1152386 41.12163734
OS 26.11397114 41.12417226
OS 26.1089013 41.1292421
OS 26.10763384 41.13177702
OS 26.10509892 41.13811178
OS 26.10193154 41.14635154
OS 26.09495924 41.1533213
OS 26.09369432 41.15585622
OS 26.07721988 41.17232812
OS 26.07595242 41.17486304
OS 26.07215004 41.17866542
OS 26.07088258 41.18120034
OS 26.0683502 41.1875351
OS 26.06328036 41.19640732
OS 26.05947798 41.2002097
OS 26.05821052 41.20274462
OS 26.0556756 41.205277
OS 26.05440814 41.20781192
OS 26.04807338 41.21414922
OS 26.04680592 41.21668414
OS 26.044271 41.22302144
OS 26.04110108 41.23125612
OS 26.0379337 41.23569096
OS 26.03286386 41.24329572
OS 26.03096394 41.25026548
OS 26.02906148 41.25470032
OS 26.02336172 41.26167008
OS 26.02019434 41.26484
OS 26.01892688 41.26737492
OS 26.01639196 41.2699073
OS 26.0151245 41.27244222
OS 26.01005466 41.27751206
OS 26.00751974 41.28384936
OS 26.00625228 41.28891666
OS 26.00054998 41.29588642
OS 25.9973826 41.2990538
OS 25.99611514 41.30158872
OS 25.99041284 41.30855848
OS 25.98851038 41.31046094
OS 25.98724292 41.31299586
OS 25.984708 41.31552824
OS 25.98344054 41.32059808
OS 25.9618988 41.36241664
OS 25.95809896 41.37128886
OS 25.95302912 41.38016108
OS 25.94795928 41.38522838
OS 25.94669182 41.3877633
OS 25.94098952 41.39473306
OS 25.93908706 41.39663552
OS 25.9378196 41.39917044
OS 25.9327523 41.4105725
OS 25.92768246 41.41944472
OS 25.92134516 41.43338424
OS 25.9150104 41.44479138
OS 25.9086731 41.4587309
OS 25.9036058 41.46760058
OS 25.89600104 41.48407502
OS 25.89473358 41.48660994
OS 25.88839882 41.49674708
OS 25.8858639 41.50308438
OS 25.88269398 41.5113216
OS 25.87572422 41.52462866
OS 25.87445676 41.52969596
OS 25.87128938 41.54427048
OS 25.86431962 41.55757754
OS 25.8617847 41.5639123
OS 25.85037756 41.58798896
OS 25.84911264 41.59686118
OS 25.84784772 41.60193102
OS 25.8446778 41.61016824
OS 25.84277788 41.61206816
OS 25.8389755 41.62094038
OS 25.83644058 41.62727514
OS 25.82630344 41.64881688
OS 25.82503598 41.65388672
OS 25.82313352 41.6633914
OS 25.8205986 41.6697287
OS 25.81362884 41.68683814
OS 25.81236138 41.69570782
OS 25.80792654 41.70774488
OS 25.80475916 41.71471718
OS 25.80222424 41.72105194
OS 25.80095678 41.72612178
OS 25.79778686 41.73942884
OS 25.79525194 41.74576614
OS 25.79208456 41.7527359
OS 25.78954964 41.75907066
OS 25.78828218 41.7641405
OS 25.78701726 41.77301018
OS 25.7806825 41.7869497
OS 25.77814758 41.793287
OS 25.77688012 41.79835684
OS 25.7737102 41.8116639
OS 25.77117528 41.81799866
OS 25.76927536 41.8237035
OS 25.76674044 41.83257064
OS 25.76547298 41.83764048
OS 25.76420552 41.85411492
OS 25.76293806 41.85918476
OS 25.76103814 41.87122436
OS 25.75977068 41.8762942
OS 25.75723576 41.88262896
OS 25.75280092 41.89720094
OS 25.75153346 41.90987554
OS 25.750266 41.91494284
OS 25.74899854 41.9225476
OS 25.74519616 41.93141982
OS 25.74139378 41.94662426
OS 25.74012632 41.95549648
OS 25.73885886 41.97197092
OS 25.73759394 41.97704076
OS 25.73569148 41.98401052
OS 25.7325241 41.99478266
OS 25.72872172 42.0099871
OS 25.72555688 42.03596876
OS 25.72048704 42.05624558
OS 25.71858458 42.07334994
OS 25.71668466 42.0929943
OS 25.7154172 42.1170735
OS 25.71414974 42.12847556
OS 25.71288228 42.1512873
OS 25.71161482 42.16142698
OS 25.71034736 42.16903174
OS 25.7090799 42.17409904
OS 25.70781244 42.18423872
OS 25.70654498 42.20578046
OS 25.70527752 42.2222549
OS 25.7040126 42.24506664
OS 25.70274514 42.28561774
OS 25.70084268 42.29005512
OS 25.69894276 42.29195504
OS 25.69387292 42.2932225
OE
SE
S P 0
OB 32.9083924 44.95700432 I
OS 32.97809254 44.95573686
OS 32.98189492 44.9544694
OS 33.0021692 44.95320194
OS 33.01104142 44.94939956
OS 33.0199111 44.94686718
OS 33.038288 44.94496472
OS 33.04335784 44.94369726
OS 33.04969006 44.94116488
OS 33.06299712 44.93546258
OS 33.07186934 44.93419512
OS 33.07693918 44.93292766
OS 33.0851764 44.92976028
OS 33.08707632 44.92785782
OS 33.09848346 44.92279052
OS 33.10671814 44.9196206
OS 33.1136879 44.91518576
OS 33.12762742 44.90884846
OS 33.13396472 44.90504608
OS 33.13903456 44.89997878
OS 33.14156948 44.89871132
OS 33.15107416 44.89174156
OS 33.15170662 44.8898391
OS 33.15424154 44.88857164
OS 33.1669136 44.88350434
OS 33.16944852 44.88223688
OS 33.17705074 44.87463466
OS 33.17958566 44.8733672
OS 33.1840205 44.87019728
OS 33.18528796 44.8676649
OS 33.18782288 44.86512998
OS 33.18845788 44.86322752
OS 33.1909928 44.86196006
OS 33.20619978 44.84675308
OS 33.2080997 44.84612062
OS 33.20936716 44.8435857
OS 33.21190208 44.84105078
OS 33.21253708 44.83914832
OS 33.21506946 44.83788086
OS 33.21760438 44.83534848
OS 33.2201393 44.83408102
OS 33.2252066 44.82647626
OS 33.23217636 44.81950904
OS 33.2372462 44.80556698
OS 33.2429485 44.79859722
OS 33.24611842 44.79542984
OS 33.24738334 44.79289492
OS 33.25308818 44.78592516
OS 33.25625556 44.78275524
OS 33.2606904 44.77071564
OS 33.26386032 44.7662808
OS 33.26892762 44.7612135
OS 33.27019508 44.75867858
OS 33.27653238 44.7498089
OS 33.28033476 44.74600652
OS 33.28286968 44.73586684
OS 33.2841346 44.7257297
OS 33.29300428 44.70672034
OS 33.2955392 44.6965832
OS 33.29680666 44.68771352
OS 33.30314396 44.67377146
OS 33.30504388 44.65919694
OS 33.30631134 44.65159472
OS 33.3075788 44.63005298
OS 33.30884626 44.61737838
OS 33.31011372 44.60597378
OS 33.31138118 44.60090394
OS 33.31518356 44.5907668
OS 33.31835094 44.58252958
OS 33.3196184 44.57746228
OS 33.31835094 44.56605514
OS 33.31201618 44.55211562
OS 33.31074872 44.54704578
OS 33.30948126 44.53817356
OS 33.3082138 44.53310626
OS 33.30694634 44.51283198
OS 33.30504388 44.49952492
OS 33.3025115 44.48685032
OS 33.29680666 44.47354326
OS 33.2955392 44.46467358
OS 33.29300428 44.45453644
OS 33.28666952 44.4443993
OS 33.2841346 44.438062
OS 33.28096722 44.42982478
OS 33.27843484 44.42348748
OS 33.27653238 44.42158756
OS 33.27526492 44.41905264
OS 33.27146254 44.41018042
OS 33.26956262 44.3968759
OS 33.2670277 44.39054114
OS 33.26005794 44.38356884
OS 33.2549881 44.37469916
OS 33.2486508 44.36836186
OS 33.2435835 44.35442234
OS 33.23597874 44.34681758
OS 33.23471128 44.34428266
OS 33.23027644 44.3385829
OS 33.22774152 44.33731544
OS 33.17134844 44.28092236
OS 33.17071344 44.27902244
OS 33.16818106 44.27775498
OS 33.16564614 44.27522006
OS 33.16311376 44.2739526
OS 33.15677646 44.2676153
OS 33.15043916 44.26508038
OS 33.14220194 44.261913
OS 33.13459972 44.25684316
OS 33.12762742 44.25367578
OS 33.1193902 44.25050586
OS 33.11242044 44.24607102
OS 33.09848346 44.23973372
OS 33.08707632 44.23339896
OS 33.07567172 44.22832912
OS 33.05159252 44.21692452
OS 33.03955546 44.2150246
OS 33.02941578 44.21122222
OS 33.02371348 44.2093223
OS 33.01484126 44.20805484
OS 32.96668794 44.20551992
OS 32.8665713 44.20425246
OS 32.7550526 44.20425246
OS 32.47625712 44.20551992
OS 32.47245474 44.20678738
OS 32.4382384 44.20805484
OS 32.43443856 44.2093223
OS 32.4261988 44.21248968
OS 32.41542666 44.21565706
OS 32.40592198 44.21755952
OS 32.39578484 44.2213619
OS 32.38754762 44.2257942
OS 32.37741048 44.22832912
OS 32.36727334 44.22959658
OS 32.35840112 44.23466642
OS 32.3444616 44.24100118
OS 32.3381243 44.2435361
OS 32.32925208 44.2498734
OS 32.3153151 44.25494324
OS 32.3096128 44.25937808
OS 32.30834534 44.261913
OS 32.2975732 44.26888276
OS 32.2912359 44.27522006
OS 32.28616606 44.27648752
OS 32.27792884 44.2796549
OS 32.26969162 44.28788958
OS 32.26335686 44.29169196
OS 32.26145694 44.29359188
OS 32.26018948 44.2961268
OS 32.25448718 44.30183164
OS 32.25195226 44.30309656
OS 32.24878234 44.30626648
OS 32.24751488 44.3088014
OS 32.24181258 44.3145037
OS 32.23927766 44.31577116
OS 32.23737774 44.31767108
OS 32.23611028 44.320206
OS 32.23040798 44.3259083
OS 32.22787306 44.32717576
OS 32.22470568 44.33034568
OS 32.2209033 44.33668044
OS 32.214566 44.34301774
OS 32.21203108 44.3493525
OS 32.21076362 44.35442234
OS 32.20189648 44.36836186
OS 32.20062902 44.3734317
OS 32.19429172 44.3848363
OS 32.18922188 44.38990614
OS 32.18795442 44.39244106
OS 32.18225212 44.39941082
OS 32.17781728 44.40384566
OS 32.17211244 44.4196851
OS 32.16704514 44.42728986
OS 32.16387522 44.438062
OS 32.1619753 44.44883414
OS 32.15944038 44.45517144
OS 32.156273 44.4621412
OS 32.15373808 44.46847596
OS 32.15247062 44.47354326
OS 32.15120316 44.48621786
OS 32.1499357 44.496355
OS 32.14486586 44.5090296
OS 32.14360094 44.5140969
OS 32.14170102 44.53500618
OS 32.14043356 44.555283
OS 32.13979856 44.60660624
OS 32.14106602 44.61040862
OS 32.14233348 44.64082512
OS 32.14360094 44.64462496
OS 32.14486586 44.65349464
OS 32.14740078 44.65983194
OS 32.1499357 44.66870416
OS 32.15437054 44.69595074
OS 32.15690546 44.7022855
OS 32.16260776 44.71559002
OS 32.16387522 44.72446224
OS 32.16577768 44.73269946
OS 32.1676776 44.73460192
OS 32.16894506 44.7371343
OS 32.1740149 44.74220414
OS 32.17528236 44.74473906
OS 32.18098466 44.75170882
OS 32.18288458 44.75361128
OS 32.18415204 44.7561462
OS 32.18922188 44.76754826
OS 32.19429172 44.77642048
OS 32.20062902 44.79036
OS 32.20506132 44.79859722
OS 32.20759624 44.79986468
OS 32.20949616 44.80176714
OS 32.21076362 44.80429952
OS 32.21646592 44.81127182
OS 32.22343822 44.81697412
OS 32.22914052 44.82394134
OS 32.23611028 44.82964364
OS 32.24181258 44.8366134
OS 32.2443475 44.83788086
OS 32.24878234 44.84231824
OS 32.2500498 44.84485316
OS 32.25448718 44.849288
OS 32.2570221 44.85055546
OS 32.26145694 44.8549903
OS 32.2627244 44.85752522
OS 32.26588924 44.8606926
OS 32.26842416 44.86196006
OS 32.272859 44.86639744
OS 32.27412646 44.86892982
OS 32.27856384 44.8733672
OS 32.28109622 44.87463466
OS 32.2855336 44.8790695
OS 32.28680106 44.88160442
OS 32.28996844 44.88476926
OS 32.29250336 44.88603672
OS 32.29503828 44.88857164
OS 32.2975732 44.8898391
OS 32.29884066 44.89237402
OS 32.30137558 44.89364148
OS 32.30390796 44.8961764
OS 32.31088026 44.89807632
OS 32.31848248 44.9018787
OS 32.3260847 44.90694854
OS 32.33622438 44.91075092
OS 32.34255914 44.91328584
OS 32.34572906 44.91645322
OS 32.34826144 44.91772068
OS 32.35713366 44.92152306
OS 32.36347096 44.92405798
OS 32.36600588 44.9253229
OS 32.37487556 44.9316602
OS 32.38691262 44.93609504
OS 32.39324992 44.93862996
OS 32.40148714 44.94306734
OS 32.40655698 44.94433226
OS 32.42429888 44.94686718
OS 32.43760594 44.95003456
OS 32.44394324 44.95256948
OS 32.45027546 44.95383694
OS 32.4680199 44.9551044
OS 32.48956418 44.95637186
OS 32.54151988 44.95763932
OS 32.90459002 44.95827178
OS 32.9083924 44.95700432
OE
SE
S P 0
OB 34.1952961 42.10883628 I
OS 34.20036594 42.10756882
OS 34.2067007 42.10630136
OS 34.21493792 42.10313144
OS 34.2250776 42.10059906
OS 34.24091958 42.0986966
OS 34.25105418 42.09616168
OS 34.25739148 42.09362676
OS 34.2592914 42.09172684
OS 34.271966 42.08792446
OS 34.28210314 42.086657
OS 34.30111504 42.07778732
OS 34.31124964 42.0752524
OS 34.32138932 42.07398494
OS 34.32835908 42.06828264
OS 34.33152646 42.06511526
OS 34.34039868 42.06004542
OS 34.34673344 42.05371066
OS 34.35307074 42.05117574
OS 34.3549732 42.05054074
OS 34.35560566 42.04990828
OS 34.3606755 42.04864082
OS 34.36827772 42.04103606
OS 34.3708101 42.0397686
OS 34.37334502 42.03723368
OS 34.37587994 42.03596876
OS 34.37904986 42.03153138
OS 34.38475216 42.02582908
OS 34.38728708 42.02456162
OS 34.39362184 42.01822432
OS 34.39615676 42.01695686
OS 34.40249406 42.01442448
OS 34.4075639 42.01315702
OS 34.41453366 42.00745218
OS 34.4189685 42.00301988
OS 34.42150342 42.00175242
OS 34.42847064 41.99478266
OS 34.4297381 41.99224774
OS 34.43164056 41.99034782
OS 34.43417548 41.98908036
OS 34.43987778 41.98337552
OS 34.44114524 41.9808406
OS 34.44748 41.97450584
OS 34.44874746 41.97197092
OS 34.45128238 41.96563362
OS 34.45254984 41.96056378
OS 34.45508476 41.9580314
OS 34.45635222 41.95549648
OS 34.46268952 41.94915918
OS 34.46395698 41.94662426
OS 34.46965928 41.93965704
OS 34.47282666 41.93648712
OS 34.47726404 41.92445006
OS 34.48043142 41.92001268
OS 34.48423126 41.9162103
OS 34.48549872 41.91367792
OS 34.4943684 41.90227078
OS 34.49690332 41.89973586
OS 34.49943824 41.88959872
OS 34.5007057 41.87946158
OS 34.50957792 41.86045222
OS 34.51211284 41.85031254
OS 34.51337776 41.84144286
OS 34.52098252 41.82496842
OS 34.52288498 41.81799866
OS 34.5241499 41.80405914
OS 34.52541736 41.79645438
OS 34.52731982 41.78948462
OS 34.52985474 41.78314732
OS 34.53238966 41.77427764
OS 34.53365712 41.76160558
OS 34.5361895 41.72738924
OS 34.53428958 41.70267758
OS 34.53302212 41.6874706
OS 34.53175466 41.67986838
OS 34.52795228 41.6697287
OS 34.52668482 41.66465886
OS 34.5247849 41.6576891
OS 34.52351744 41.64501958
OS 34.52224998 41.63614736
OS 34.52098252 41.63234498
OS 34.51464522 41.61840546
OS 34.51211284 41.60953324
OS 34.51084538 41.5993961
OS 34.49817078 41.57278452
OS 34.49310094 41.5639123
OS 34.48549872 41.54743786
OS 34.48043142 41.53856564
OS 34.47536158 41.52716104
OS 34.47029174 41.51829136
OS 34.46522444 41.51322406
OS 34.46395698 41.51068914
OS 34.4595196 41.5049843
OS 34.45698722 41.50371684
OS 34.44874746 41.49547962
OS 34.448115 41.4935797
OS 34.44558008 41.49231224
OS 34.43734286 41.48407502
OS 34.4360754 41.4815401
OS 34.42847064 41.4752028
OS 34.38791954 41.4346517
OS 34.38728708 41.43275178
OS 34.38475216 41.43148432
OS 34.37651494 41.4232471
OS 34.37524748 41.42071218
OS 34.3708101 41.41754226
OS 34.36384034 41.41183996
OS 34.3606755 41.40867258
OS 34.3543382 41.40613766
OS 34.34926836 41.40487274
OS 34.3429336 41.40107036
OS 34.34039868 41.39853544
OS 34.33152646 41.39473306
OS 34.32328924 41.39156568
OS 34.31631948 41.38713084
OS 34.30237996 41.38079354
OS 34.2833706 41.37192132
OS 34.2783033 41.37065386
OS 34.26182632 41.36938894
OS 34.25675902 41.36812148
OS 34.24471942 41.3636841
OS 34.23394982 41.36051672
OS 34.22887998 41.35924926
OS 34.21620538 41.3579818
OS 34.2073357 41.35671434
OS 34.1952961 41.35481442
OS 34.19022626 41.35354696
OS 34.18008912 41.34974458
OS 34.17375436 41.34847712
OS 34.16361468 41.34720966
OS 34.14650778 41.34531228
OS 34.12939834 41.34720966
OS 34.1192612 41.34847712
OS 34.1129239 41.34974458
OS 34.10595414 41.35291196
OS 34.09898438 41.35481442
OS 34.09137962 41.35608188
OS 34.07427272 41.3579818
OS 34.0609682 41.35988172
OS 34.05589836 41.36114918
OS 34.04766114 41.3643191
OS 34.03878892 41.36812148
OS 34.02991924 41.36938894
OS 34.0248494 41.37065386
OS 34.01661218 41.37382378
OS 34.00077274 41.38079354
OS 33.99190052 41.382061
OS 33.9842983 41.38332846
OS 33.97732854 41.38903076
OS 33.97415862 41.39219814
OS 33.96528894 41.39726798
OS 33.95895164 41.40360528
OS 33.95261434 41.40613766
OS 33.94437712 41.40930504
OS 33.9367749 41.41437488
OS 33.92980514 41.41754226
OS 33.919668 41.42134464
OS 33.91206324 41.4289494
OS 33.90952832 41.43021686
OS 33.9012911 41.43845408
OS 33.90065864 41.440354
OS 33.89812372 41.44162146
OS 33.84743294 41.49231224
OS 33.84489802 41.4935797
OS 33.83982818 41.50118446
OS 33.83285842 41.50815422
OS 33.8303235 41.51448898
OS 33.82652112 41.52462866
OS 33.82398874 41.52716104
OS 33.82272382 41.52969596
OS 33.81892144 41.53856564
OS 33.81575152 41.5468054
OS 33.8075143 41.55504262
OS 33.80624684 41.55757754
OS 33.79991208 41.56644722
OS 33.79737716 41.56898214
OS 33.79484224 41.57531944
OS 33.79357478 41.58418912
OS 33.79167232 41.59115888
OS 33.78913994 41.59749364
OS 33.78216764 41.61333562
OS 33.78026772 41.62537522
OS 33.77646534 41.6355149
OS 33.77456542 41.64248466
OS 33.77329796 41.64755196
OS 33.7713955 41.67733346
OS 33.77012804 41.7102798
OS 33.76949558 41.7463986
OS 33.77076304 41.75020098
OS 33.7720305 41.79582192
OS 33.77329796 41.7996243
OS 33.77456542 41.8173662
OS 33.7783678 41.82623334
OS 33.78090018 41.83510556
OS 33.78280264 41.8458777
OS 33.78533756 41.852215
OS 33.79230732 41.86678952
OS 33.79357478 41.8756592
OS 33.7954747 41.88389642
OS 33.79800962 41.89023118
OS 33.80117954 41.89339856
OS 33.80497938 41.90227078
OS 33.80624684 41.90734062
OS 33.81004922 41.91367792
OS 33.81638652 41.92001268
OS 33.81765398 41.9225476
OS 33.82335628 41.93078482
OS 33.8252562 41.93141982
OS 33.82652112 41.93395474
OS 33.8303235 41.94282442
OS 33.83539334 41.9516941
OS 33.84173064 41.9580314
OS 33.8429981 41.96056378
OS 33.89939118 42.01695686
OS 33.9012911 42.01759186
OS 33.90255856 42.02012678
OS 33.91079578 42.028364
OS 33.9133307 42.02963146
OS 33.919668 42.03596876
OS 33.92600276 42.03850114
OS 33.93424252 42.04167106
OS 33.93994482 42.04737336
OS 33.94247974 42.04864082
OS 33.94501212 42.05117574
OS 33.95134688 42.05497812
OS 33.95768418 42.06131288
OS 33.9716237 42.06638018
OS 33.98049592 42.07271748
OS 33.99253552 42.07715232
OS 33.99697036 42.07905478
OS 34.0071075 42.08538954
OS 34.02231448 42.08792446
OS 34.03435408 42.0923593
OS 34.04132384 42.09552922
OS 34.05146352 42.09806414
OS 34.06793542 42.0993316
OS 34.07300526 42.10059906
OS 34.08567732 42.10186652
OS 34.0894797 42.10313144
OS 34.10215176 42.10693382
OS 34.1072216 42.10820128
OS 34.1198962 42.10946874
OS 34.15411 42.11200366
OS 34.1952961 42.10883628
OE
SE
S P 0
OB -2.28224842 -38.48662356 I
OS -2.27485194 -38.48754812
OS -2.26560634 -38.48939724
OS -2.25543618 -38.49124636
OS -2.2434169 -38.49402004
OS -2.23232218 -38.49679372
OS -2.21937834 -38.50141652
OS -2.20735906 -38.50603932
OS -2.19441522 -38.51251124
OS -2.18147138 -38.51990772
OS -2.16852754 -38.52822876
OS -2.15650826 -38.53839892
OS -2.14541354 -38.54949364
OS -2.14448898 -38.5504182
OS -2.14263986 -38.55226732
OS -2.13986618 -38.55596556
OS -2.13616794 -38.56151292
OS -2.13154514 -38.56798484
OS -2.12692234 -38.57538132
OS -2.12137498 -38.58462692
OS -2.11582762 -38.59572164
OS -2.11028026 -38.60774092
OS -2.1047329 -38.62068476
OS -2.1001101 -38.63547772
OS -2.0954873 -38.65119524
OS -2.09178906 -38.66876188
OS -2.08901538 -38.68725308
OS -2.08716626 -38.70666884
OS -2.0862417 -38.72793372
OS -2.0862417 -38.72885828
OS -2.0862417 -38.73255652
OS -2.0862417 -38.73902844
OS -2.08716626 -38.74827404
OS -2.43387626 -38.74827404
OS -2.43387626 -38.7491986
OS -2.43387626 -38.75197228
OS -2.4329517 -38.75567052
OS -2.4329517 -38.76121788
OS -2.43202714 -38.7676898
OS -2.43017802 -38.77508628
OS -2.42740434 -38.79172836
OS -2.42185698 -38.81021956
OS -2.4144605 -38.83055988
OS -2.40429034 -38.84905108
OS -2.3913465 -38.86569316
OS -2.39042194 -38.86569316
OS -2.38949738 -38.86754228
OS -2.38395002 -38.87216508
OS -2.37562898 -38.878637
OS -2.36453426 -38.88510892
OS -2.3497413 -38.8925054
OS -2.33309922 -38.89897732
OS -2.31460802 -38.90360012
OS -2.30443786 -38.90452468
OS -2.29334314 -38.90544924
OS -2.28594666 -38.90544924
OS -2.27762562 -38.90452468
OS -2.26745546 -38.90267556
OS -2.25636074 -38.89990188
OS -2.2434169 -38.89620364
OS -2.23139762 -38.89065628
OS -2.21937834 -38.8832598
OS -2.21845378 -38.88233524
OS -2.21383098 -38.878637
OS -2.20828362 -38.87308964
OS -2.2018117 -38.86569316
OS -2.19441522 -38.855523
OS -2.18609418 -38.84257916
OS -2.17777314 -38.8277862
OS -2.17037666 -38.81021956
OS -2.08901538 -38.82038972
OS -2.08901538 -38.82131428
OS -2.08993994 -38.8231634
OS -2.0908645 -38.82686164
OS -2.09271362 -38.832409
OS -2.0954873 -38.83795636
OS -2.09826098 -38.84535284
OS -2.10565746 -38.86107036
OS -2.11490306 -38.878637
OS -2.1278469 -38.8971282
OS -2.14263986 -38.91469484
OS -2.16113106 -38.93133692
OS -2.16205562 -38.93133692
OS -2.16390474 -38.93318604
OS -2.16667842 -38.93503516
OS -2.17037666 -38.93780884
OS -2.17592402 -38.94058252
OS -2.18147138 -38.9433562
OS -2.18886786 -38.94705444
OS -2.1971889 -38.95075268
OS -2.2064345 -38.95445092
OS -2.2156801 -38.95814916
OS -2.2387941 -38.96369652
OS -2.26468178 -38.96831932
OS -2.29334314 -38.97016844
OS -2.3035133 -38.97016844
OS -2.30998522 -38.96924388
OS -2.31830626 -38.96831932
OS -2.32847642 -38.9664702
OS -2.33957114 -38.96462108
OS -2.35159042 -38.96277196
OS -2.3774781 -38.95537548
OS -2.3913465 -38.94982812
OS -2.40429034 -38.94428076
OS -2.41815874 -38.93688428
OS -2.43110258 -38.92856324
OS -2.44312186 -38.91931764
OS -2.45514114 -38.90822292
OS -2.4560657 -38.90729836
OS -2.45791482 -38.90544924
OS -2.4606885 -38.901751
OS -2.46438674 -38.89620364
OS -2.46900954 -38.88973172
OS -2.47363234 -38.88233524
OS -2.4791797 -38.87308964
OS -2.48472706 -38.86291948
OS -2.49027442 -38.8509002
OS -2.49582178 -38.83795636
OS -2.50044458 -38.8231634
OS -2.50506738 -38.80744588
OS -2.50876562 -38.7908038
OS -2.5115393 -38.7723126
OS -2.51338842 -38.75289684
OS -2.51431298 -38.73255652
OS -2.51431298 -38.73163196
OS -2.51431298 -38.72700916
OS -2.51431298 -38.7214618
OS -2.51338842 -38.71314076
OS -2.51246386 -38.7029706
OS -2.5115393 -38.69187588
OS -2.50969018 -38.67893204
OS -2.5069165 -38.6659882
OS -2.49952002 -38.63640228
OS -2.49489722 -38.62160932
OS -2.48934986 -38.6058918
OS -2.48195338 -38.59109884
OS -2.47363234 -38.57723044
OS -2.46438674 -38.56336204
OS -2.45421658 -38.5504182
OS -2.45329202 -38.54949364
OS -2.4514429 -38.54764452
OS -2.44774466 -38.54487084
OS -2.44312186 -38.54024804
OS -2.4375745 -38.53562524
OS -2.43017802 -38.53007788
OS -2.42185698 -38.52360596
OS -2.41168682 -38.5180586
OS -2.40151666 -38.51158668
OS -2.38949738 -38.50603932
OS -2.37655354 -38.50049196
OS -2.36268514 -38.49586916
OS -2.34789218 -38.49124636
OS -2.33217466 -38.48847268
OS -2.31553258 -38.48662356
OS -2.29796594 -38.485699
OS -2.28872034 -38.485699
OS -2.28224842 -38.48662356
OE
OB -3.95755114 -38.48662356 I
OS -3.94368274 -38.48754812
OS -3.92888978 -38.48939724
OS -3.91317226 -38.49309548
OS -3.89653018 -38.49679372
OS -3.88081266 -38.50234108
OS -3.8798881 -38.50234108
OS -3.87896354 -38.50326564
OS -3.87434074 -38.50511476
OS -3.86694426 -38.508813
OS -3.85769866 -38.5134358
OS -3.8475285 -38.51990772
OS -3.83735834 -38.5273042
OS -3.82811274 -38.53562524
OS -3.8197917 -38.54487084
OS -3.81886714 -38.5457954
OS -3.81701802 -38.54949364
OS -3.81331978 -38.55596556
OS -3.80869698 -38.56336204
OS -3.80407418 -38.57445676
OS -3.79945138 -38.58647604
OS -3.79575314 -38.60034444
OS -3.7920549 -38.61606196
OS -3.86879338 -38.62623212
OS -3.86879338 -38.624383
OS -3.86971794 -38.62068476
OS -3.87156706 -38.61421284
OS -3.87434074 -38.6058918
OS -3.87896354 -38.59757076
OS -3.8845109 -38.58832516
OS -3.89098282 -38.57907956
OS -3.90022842 -38.57075852
OS -3.90115298 -38.56983396
OS -3.90485122 -38.56798484
OS -3.91039858 -38.5642866
OS -3.91871962 -38.56058836
OS -3.92796522 -38.55689012
OS -3.9399845 -38.55319188
OS -3.95477746 -38.55134276
OS -3.97049498 -38.5504182
OS -3.97974058 -38.5504182
OS -3.98898618 -38.55134276
OS -4.00100546 -38.55226732
OS -4.01302474 -38.555041
OS -4.02596858 -38.55781468
OS -4.03798786 -38.56243748
OS -4.04815802 -38.5689094
OS -4.04908258 -38.56983396
OS -4.05185626 -38.57168308
OS -4.0555545 -38.57538132
OS -4.05925274 -38.58092868
OS -4.06387554 -38.58647604
OS -4.06757378 -38.59387252
OS -4.07034746 -38.60219356
OS -4.07127202 -38.6105146
OS -4.07127202 -38.61143916
OS -4.07127202 -38.61328828
OS -4.07034746 -38.61606196
OS -4.07034746 -38.6197602
OS -4.06757378 -38.6290058
OS -4.06202642 -38.6382514
OS -4.06110186 -38.63917596
OS -4.0601773 -38.64010052
OS -4.05832818 -38.6428742
OS -4.05462994 -38.64564788
OS -4.0509317 -38.64842156
OS -4.04538434 -38.6521198
OS -4.03891242 -38.65489348
OS -4.03151594 -38.65859172
OS -4.03059138 -38.65859172
OS -4.02874226 -38.65951628
OS -4.02504402 -38.66044084
OS -4.0185721 -38.66321452
OS -4.0093265 -38.6659882
OS -3.99730722 -38.66876188
OS -3.98991074 -38.67153556
OS -3.9815897 -38.67338468
OS -3.9723441 -38.67615836
OS -3.96217394 -38.67893204
OS -3.96124938 -38.67893204
OS -3.9584757 -38.6798566
OS -3.9538529 -38.68078116
OS -3.94830554 -38.68263028
OS -3.94183362 -38.6844794
OS -3.93351258 -38.68632852
OS -3.91594594 -38.69187588
OS -3.89653018 -38.69742324
OS -3.87711442 -38.70389516
OS -3.85954778 -38.71036708
OS -3.8521513 -38.71314076
OS -3.84567938 -38.71591444
OS -3.84383026 -38.716839
OS -3.84013202 -38.71868812
OS -3.83458466 -38.7214618
OS -3.82626362 -38.7260846
OS -3.81794258 -38.73163196
OS -3.80962154 -38.73902844
OS -3.8013005 -38.74734948
OS -3.79390402 -38.75659508
OS -3.79297946 -38.75751964
OS -3.79113034 -38.76121788
OS -3.7874321 -38.76676524
OS -3.78373386 -38.77508628
OS -3.78096018 -38.78525644
OS -3.77726194 -38.79635116
OS -3.77541282 -38.809295
OS -3.77448826 -38.82408796
OS -3.77448826 -38.82593708
OS -3.77448826 -38.83055988
OS -3.77541282 -38.83795636
OS -3.77726194 -38.84812652
OS -3.78003562 -38.85922124
OS -3.78465842 -38.87124052
OS -3.79020578 -38.88510892
OS -3.79760226 -38.89805276
OS -3.79852682 -38.89990188
OS -3.80222506 -38.90360012
OS -3.80684786 -38.91007204
OS -3.81424434 -38.91746852
OS -3.8244145 -38.92578956
OS -3.83550922 -38.93503516
OS -3.84845306 -38.9433562
OS -3.86417058 -38.95167724
OS -3.86509514 -38.95167724
OS -3.8660197 -38.9526018
OS -3.87156706 -38.95445092
OS -3.88081266 -38.9572246
OS -3.89283194 -38.96092284
OS -3.9076249 -38.96462108
OS -3.92426698 -38.96739476
OS -3.94183362 -38.96924388
OS -3.96217394 -38.97016844
OS -3.97049498 -38.97016844
OS -3.9769669 -38.96924388
OS -3.98436338 -38.96924388
OS -3.99360898 -38.96831932
OS -4.00285458 -38.96739476
OS -4.01302474 -38.96554564
OS -4.03521418 -38.96092284
OS -4.05832818 -38.95445092
OS -4.08051762 -38.94520532
OS -4.09068778 -38.93965796
OS -4.09993338 -38.93318604
OS -4.10085794 -38.93226148
OS -4.1017825 -38.93133692
OS -4.10732986 -38.92578956
OS -4.1156509 -38.91746852
OS -4.1248965 -38.90452468
OS -4.13506666 -38.88880716
OS -4.14523682 -38.87031596
OS -4.15355786 -38.84720196
OS -4.16002978 -38.82131428
OS -4.08236674 -38.809295
OS -4.08236674 -38.81021956
OS -4.08236674 -38.81114412
OS -4.08051762 -38.81669148
OS -4.0786685 -38.82593708
OS -4.07497026 -38.83610724
OS -4.07034746 -38.84720196
OS -4.0648001 -38.85922124
OS -4.05647906 -38.87124052
OS -4.0463089 -38.88141068
OS -4.04445978 -38.88233524
OS -4.04076154 -38.88510892
OS -4.03336506 -38.88880716
OS -4.02411946 -38.89342996
OS -4.01210018 -38.89805276
OS -3.99823178 -38.901751
OS -3.9815897 -38.90452468
OS -3.96217394 -38.90544924
OS -3.95292834 -38.90544924
OS -3.94368274 -38.90452468
OS -3.93166346 -38.90267556
OS -3.91871962 -38.89990188
OS -3.90485122 -38.89620364
OS -3.89283194 -38.89158084
OS -3.88173722 -38.88418436
OS -3.88081266 -38.8832598
OS -3.87711442 -38.88048612
OS -3.87341618 -38.87586332
OS -3.86786882 -38.8693914
OS -3.86324602 -38.86199492
OS -3.85862322 -38.85274932
OS -3.85584954 -38.84350372
OS -3.85492498 -38.832409
OS -3.85492498 -38.83148444
OS -3.85492498 -38.8277862
OS -3.85584954 -38.8231634
OS -3.85769866 -38.81669148
OS -3.86047234 -38.81021956
OS -3.86509514 -38.80374764
OS -3.8706425 -38.79635116
OS -3.87896354 -38.7908038
OS -3.8798881 -38.78987924
OS -3.88266178 -38.78895468
OS -3.88728458 -38.786181
OS -3.89468106 -38.78340732
OS -3.90577578 -38.77970908
OS -3.9122477 -38.7769354
OS -3.91964418 -38.77508628
OS -3.92796522 -38.7723126
OS -3.93721082 -38.76953892
OS -3.94738098 -38.76676524
OS -3.95940026 -38.76399156
OS -3.96032482 -38.76399156
OS -3.9630985 -38.763067
OS -3.9677213 -38.76214244
OS -3.97326866 -38.76029332
OS -3.98066514 -38.7584442
OS -3.98898618 -38.75567052
OS -4.00655282 -38.75104772
OS -4.02689314 -38.7445758
OS -4.0463089 -38.73902844
OS -4.0648001 -38.73255652
OS -4.07312114 -38.72885828
OS -4.07959306 -38.7260846
OS -4.08144218 -38.72516004
OS -4.08514042 -38.72331092
OS -4.09068778 -38.71961268
OS -4.09808426 -38.71498988
OS -4.1064053 -38.70851796
OS -4.11472634 -38.70112148
OS -4.12304738 -38.69280044
OS -4.13044386 -38.68263028
OS -4.13136842 -38.68170572
OS -4.13321754 -38.67800748
OS -4.13599122 -38.67153556
OS -4.1387649 -38.66413908
OS -4.14153858 -38.65489348
OS -4.14431226 -38.64379876
OS -4.14616138 -38.63270404
OS -4.14708594 -38.6197602
OS -4.14708594 -38.61791108
OS -4.14708594 -38.61421284
OS -4.14616138 -38.60866548
OS -4.14523682 -38.60034444
OS -4.1433877 -38.5920234
OS -4.14153858 -38.58185324
OS -4.13784034 -38.57260764
OS -4.13321754 -38.56243748
OS -4.13229298 -38.56151292
OS -4.13044386 -38.55781468
OS -4.12767018 -38.55319188
OS -4.12304738 -38.54671996
OS -4.11750002 -38.54024804
OS -4.1110281 -38.531927
OS -4.10363162 -38.52453052
OS -4.09438602 -38.5180586
OS -4.09346146 -38.51713404
OS -4.09068778 -38.51620948
OS -4.08698954 -38.5134358
OS -4.08144218 -38.51066212
OS -4.0740457 -38.50696388
OS -4.06572466 -38.50326564
OS -4.0555545 -38.4995674
OS -4.04445978 -38.49586916
OS -4.04261066 -38.4949446
OS -4.03891242 -38.49402004
OS -4.0324405 -38.49217092
OS -4.02411946 -38.4903218
OS -4.0139493 -38.48847268
OS -4.00285458 -38.48754812
OS -3.98991074 -38.485699
OS -3.9677213 -38.485699
OS -3.95755114 -38.48662356
OE
OB -4.17852098 -39.1375138 I
OS -4.69904826 -39.1375138
OS -4.69904826 -39.08111564
OS -4.17852098 -39.08111564
OS -4.17852098 -39.1375138
OE
OB -2.61231634 -38.95999828 I
OS -2.68535658 -38.95999828
OS -2.68535658 -38.901751
OS -2.68628114 -38.90267556
OS -2.6872057 -38.90452468
OS -2.68997938 -38.90822292
OS -2.69367762 -38.91284572
OS -2.69830042 -38.91746852
OS -2.70384778 -38.92301588
OS -2.7103197 -38.9294878
OS -2.71864074 -38.93595972
OS -2.72696178 -38.94243164
OS -2.73620738 -38.94890356
OS -2.7473021 -38.95445092
OS -2.75932138 -38.95907372
OS -2.77134066 -38.96369652
OS -2.78520906 -38.96739476
OS -2.80000202 -38.96924388
OS -2.81571954 -38.97016844
OS -2.8212669 -38.97016844
OS -2.82496514 -38.96924388
OS -2.83605986 -38.96831932
OS -2.8490037 -38.9664702
OS -2.86472122 -38.96277196
OS -2.88228786 -38.9572246
OS -2.8998545 -38.94982812
OS -2.91742114 -38.93965796
OS -2.9183457 -38.93965796
OS -2.91927026 -38.93780884
OS -2.92481762 -38.9341106
OS -2.93313866 -38.92671412
OS -2.94330882 -38.91746852
OS -2.9553281 -38.90544924
OS -2.96734738 -38.89065628
OS -2.97936666 -38.8740142
OS -2.98953682 -38.85459844
OS -2.98953682 -38.85367388
OS -2.99046138 -38.85182476
OS -2.99138594 -38.84905108
OS -2.99323506 -38.84535284
OS -2.99508418 -38.83980548
OS -2.99785786 -38.83333356
OS -2.99970698 -38.82686164
OS -3.0015561 -38.8185406
OS -3.0061789 -38.8000494
OS -3.0108017 -38.77878452
OS -3.01357538 -38.75474596
OS -3.01449994 -38.72885828
OS -3.01449994 -38.72793372
OS -3.01449994 -38.7260846
OS -3.01449994 -38.72238636
OS -3.01449994 -38.716839
OS -3.01357538 -38.71129164
OS -3.01357538 -38.70389516
OS -3.01172626 -38.68725308
OS -3.00895258 -38.66783732
OS -3.00432978 -38.64657244
OS -2.99878242 -38.624383
OS -2.99138594 -38.60311812
OS -2.99138594 -38.60219356
OS -2.99046138 -38.60034444
OS -2.98861226 -38.59757076
OS -2.98676314 -38.59387252
OS -2.98121578 -38.58370236
OS -2.9738193 -38.57075852
OS -2.9645737 -38.55689012
OS -2.95255442 -38.54302172
OS -2.93868602 -38.52822876
OS -2.92204394 -38.51620948
OS -2.92111938 -38.51620948
OS -2.92019482 -38.51528492
OS -2.91742114 -38.5134358
OS -2.9137229 -38.51158668
OS -2.9044773 -38.50696388
OS -2.89153346 -38.50049196
OS -2.8767405 -38.4949446
OS -2.85917386 -38.4903218
OS -2.8397581 -38.48662356
OS -2.81941778 -38.485699
OS -2.8120213 -38.485699
OS -2.80462482 -38.48662356
OS -2.79445466 -38.48754812
OS -2.78243538 -38.4903218
OS -2.76949154 -38.49309548
OS -2.7565477 -38.49771828
OS -2.74452842 -38.5041902
OS -2.7426793 -38.50511476
OS -2.73898106 -38.50696388
OS -2.7334337 -38.51158668
OS -2.72603722 -38.51620948
OS -2.71679162 -38.5226814
OS -2.70847058 -38.53100244
OS -2.69922498 -38.53932348
OS -2.69090394 -38.54949364
OS -2.69090394 -38.32020276
OS -2.61231634 -38.32020276
OS -2.61231634 -38.95999828
OE
OB -3.10695594 -38.95999828 I
OS -3.18554354 -38.95999828
OS -3.18554354 -38.32020276
OS -3.10695594 -38.32020276
OS -3.10695594 -38.95999828
OE
OB -3.4777045 -38.48662356 I
OS -3.46938346 -38.48754812
OS -3.46013786 -38.48939724
OS -3.4499677 -38.49124636
OS -3.43794842 -38.49309548
OS -3.4129853 -38.50141652
OS -3.40004146 -38.50603932
OS -3.38709762 -38.51251124
OS -3.37415378 -38.51898316
OS -3.36120994 -38.52822876
OS -3.34919066 -38.53747436
OS -3.33717138 -38.54856908
OS -3.33624682 -38.54949364
OS -3.3343977 -38.55134276
OS -3.33162402 -38.555041
OS -3.32792578 -38.5596638
OS -3.32330298 -38.56613572
OS -3.31775562 -38.57445676
OS -3.31220826 -38.58370236
OS -3.3066609 -38.59387252
OS -3.30111354 -38.60496724
OS -3.29556618 -38.61883564
OS -3.29001882 -38.63270404
OS -3.28539602 -38.64842156
OS -3.28169778 -38.66506364
OS -3.2789241 -38.68263028
OS -3.27707498 -38.70112148
OS -3.27615042 -38.7214618
OS -3.27615042 -38.72238636
OS -3.27615042 -38.72516004
OS -3.27615042 -38.72978284
OS -3.27615042 -38.73625476
OS -3.27707498 -38.74365124
OS -3.27799954 -38.75289684
OS -3.27799954 -38.76214244
OS -3.27984866 -38.7723126
OS -3.28262234 -38.7954266
OS -3.2881697 -38.8185406
OS -3.29464162 -38.8416546
OS -3.30388722 -38.86291948
OS -3.30388722 -38.86384404
OS -3.30481178 -38.8647686
OS -3.3066609 -38.86754228
OS -3.30851002 -38.87124052
OS -3.31498194 -38.88048612
OS -3.32330298 -38.89158084
OS -3.3343977 -38.90452468
OS -3.3482661 -38.91746852
OS -3.36398362 -38.93041236
OS -3.38247482 -38.94243164
OS -3.38339938 -38.94243164
OS -3.38432394 -38.9433562
OS -3.38709762 -38.94520532
OS -3.39172042 -38.94705444
OS -3.39634322 -38.94890356
OS -3.40189058 -38.95075268
OS -3.41575898 -38.95630004
OS -3.4314765 -38.96092284
OS -3.45089226 -38.96554564
OS -3.47123258 -38.96924388
OS -3.49342202 -38.97016844
OS -3.50266762 -38.97016844
OS -3.5100641 -38.96924388
OS -3.51838514 -38.96831932
OS -3.52763074 -38.9664702
OS -3.53872546 -38.96462108
OS -3.54982018 -38.96277196
OS -3.5747833 -38.95537548
OS -3.5886517 -38.94982812
OS -3.60159554 -38.94428076
OS -3.61453938 -38.93688428
OS -3.62748322 -38.92856324
OS -3.6395025 -38.91931764
OS -3.65152178 -38.90822292
OS -3.65244634 -38.90729836
OS -3.65429546 -38.90544924
OS -3.65706914 -38.901751
OS -3.66076738 -38.89620364
OS -3.66539018 -38.88973172
OS -3.67001298 -38.88233524
OS -3.67556034 -38.87308964
OS -3.6811077 -38.86199492
OS -3.68665506 -38.84997564
OS -3.69220242 -38.83610724
OS -3.69682522 -38.82131428
OS -3.70144802 -38.80559676
OS -3.70514626 -38.78803012
OS -3.70791994 -38.76953892
OS -3.70976906 -38.7491986
OS -3.71069362 -38.72793372
OS -3.71069362 -38.7260846
OS -3.71069362 -38.72238636
OS -3.70976906 -38.71591444
OS -3.70976906 -38.70666884
OS -3.7088445 -38.69649868
OS -3.70699538 -38.68355484
OS -3.70514626 -38.670611
OS -3.70144802 -38.65581804
OS -3.69774978 -38.64102508
OS -3.69312698 -38.62530756
OS -3.68757962 -38.60866548
OS -3.68018314 -38.59294796
OS -3.67278666 -38.578155
OS -3.6626165 -38.56336204
OS -3.65244634 -38.54949364
OS -3.6395025 -38.53747436
OS -3.63857794 -38.5365498
OS -3.63672882 -38.53562524
OS -3.63303058 -38.53285156
OS -3.62840778 -38.52915332
OS -3.62286042 -38.52545508
OS -3.61546394 -38.52083228
OS -3.60806746 -38.51620948
OS -3.59882186 -38.51158668
OS -3.5886517 -38.50696388
OS -3.57755698 -38.50234108
OS -3.55259386 -38.49402004
OS -3.5239325 -38.48754812
OS -3.50913954 -38.48662356
OS -3.49342202 -38.485699
OS -3.48417642 -38.485699
OS -3.4777045 -38.48662356
OE
OB -1.62211258 -38.42745172 I
OS -1.64337746 -38.54671996
OS -1.69237914 -38.54671996
OS -1.7117949 -38.42745172
OS -1.7117949 -38.32020276
OS -1.62211258 -38.32020276
OS -1.62211258 -38.42745172
OE
OB -5.97031826 -38.42745172 I
OS -5.99158314 -38.54671996
OS -6.04058482 -38.54671996
OS -6.06000058 -38.42745172
OS -6.06000058 -38.32020276
OS -5.97031826 -38.32020276
OS -5.97031826 -38.42745172
OE
OB -5.77800978 -38.49586916 I
OS -5.69849762 -38.49586916
OS -5.69849762 -38.55689012
OS -5.77800978 -38.55689012
OS -5.77800978 -38.82963532
OS -5.77800978 -38.83148444
OS -5.77800978 -38.83518268
OS -5.77800978 -38.84073004
OS -5.77708522 -38.84720196
OS -5.77616066 -38.86199492
OS -5.7752361 -38.86846684
OS -5.77431154 -38.87308964
OS -5.77338698 -38.87493876
OS -5.7706133 -38.878637
OS -5.76691506 -38.8832598
OS -5.76044314 -38.8878826
OS -5.75859402 -38.88880716
OS -5.75397122 -38.89065628
OS -5.74565018 -38.8925054
OS -5.7336309 -38.89342996
OS -5.7243853 -38.89342996
OS -5.7197625 -38.8925054
OS -5.71329058 -38.8925054
OS -5.7058941 -38.89158084
OS -5.69849762 -38.89065628
OS -5.68832746 -38.95999828
OS -5.69017658 -38.95999828
OS -5.69387482 -38.96092284
OS -5.70034674 -38.9618474
OS -5.70866778 -38.96277196
OS -5.71791338 -38.96462108
OS -5.72808354 -38.96554564
OS -5.74842386 -38.9664702
OS -5.75582034 -38.9664702
OS -5.76321682 -38.96554564
OS -5.77246242 -38.96462108
OS -5.78355714 -38.96369652
OS -5.79465186 -38.96092284
OS -5.80482202 -38.95814916
OS -5.81499218 -38.95352636
OS -5.81591674 -38.9526018
OS -5.81869042 -38.95075268
OS -5.82238866 -38.947979
OS -5.82793602 -38.9433562
OS -5.83255882 -38.9387334
OS -5.83810618 -38.93226148
OS -5.84365354 -38.92578956
OS -5.84735178 -38.91746852
OS -5.84735178 -38.91654396
OS -5.8492009 -38.91284572
OS -5.85012546 -38.9063738
OS -5.85197458 -38.8971282
OS -5.8538237 -38.88510892
OS -5.85474826 -38.87771244
OS -5.85474826 -38.8693914
OS -5.85567282 -38.85922124
OS -5.85659738 -38.84905108
OS -5.85659738 -38.83795636
OS -5.85659738 -38.82501252
OS -5.85659738 -38.55689012
OS -5.91484466 -38.55689012
OS -5.91484466 -38.49586916
OS -5.85659738 -38.49586916
OS -5.85659738 -38.38122372
OS -5.77800978 -38.33407116
OS -5.77800978 -38.49586916
OE
OB -1.80517546 -38.48662356 I
OS -1.7950053 -38.48847268
OS -1.78298602 -38.49217092
OS -1.77004218 -38.49679372
OS -1.75524922 -38.50326564
OS -1.7395317 -38.51158668
OS -1.76819306 -38.58370236
OS -1.76911762 -38.5827778
OS -1.77281586 -38.58092868
OS -1.77836322 -38.578155
OS -1.7857597 -38.57538132
OS -1.79408074 -38.57260764
OS -1.8042509 -38.56983396
OS -1.81442106 -38.56798484
OS -1.82459122 -38.56706028
OS -1.82921402 -38.56706028
OS -1.83383682 -38.56798484
OS -1.84030874 -38.5689094
OS -1.84678066 -38.57075852
OS -1.8551017 -38.5735322
OS -1.86342274 -38.57723044
OS -1.87081922 -38.5827778
OS -1.87174378 -38.58370236
OS -1.87451746 -38.58555148
OS -1.87729114 -38.58924972
OS -1.88191394 -38.59387252
OS -1.88653674 -38.60034444
OS -1.89115954 -38.60774092
OS -1.89578234 -38.61606196
OS -1.89948058 -38.62623212
OS -1.90040514 -38.62808124
OS -1.9013297 -38.6336286
OS -1.90317882 -38.64194964
OS -1.9059525 -38.65304436
OS -1.90872618 -38.66691276
OS -1.9105753 -38.68263028
OS -1.91149986 -38.69927236
OS -1.91242442 -38.71776356
OS -1.91242442 -38.95999828
OS -1.99101202 -38.95999828
OS -1.99101202 -38.49586916
OS -1.9198209 -38.49586916
OS -1.9198209 -38.56613572
OS -1.91889634 -38.56521116
OS -1.9151981 -38.55873924
OS -1.9105753 -38.5504182
OS -1.90317882 -38.54024804
OS -1.89578234 -38.53007788
OS -1.8874613 -38.51898316
OS -1.87914026 -38.50973756
OS -1.87081922 -38.50234108
OS -1.86989466 -38.50141652
OS -1.86712098 -38.4995674
OS -1.86157362 -38.49679372
OS -1.85602626 -38.49402004
OS -1.84862978 -38.49124636
OS -1.83938418 -38.48847268
OS -1.83013858 -38.48662356
OS -1.81996842 -38.485699
OS -1.8134965 -38.485699
OS -1.80517546 -38.48662356
OE
OB -4.90337602 -38.48662356 I
OS -4.8969041 -38.48754812
OS -4.8830357 -38.48939724
OS -4.86639362 -38.49309548
OS -4.84882698 -38.49864284
OS -4.83126034 -38.50696388
OS -4.8136937 -38.51713404
OS -4.81276914 -38.51713404
OS -4.81184458 -38.51898316
OS -4.80629722 -38.5226814
OS -4.79797618 -38.53007788
OS -4.78780602 -38.53932348
OS -4.7767113 -38.55134276
OS -4.76561658 -38.56613572
OS -4.75452186 -38.58370236
OS -4.74527626 -38.60311812
OS -4.74527626 -38.60404268
OS -4.7443517 -38.6058918
OS -4.74342714 -38.60866548
OS -4.74157802 -38.61236372
OS -4.7397289 -38.61791108
OS -4.73787978 -38.624383
OS -4.73325698 -38.63917596
OS -4.72863418 -38.65766716
OS -4.72493594 -38.67800748
OS -4.72216226 -38.70112148
OS -4.7212377 -38.72516004
OS -4.7212377 -38.7260846
OS -4.7212377 -38.72793372
OS -4.7212377 -38.73163196
OS -4.7212377 -38.73717932
OS -4.72216226 -38.74365124
OS -4.72216226 -38.75104772
OS -4.72401138 -38.7676898
OS -4.72770962 -38.78803012
OS -4.73233242 -38.809295
OS -4.73880434 -38.83148444
OS -4.74712538 -38.85367388
OS -4.74712538 -38.85459844
OS -4.74804994 -38.85644756
OS -4.74989906 -38.85922124
OS -4.75174818 -38.86291948
OS -4.7582201 -38.87308964
OS -4.76654114 -38.88603348
OS -4.7767113 -38.89990188
OS -4.78965514 -38.91377028
OS -4.8044481 -38.92763868
OS -4.82201474 -38.94058252
OS -4.8229393 -38.94058252
OS -4.82386386 -38.94150708
OS -4.82663754 -38.9433562
OS -4.83033578 -38.94520532
OS -4.83958138 -38.94982812
OS -4.85252522 -38.95537548
OS -4.86824274 -38.96092284
OS -4.88488482 -38.96554564
OS -4.90430058 -38.96924388
OS -4.92371634 -38.97016844
OS -4.93018826 -38.97016844
OS -4.93758474 -38.96924388
OS -4.94683034 -38.96831932
OS -4.95792506 -38.9664702
OS -4.96994434 -38.96369652
OS -4.98196362 -38.95999828
OS -4.9939829 -38.95445092
OS -4.99490746 -38.95352636
OS -4.99953026 -38.95167724
OS -5.00507762 -38.947979
OS -5.0124741 -38.94243164
OS -5.01987058 -38.93688428
OS -5.02911618 -38.9294878
OS -5.03743722 -38.92116676
OS -5.0448337 -38.91192116
OS -5.0448337 -39.1375138
OS -5.1234213 -39.1375138
OS -5.1234213 -38.49586916
OS -5.05223018 -38.49586916
OS -5.05223018 -38.55689012
OS -5.05130562 -38.555041
OS -5.04760738 -38.55134276
OS -5.04298458 -38.54487084
OS -5.0355881 -38.53747436
OS -5.02726706 -38.52822876
OS -5.01802146 -38.51990772
OS -5.00692674 -38.51158668
OS -4.99583202 -38.5041902
OS -4.9939829 -38.50326564
OS -4.99028466 -38.50141652
OS -4.98288818 -38.49864284
OS -4.97364258 -38.4949446
OS -4.96254786 -38.49124636
OS -4.94960402 -38.48847268
OS -4.93481106 -38.48662356
OS -4.91816898 -38.485699
OS -4.90799882 -38.485699
OS -4.90337602 -38.48662356
OE
OB -5.41743138 -38.48662356 I
OS -5.40911034 -38.48754812
OS -5.39986474 -38.48939724
OS -5.38969458 -38.49124636
OS -5.3776753 -38.49309548
OS -5.35271218 -38.50141652
OS -5.33976834 -38.50603932
OS -5.3268245 -38.51251124
OS -5.31388066 -38.51898316
OS -5.30093682 -38.52822876
OS -5.28891754 -38.53747436
OS -5.27689826 -38.54856908
OS -5.2759737 -38.54949364
OS -5.27412458 -38.55134276
OS -5.2713509 -38.555041
OS -5.26765266 -38.5596638
OS -5.26302986 -38.56613572
OS -5.2574825 -38.57445676
OS -5.25193514 -38.58370236
OS -5.24638778 -38.59387252
OS -5.24084042 -38.60496724
OS -5.23529306 -38.61883564
OS -5.2297457 -38.63270404
OS -5.2251229 -38.64842156
OS -5.22142466 -38.66506364
OS -5.21865098 -38.68263028
OS -5.21680186 -38.70112148
OS -5.2158773 -38.7214618
OS -5.2158773 -38.72238636
OS -5.2158773 -38.72516004
OS -5.2158773 -38.72978284
OS -5.2158773 -38.73625476
OS -5.21680186 -38.74365124
OS -5.21772642 -38.75289684
OS -5.21772642 -38.76214244
OS -5.21957554 -38.7723126
OS -5.22234922 -38.7954266
OS -5.22789658 -38.8185406
OS -5.2343685 -38.8416546
OS -5.2436141 -38.86291948
OS -5.2436141 -38.86384404
OS -5.24453866 -38.8647686
OS -5.24638778 -38.86754228
OS -5.2482369 -38.87124052
OS -5.25470882 -38.88048612
OS -5.26302986 -38.89158084
OS -5.27412458 -38.90452468
OS -5.28799298 -38.91746852
OS -5.3037105 -38.93041236
OS -5.3222017 -38.94243164
OS -5.32312626 -38.94243164
OS -5.32405082 -38.9433562
OS -5.3268245 -38.94520532
OS -5.3314473 -38.94705444
OS -5.3360701 -38.94890356
OS -5.34161746 -38.95075268
OS -5.35548586 -38.95630004
OS -5.37120338 -38.96092284
OS -5.39061914 -38.96554564
OS -5.41095946 -38.96924388
OS -5.4331489 -38.97016844
OS -5.4423945 -38.97016844
OS -5.44979098 -38.96924388
OS -5.45811202 -38.96831932
OS -5.46735762 -38.9664702
OS -5.47845234 -38.96462108
OS -5.48954706 -38.96277196
OS -5.51451018 -38.95537548
OS -5.52837858 -38.94982812
OS -5.54132242 -38.94428076
OS -5.55426626 -38.93688428
OS -5.5672101 -38.92856324
OS -5.57922938 -38.91931764
OS -5.59124866 -38.90822292
OS -5.59217322 -38.90729836
OS -5.59402234 -38.90544924
OS -5.59679602 -38.901751
OS -5.60049426 -38.89620364
OS -5.60511706 -38.88973172
OS -5.60973986 -38.88233524
OS -5.61528722 -38.87308964
OS -5.62083458 -38.86199492
OS -5.62638194 -38.84997564
OS -5.6319293 -38.83610724
OS -5.6365521 -38.82131428
OS -5.6411749 -38.80559676
OS -5.64487314 -38.78803012
OS -5.64764682 -38.76953892
OS -5.64949594 -38.7491986
OS -5.6504205 -38.72793372
OS -5.6504205 -38.7260846
OS -5.6504205 -38.72238636
OS -5.64949594 -38.71591444
OS -5.64949594 -38.70666884
OS -5.64857138 -38.69649868
OS -5.64672226 -38.68355484
OS -5.64487314 -38.670611
OS -5.6411749 -38.65581804
OS -5.63747666 -38.64102508
OS -5.63285386 -38.62530756
OS -5.6273065 -38.60866548
OS -5.61991002 -38.59294796
OS -5.61251354 -38.578155
OS -5.60234338 -38.56336204
OS -5.59217322 -38.54949364
OS -5.57922938 -38.53747436
OS -5.57830482 -38.5365498
OS -5.5764557 -38.53562524
OS -5.57275746 -38.53285156
OS -5.56813466 -38.52915332
OS -5.5625873 -38.52545508
OS -5.55519082 -38.52083228
OS -5.54779434 -38.51620948
OS -5.53854874 -38.51158668
OS -5.52837858 -38.50696388
OS -5.51728386 -38.50234108
OS -5.49232074 -38.49402004
OS -5.46365938 -38.48754812
OS -5.44886642 -38.48662356
OS -5.4331489 -38.485699
OS -5.4239033 -38.485699
OS -5.41743138 -38.48662356
OE
OB -2.29704138 -38.5504182 H
OS -2.30258874 -38.5504182
OS -2.30628698 -38.55134276
OS -2.31645714 -38.55226732
OS -2.32847642 -38.555041
OS -2.34326938 -38.5596638
OS -2.3589869 -38.56613572
OS -2.37377986 -38.57538132
OS -2.38857282 -38.5874006
OS -2.39042194 -38.58924972
OS -2.39412018 -38.59387252
OS -2.4005921 -38.60219356
OS -2.40706402 -38.61328828
OS -2.4144605 -38.62623212
OS -2.42093242 -38.6428742
OS -2.42647978 -38.66228996
OS -2.42925346 -38.68355484
OS -2.1694521 -38.68355484
OS -2.1694521 -38.68263028
OS -2.1694521 -38.68078116
OS -2.17037666 -38.67800748
OS -2.17037666 -38.67430924
OS -2.17222578 -38.66321452
OS -2.17499946 -38.65119524
OS -2.17962226 -38.63640228
OS -2.18424506 -38.62253388
OS -2.19164154 -38.60866548
OS -2.19996258 -38.5966462
OS -2.19996258 -38.59572164
OS -2.2018117 -38.59479708
OS -2.2064345 -38.58924972
OS -2.21475554 -38.58185324
OS -2.22585026 -38.5735322
OS -2.23971866 -38.56521116
OS -2.25636074 -38.55781468
OS -2.2757765 -38.55226732
OS -2.28594666 -38.55134276
OS -2.29704138 -38.5504182
OE
OB -4.92556546 -38.54764452 H
OS -4.93018826 -38.54764452
OS -4.9338865 -38.54856908
OS -4.9431321 -38.5504182
OS -4.95515138 -38.55319188
OS -4.96901978 -38.55873924
OS -4.98381274 -38.56706028
OS -4.99213378 -38.57260764
OS -4.99953026 -38.57907956
OS -5.00692674 -38.58647604
OS -5.01432322 -38.59479708
OS -5.01432322 -38.59572164
OS -5.01617234 -38.5966462
OS -5.01802146 -38.59941988
OS -5.01987058 -38.60311812
OS -5.02264426 -38.60866548
OS -5.0263425 -38.61421284
OS -5.03004074 -38.62160932
OS -5.03281442 -38.6290058
OS -5.03651266 -38.6382514
OS -5.0402109 -38.64842156
OS -5.04298458 -38.65951628
OS -5.04668282 -38.67153556
OS -5.04853194 -38.68540396
OS -5.05038106 -38.69927236
OS -5.05223018 -38.71406532
OS -5.05223018 -38.7307074
OS -5.05223018 -38.73163196
OS -5.05223018 -38.73440564
OS -5.05223018 -38.73902844
OS -5.05130562 -38.74550036
OS -5.05130562 -38.75289684
OS -5.05038106 -38.76121788
OS -5.04760738 -38.78063364
OS -5.04298458 -38.80282308
OS -5.03743722 -38.82408796
OS -5.02819162 -38.84535284
OS -5.02264426 -38.85459844
OS -5.01617234 -38.86291948
OS -5.01432322 -38.8647686
OS -5.00970042 -38.8693914
OS -5.00230394 -38.87678788
OS -4.99213378 -38.88418436
OS -4.97918994 -38.89158084
OS -4.96439698 -38.89897732
OS -4.9477549 -38.90360012
OS -4.9385093 -38.90452468
OS -4.9292637 -38.90544924
OS -4.92371634 -38.90544924
OS -4.9200181 -38.90452468
OS -4.9107725 -38.90267556
OS -4.89782866 -38.89990188
OS -4.88396026 -38.89435452
OS -4.8691673 -38.88695804
OS -4.85437434 -38.87586332
OS -4.84697786 -38.8693914
OS -4.83958138 -38.86199492
OS -4.83958138 -38.86107036
OS -4.83773226 -38.8601458
OS -4.83588314 -38.85737212
OS -4.83403402 -38.85367388
OS -4.83033578 -38.84905108
OS -4.8275621 -38.84257916
OS -4.82386386 -38.83610724
OS -4.82016562 -38.8277862
OS -4.81739194 -38.81946516
OS -4.8136937 -38.80837044
OS -4.80999546 -38.79727572
OS -4.80722178 -38.78525644
OS -4.80537266 -38.77138804
OS -4.80352354 -38.75659508
OS -4.80167442 -38.74087756
OS -4.80167442 -38.72423548
OS -4.80167442 -38.72331092
OS -4.80167442 -38.72053724
OS -4.80167442 -38.71591444
OS -4.80259898 -38.70944252
OS -4.80259898 -38.70204604
OS -4.80352354 -38.693725
OS -4.80629722 -38.67430924
OS -4.81092002 -38.65304436
OS -4.81739194 -38.63177948
OS -4.82663754 -38.6105146
OS -4.8321849 -38.60034444
OS -4.83865682 -38.5920234
OS -4.83865682 -38.59109884
OS -4.84050594 -38.59017428
OS -4.84512874 -38.58462692
OS -4.85252522 -38.578155
OS -4.86269538 -38.56983396
OS -4.87563922 -38.56151292
OS -4.89043218 -38.55411644
OS -4.90707426 -38.54949364
OS -4.91631986 -38.54856908
OS -4.92556546 -38.54764452
OE
OB -5.4331489 -38.5504182 H
OS -5.43869626 -38.5504182
OS -5.44331906 -38.55134276
OS -5.45348922 -38.55226732
OS -5.46735762 -38.55596556
OS -5.48307514 -38.56151292
OS -5.49971722 -38.5689094
OS -5.51543474 -38.58000412
OS -5.52375578 -38.5874006
OS -5.53115226 -38.59479708
OS -5.53115226 -38.59572164
OS -5.53300138 -38.5966462
OS -5.5348505 -38.59941988
OS -5.53762418 -38.60311812
OS -5.54039786 -38.60774092
OS -5.54317154 -38.61328828
OS -5.54686978 -38.62068476
OS -5.55056802 -38.62808124
OS -5.55426626 -38.63732684
OS -5.5579645 -38.64657244
OS -5.56073818 -38.65766716
OS -5.56351186 -38.66968644
OS -5.56628554 -38.68263028
OS -5.56813466 -38.69649868
OS -5.56905922 -38.7122162
OS -5.56998378 -38.72793372
OS -5.56998378 -38.72885828
OS -5.56998378 -38.73163196
OS -5.56998378 -38.73625476
OS -5.56905922 -38.74272668
OS -5.56905922 -38.75012316
OS -5.56813466 -38.7584442
OS -5.56536098 -38.77785996
OS -5.56073818 -38.8000494
OS -5.5533417 -38.82223884
OS -5.5440961 -38.84350372
OS -5.53762418 -38.85274932
OS -5.53115226 -38.86199492
OS -5.5302277 -38.86199492
OS -5.52930314 -38.86384404
OS -5.52375578 -38.86846684
OS -5.51543474 -38.87586332
OS -5.50434002 -38.8832598
OS -5.49047162 -38.89158084
OS -5.47382954 -38.89897732
OS -5.45441378 -38.90360012
OS -5.44424362 -38.90452468
OS -5.4331489 -38.90544924
OS -5.42760154 -38.90544924
OS -5.42297874 -38.90452468
OS -5.41280858 -38.90267556
OS -5.39894018 -38.89990188
OS -5.38414722 -38.89435452
OS -5.36750514 -38.88695804
OS -5.35178762 -38.87586332
OS -5.34346658 -38.86846684
OS -5.3360701 -38.86107036
OS -5.33514554 -38.8601458
OS -5.33422098 -38.85922124
OS -5.33237186 -38.85644756
OS -5.32959818 -38.85274932
OS -5.3268245 -38.84812652
OS -5.32312626 -38.84257916
OS -5.31942802 -38.83518268
OS -5.31572978 -38.8277862
OS -5.31203154 -38.8185406
OS -5.30925786 -38.80837044
OS -5.30555962 -38.79727572
OS -5.30278594 -38.78525644
OS -5.30001226 -38.77138804
OS -5.29816314 -38.75751964
OS -5.29631402 -38.74180212
OS -5.29631402 -38.72516004
OS -5.29631402 -38.72423548
OS -5.29631402 -38.7214618
OS -5.29631402 -38.716839
OS -5.29723858 -38.71129164
OS -5.29723858 -38.70389516
OS -5.29816314 -38.69557412
OS -5.30093682 -38.67615836
OS -5.30555962 -38.65581804
OS -5.3129561 -38.6336286
OS -5.32312626 -38.61328828
OS -5.32867362 -38.60311812
OS -5.3360701 -38.59479708
OS -5.3360701 -38.59387252
OS -5.33791922 -38.59294796
OS -5.34346658 -38.5874006
OS -5.35178762 -38.58092868
OS -5.36288234 -38.57260764
OS -5.37675074 -38.5642866
OS -5.39339282 -38.55689012
OS -5.41188402 -38.55226732
OS -5.42205418 -38.55134276
OS -5.4331489 -38.5504182
OE
OB -2.81109674 -38.5504182 H
OS -2.81571954 -38.5504182
OS -2.81941778 -38.55134276
OS -2.82958794 -38.55226732
OS -2.84160722 -38.55596556
OS -2.85547562 -38.56058836
OS -2.87026858 -38.5689094
OS -2.88506154 -38.57907956
OS -2.89245802 -38.58647604
OS -2.89892994 -38.59387252
OS -2.89892994 -38.59479708
OS -2.90077906 -38.59572164
OS -2.90170362 -38.59849532
OS -2.9044773 -38.60219356
OS -2.90725098 -38.60681636
OS -2.91002466 -38.61236372
OS -2.91279834 -38.61883564
OS -2.91649658 -38.62623212
OS -2.92019482 -38.63547772
OS -2.9229685 -38.64564788
OS -2.92574218 -38.6567426
OS -2.92851586 -38.66876188
OS -2.93036498 -38.68170572
OS -2.9322141 -38.69649868
OS -2.93406322 -38.7122162
OS -2.93406322 -38.72885828
OS -2.93406322 -38.72978284
OS -2.93406322 -38.73255652
OS -2.93406322 -38.73717932
OS -2.93313866 -38.74365124
OS -2.93313866 -38.75104772
OS -2.9322141 -38.75936876
OS -2.92944042 -38.77878452
OS -2.92481762 -38.8000494
OS -2.9183457 -38.82223884
OS -2.9091001 -38.84350372
OS -2.90355274 -38.85274932
OS -2.89708082 -38.86199492
OS -2.89615626 -38.86199492
OS -2.8952317 -38.86384404
OS -2.8906089 -38.86846684
OS -2.88228786 -38.87586332
OS -2.8721177 -38.8832598
OS -2.85917386 -38.89158084
OS -2.84345634 -38.89897732
OS -2.82681426 -38.90360012
OS -2.81756866 -38.90452468
OS -2.80832306 -38.90544924
OS -2.80370026 -38.90544924
OS -2.80000202 -38.90452468
OS -2.78983186 -38.90360012
OS -2.77781258 -38.89990188
OS -2.76394418 -38.89527908
OS -2.74915122 -38.8878826
OS -2.73435826 -38.87771244
OS -2.72696178 -38.87124052
OS -2.72048986 -38.86384404
OS -2.72048986 -38.86291948
OS -2.71864074 -38.86199492
OS -2.71679162 -38.85922124
OS -2.7149425 -38.855523
OS -2.71216882 -38.8509002
OS -2.70847058 -38.8462774
OS -2.7056969 -38.83888092
OS -2.70199866 -38.83148444
OS -2.69830042 -38.8231634
OS -2.69552674 -38.8139178
OS -2.6918285 -38.80282308
OS -2.68905482 -38.79172836
OS -2.6872057 -38.77878452
OS -2.68535658 -38.76584068
OS -2.68350746 -38.75104772
OS -2.68350746 -38.7353302
OS -2.68350746 -38.73440564
OS -2.68350746 -38.7307074
OS -2.68350746 -38.7260846
OS -2.68443202 -38.71961268
OS -2.68443202 -38.7122162
OS -2.68535658 -38.7029706
OS -2.68628114 -38.69280044
OS -2.68813026 -38.68170572
OS -2.69275306 -38.65951628
OS -2.69922498 -38.63640228
OS -2.70847058 -38.61421284
OS -2.71401794 -38.60496724
OS -2.72048986 -38.59572164
OS -2.72048986 -38.59479708
OS -2.72233898 -38.59387252
OS -2.72696178 -38.58832516
OS -2.73528282 -38.58092868
OS -2.74545298 -38.57260764
OS -2.75839682 -38.5642866
OS -2.77411434 -38.55781468
OS -2.79168098 -38.55226732
OS -2.80092658 -38.55134276
OS -2.81109674 -38.5504182
OE
OB -3.49342202 -38.5504182 H
OS -3.49896938 -38.5504182
OS -3.50359218 -38.55134276
OS -3.51376234 -38.55226732
OS -3.52763074 -38.55596556
OS -3.54334826 -38.56151292
OS -3.55999034 -38.5689094
OS -3.57570786 -38.58000412
OS -3.5840289 -38.5874006
OS -3.59142538 -38.59479708
OS -3.59142538 -38.59572164
OS -3.5932745 -38.5966462
OS -3.59512362 -38.59941988
OS -3.5978973 -38.60311812
OS -3.60067098 -38.60774092
OS -3.60344466 -38.61328828
OS -3.6071429 -38.62068476
OS -3.61084114 -38.62808124
OS -3.61453938 -38.63732684
OS -3.61823762 -38.64657244
OS -3.6210113 -38.65766716
OS -3.62378498 -38.66968644
OS -3.62655866 -38.68263028
OS -3.62840778 -38.69649868
OS -3.62933234 -38.7122162
OS -3.6302569 -38.72793372
OS -3.6302569 -38.72885828
OS -3.6302569 -38.73163196
OS -3.6302569 -38.73625476
OS -3.62933234 -38.74272668
OS -3.62933234 -38.75012316
OS -3.62840778 -38.7584442
OS -3.6256341 -38.77785996
OS -3.6210113 -38.8000494
OS -3.61361482 -38.82223884
OS -3.60436922 -38.84350372
OS -3.5978973 -38.85274932
OS -3.59142538 -38.86199492
OS -3.59050082 -38.86199492
OS -3.58957626 -38.86384404
OS -3.5840289 -38.86846684
OS -3.57570786 -38.87586332
OS -3.56461314 -38.8832598
OS -3.55074474 -38.89158084
OS -3.53410266 -38.89897732
OS -3.5146869 -38.90360012
OS -3.50451674 -38.90452468
OS -3.49342202 -38.90544924
OS -3.48787466 -38.90544924
OS -3.48325186 -38.90452468
OS -3.4730817 -38.90267556
OS -3.4592133 -38.89990188
OS -3.44442034 -38.89435452
OS -3.42777826 -38.88695804
OS -3.41206074 -38.87586332
OS -3.4037397 -38.86846684
OS -3.39634322 -38.86107036
OS -3.39541866 -38.8601458
OS -3.3944941 -38.85922124
OS -3.39264498 -38.85644756
OS -3.3898713 -38.85274932
OS -3.38709762 -38.84812652
OS -3.38339938 -38.84257916
OS -3.37970114 -38.83518268
OS -3.3760029 -38.8277862
OS -3.37230466 -38.8185406
OS -3.36953098 -38.80837044
OS -3.36583274 -38.79727572
OS -3.36305906 -38.78525644
OS -3.36028538 -38.77138804
OS -3.35843626 -38.75751964
OS -3.35658714 -38.74180212
OS -3.35658714 -38.72516004
OS -3.35658714 -38.72423548
OS -3.35658714 -38.7214618
OS -3.35658714 -38.716839
OS -3.3575117 -38.71129164
OS -3.3575117 -38.70389516
OS -3.35843626 -38.69557412
OS -3.36120994 -38.67615836
OS -3.36583274 -38.65581804
OS -3.37322922 -38.6336286
OS -3.38339938 -38.61328828
OS -3.38894674 -38.60311812
OS -3.39634322 -38.59479708
OS -3.39634322 -38.59387252
OS -3.39819234 -38.59294796
OS -3.4037397 -38.5874006
OS -3.41206074 -38.58092868
OS -3.42315546 -38.57260764
OS -3.43702386 -38.5642866
OS -3.45366594 -38.55689012
OS -3.47215714 -38.55226732
OS -3.4823273 -38.55134276
OS -3.49342202 -38.5504182
OE
SE
S P 0
OB -4.66714078 -36.5016923 I
OS -4.65465922 -36.5016923
OS -4.62553558 -36.50307914
OS -4.5950251 -36.50723966
OS -4.56174094 -36.51140018
OS -4.53123046 -36.51833438
OS -4.51597522 -36.5224949
OS -4.50349366 -36.52665542
OS -4.50210682 -36.52665542
OS -4.50071998 -36.52804226
OS -4.49239894 -36.53220278
OS -4.47991738 -36.53775014
OS -4.46466214 -36.54745802
OS -4.44802006 -36.55993958
OS -4.42999114 -36.57658166
OS -4.41334906 -36.59599742
OS -4.39670698 -36.61818686
OS -4.39670698 -36.6195737
OS -4.39532014 -36.62096054
OS -4.38977278 -36.62928158
OS -4.38422542 -36.64314998
OS -4.37590438 -36.6611789
OS -4.36897018 -36.6819815
OS -4.36203598 -36.70694462
OS -4.35787546 -36.73329458
OS -4.35648862 -36.76241822
OS -4.35648862 -36.76380506
OS -4.35648862 -36.76657874
OS -4.35648862 -36.7721261
OS -4.35787546 -36.7790603
OS -4.35787546 -36.78876818
OS -4.3592623 -36.79847606
OS -4.36480966 -36.82205234
OS -4.3731307 -36.84978914
OS -4.38422542 -36.87891278
OS -4.4008675 -36.90803642
OS -4.41196222 -36.92190482
OS -4.42305694 -36.93577322
OS -4.42444378 -36.93716006
OS -4.42583062 -36.9385469
OS -4.42999114 -36.94270742
OS -4.4355385 -36.94686794
OS -4.4424727 -36.9524153
OS -4.45079374 -36.95796266
OS -4.46188846 -36.96489686
OS -4.47298318 -36.9732179
OS -4.48685158 -36.9801521
OS -4.50210682 -36.9870863
OS -4.5187489 -36.99540734
OS -4.53677782 -37.00234154
OS -4.55758042 -37.0078889
OS -4.57838302 -37.0148231
OS -4.6019593 -37.01898362
OS -4.62692242 -37.02314414
OS -4.62414874 -37.02453098
OS -4.61860138 -37.02730466
OS -4.61028034 -37.03285202
OS -4.59918562 -37.03839938
OS -4.5742225 -37.05365462
OS -4.56174094 -37.0633625
OS -4.55064622 -37.07168354
OS -4.54787254 -37.07445722
OS -4.54093834 -37.08139142
OS -4.52984362 -37.09248614
OS -4.51597522 -37.10635454
OS -4.50071998 -37.1257703
OS -4.48269106 -37.1465729
OS -4.46466214 -37.17153602
OS -4.44524638 -37.19927282
OS -4.28021242 -37.45999874
OS -4.43831218 -37.45999874
OS -4.56451462 -37.26029378
OS -4.56451462 -37.25890694
OS -4.5672883 -37.25613326
OS -4.57006198 -37.25197274
OS -4.5742225 -37.24642538
OS -4.58393038 -37.23117014
OS -4.59641194 -37.21175438
OS -4.61166718 -37.19095178
OS -4.62692242 -37.16876234
OS -4.64217766 -37.14795974
OS -4.65604606 -37.12854398
OS -4.6574329 -37.12715714
OS -4.66159342 -37.12160978
OS -4.66852762 -37.11328874
OS -4.6782355 -37.10358086
OS -4.6990381 -37.08277826
OS -4.71013282 -37.07307038
OS -4.72122754 -37.06474934
OS -4.72261438 -37.0633625
OS -4.72538806 -37.06197566
OS -4.73093542 -37.05920198
OS -4.73925646 -37.05504146
OS -4.7475775 -37.05088094
OS -4.75728538 -37.04672042
OS -4.77947482 -37.03978622
OS -4.78086166 -37.03978622
OS -4.78363534 -37.03839938
OS -4.7891827 -37.03839938
OS -4.7961169 -37.03701254
OS -4.80582478 -37.0356257
OS -4.8169195 -37.0356257
OS -4.83217474 -37.03423886
OS -4.99582186 -37.03423886
OS -4.99582186 -37.45999874
OS -5.12341114 -37.45999874
OS -5.12341114 -36.50030546
OS -4.6782355 -36.50030546
OS -4.66714078 -36.5016923
OE
OB -1.0100437 -37.45999874 I
OS -1.13208562 -37.45999874
OS -1.13208562 -36.65701838
OS -1.4122273 -37.45999874
OS -1.52594818 -37.45999874
OS -1.80331618 -36.64314998
OS -1.80331618 -37.45999874
OS -1.9253581 -37.45999874
OS -1.9253581 -36.50030546
OS -1.73536102 -36.50030546
OS -1.50791926 -37.1812439
OS -1.50791926 -37.18263074
OS -1.50653242 -37.18540442
OS -1.50514558 -37.18956494
OS -1.5023719 -37.19649914
OS -1.49682454 -37.21314122
OS -1.48989034 -37.23394382
OS -1.48295614 -37.2575201
OS -1.4746351 -37.28109638
OS -1.4677009 -37.30328582
OS -1.46215354 -37.32270158
OS -1.4607667 -37.3199279
OS -1.45937986 -37.3129937
OS -1.45521934 -37.30051214
OS -1.44967198 -37.28387006
OS -1.44273778 -37.26168062
OS -1.4330299 -37.23533066
OS -1.42332202 -37.20482018
OS -1.41084046 -37.16876234
OS -1.18062502 -36.50030546
OS -1.0100437 -36.50030546
OS -1.0100437 -37.45999874
OE
OB -2.02382374 -37.45999874 I
OS -2.1680551 -37.45999874
OS -2.28038914 -37.16876234
OS -2.68257274 -37.16876234
OS -2.78658574 -37.45999874
OS -2.92110922 -37.45999874
OS -2.55498346 -36.50030546
OS -2.41629946 -36.50030546
OS -2.02382374 -37.45999874
OE
OB -3.02928274 -37.45999874 I
OS -3.16103254 -37.45999874
OS -3.66306862 -36.70694462
OS -3.66306862 -37.45999874
OS -3.78511054 -37.45999874
OS -3.78511054 -36.50030546
OS -3.65474758 -36.50030546
OS -3.15132466 -37.25474642
OS -3.15132466 -36.50030546
OS -3.02928274 -36.50030546
OS -3.02928274 -37.45999874
OE
OB -5.3231161 -36.61402634 I
OS -5.89033366 -36.61402634
OS -5.89033366 -36.90664958
OS -5.35917394 -36.90664958
OS -5.35917394 -37.02037046
OS -5.89033366 -37.02037046
OS -5.89033366 -37.34627786
OS -5.30092666 -37.34627786
OS -5.30092666 -37.45999874
OS -6.01792294 -37.45999874
OS -6.01792294 -36.50030546
OS -5.3231161 -36.50030546
OS -5.3231161 -36.61402634
OE
OB -0.10721086 -36.61402634 I
OS -0.67442842 -36.61402634
OS -0.67442842 -36.90664958
OS -0.1432687 -36.90664958
OS -0.1432687 -37.02037046
OS -0.67442842 -37.02037046
OS -0.67442842 -37.34627786
OS -0.08502142 -37.34627786
OS -0.08502142 -37.45999874
OS -0.8020177 -37.45999874
OS -0.8020177 -36.50030546
OS -0.10721086 -36.50030546
OS -0.10721086 -36.61402634
OE
OB -8.43241138 -37.34627786 I
OS -7.95949894 -37.34627786
OS -7.95949894 -37.45999874
OS -8.56000066 -37.45999874
OS -8.56000066 -36.50030546
OS -8.43241138 -36.50030546
OS -8.43241138 -37.34627786
OE
OB -6.51718534 -37.05365462 I
OS -6.51718534 -37.45999874
OS -6.64477462 -37.45999874
OS -6.64477462 -37.05365462
OS -7.0150609 -36.50030546
OS -6.86112166 -36.50030546
OS -6.67251142 -36.79154186
OS -6.67251142 -36.7929287
OS -6.66973774 -36.79570238
OS -6.66696406 -36.7998629
OS -6.66419038 -36.80541026
OS -6.65864302 -36.81234446
OS -6.65309566 -36.8206655
OS -6.6406141 -36.8414681
OS -6.62535886 -36.86643122
OS -6.60871678 -36.89416802
OS -6.59068786 -36.92329166
OS -6.57404578 -36.95380214
OS -6.57404578 -36.9524153
OS -6.57265894 -36.94964162
OS -6.56988526 -36.9454811
OS -6.56572474 -36.93993374
OS -6.56156422 -36.93299954
OS -6.55601686 -36.9246785
OS -6.5435353 -36.9038759
OS -6.52828006 -36.87891278
OS -6.51025114 -36.84978914
OS -6.48944854 -36.81789182
OS -6.4672591 -36.78322082
OS -6.28280938 -36.50030546
OS -6.1344175 -36.50030546
OS -6.51718534 -37.05365462
OE
OB -7.01644774 -37.45999874 I
OS -7.1606791 -37.45999874
OS -7.27301314 -37.16876234
OS -7.67519674 -37.16876234
OS -7.77920974 -37.45999874
OS -7.91373322 -37.45999874
OS -7.54760746 -36.50030546
OS -7.40892346 -36.50030546
OS -7.01644774 -37.45999874
OE
OB -7.48103914 -36.60015794 H
OS -7.48103914 -36.60154478
OS -7.48242598 -36.60431846
OS -7.48242598 -36.60986582
OS -7.48519966 -36.61541318
OS -7.4865865 -36.62512106
OS -7.48936018 -36.63482894
OS -7.49490754 -36.65840522
OS -7.50184174 -36.68614202
OS -7.51154962 -36.7166525
OS -7.5212575 -36.74993666
OS -7.53373906 -36.78460766
OS -7.63775206 -37.06474934
OS -7.3132315 -37.06474934
OS -7.41308398 -36.80124974
OS -7.41308398 -36.7998629
OS -7.41447082 -36.79570238
OS -7.4172445 -36.78876818
OS -7.42001818 -36.78044714
OS -7.4241787 -36.77073926
OS -7.42833922 -36.7582577
OS -7.43249974 -36.7443893
OS -7.4380471 -36.7305209
OS -7.44914182 -36.69862358
OS -7.46023654 -36.66533942
OS -7.47133126 -36.63205526
OS -7.48103914 -36.60015794
OE
OB -4.69349074 -36.60709214 H
OS -4.99582186 -36.60709214
OS -4.99582186 -36.9246785
OS -4.71013282 -36.9246785
OS -4.69349074 -36.92329166
OS -4.67407498 -36.92190482
OS -4.65188554 -36.92051798
OS -4.6296961 -36.9177443
OS -4.60750666 -36.91358378
OS -4.5880909 -36.90803642
OS -4.58531722 -36.90664958
OS -4.57976986 -36.9038759
OS -4.57144882 -36.89971538
OS -4.5603541 -36.89416802
OS -4.54787254 -36.88584698
OS -4.53539098 -36.8761391
OS -4.52290942 -36.86365754
OS -4.51320154 -36.84978914
OS -4.5118147 -36.8484023
OS -4.50904102 -36.84285494
OS -4.5048805 -36.8345339
OS -4.49933314 -36.82343918
OS -4.49517262 -36.81095762
OS -4.4910121 -36.79708922
OS -4.48823842 -36.78044714
OS -4.48685158 -36.76380506
OS -4.48685158 -36.76241822
OS -4.48685158 -36.76103138
OS -4.48823842 -36.75271034
OS -4.48962526 -36.74022878
OS -4.49239894 -36.7235867
OS -4.49933314 -36.70694462
OS -4.50765418 -36.68752886
OS -4.52013574 -36.66949994
OS -4.53677782 -36.65147102
OS -4.5395515 -36.65008418
OS -4.5464857 -36.64453682
OS -4.55758042 -36.63760262
OS -4.57560934 -36.62928158
OS -4.59641194 -36.62096054
OS -4.62414874 -36.61402634
OS -4.65604606 -36.60847898
OS -4.69349074 -36.60709214
OE
OB -2.48841514 -36.60015794 H
OS -2.48841514 -36.60154478
OS -2.48980198 -36.60431846
OS -2.48980198 -36.60986582
OS -2.49257566 -36.61541318
OS -2.4939625 -36.62512106
OS -2.49673618 -36.63482894
OS -2.50228354 -36.65840522
OS -2.50921774 -36.68614202
OS -2.51892562 -36.7166525
OS -2.5286335 -36.74993666
OS -2.54111506 -36.78460766
OS -2.64512806 -37.06474934
OS -2.3206075 -37.06474934
OS -2.42045998 -36.80124974
OS -2.42045998 -36.7998629
OS -2.42184682 -36.79570238
OS -2.4246205 -36.78876818
OS -2.42739418 -36.78044714
OS -2.4315547 -36.77073926
OS -2.43571522 -36.7582577
OS -2.43987574 -36.7443893
OS -2.4454231 -36.7305209
OS -2.45651782 -36.69862358
OS -2.46761254 -36.66533942
OS -2.47870726 -36.63205526
OS -2.48841514 -36.60015794
OE
SE
S P 0
OB 35.73690338 -37.45999874 I
OS 35.61486146 -37.45999874
OS 35.61486146 -36.65701838
OS 35.33471978 -37.45999874
OS 35.2209989 -37.45999874
OS 34.9436309 -36.64314998
OS 34.9436309 -37.45999874
OS 34.82158898 -37.45999874
OS 34.82158898 -36.50030546
OS 35.01158606 -36.50030546
OS 35.23902782 -37.1812439
OS 35.23902782 -37.18263074
OS 35.24041466 -37.18540442
OS 35.2418015 -37.18956494
OS 35.24457518 -37.19649914
OS 35.25012254 -37.21314122
OS 35.25705674 -37.23394382
OS 35.26399094 -37.2575201
OS 35.27231198 -37.28109638
OS 35.27924618 -37.30328582
OS 35.28479354 -37.32270158
OS 35.28618038 -37.3199279
OS 35.28756722 -37.3129937
OS 35.29172774 -37.30051214
OS 35.2972751 -37.28387006
OS 35.3042093 -37.26168062
OS 35.31391718 -37.23533066
OS 35.32362506 -37.20482018
OS 35.33610662 -37.16876234
OS 35.56632206 -36.50030546
OS 35.73690338 -36.50030546
OS 35.73690338 -37.45999874
OE
OB 34.61356298 -37.05504146 I
OS 34.61356298 -37.0564283
OS 34.61356298 -37.06197566
OS 34.61356298 -37.06890986
OS 34.61356298 -37.07861774
OS 34.61217614 -37.0910993
OS 34.61217614 -37.1049677
OS 34.6107893 -37.12160978
OS 34.60940246 -37.13825186
OS 34.60524194 -37.17569654
OS 34.59969458 -37.21452806
OS 34.59137354 -37.25197274
OS 34.58582618 -37.27000166
OS 34.58027882 -37.28664374
OS 34.58027882 -37.28803058
OS 34.57889198 -37.29080426
OS 34.5761183 -37.29496478
OS 34.57334462 -37.30051214
OS 34.56502358 -37.31576738
OS 34.55254202 -37.33518314
OS 34.53589994 -37.35737258
OS 34.51648418 -37.37956202
OS 34.49152106 -37.4031383
OS 34.46101058 -37.4239409
OS 34.45962374 -37.4239409
OS 34.45685006 -37.42671458
OS 34.45268954 -37.42810142
OS 34.44575534 -37.43226194
OS 34.4374343 -37.43642246
OS 34.42633958 -37.44058298
OS 34.41524486 -37.4447435
OS 34.40137646 -37.45029086
OS 34.38612122 -37.45583822
OS 34.36947914 -37.45999874
OS 34.35145022 -37.46415926
OS 34.33064762 -37.46831978
OS 34.30984502 -37.47109346
OS 34.28765558 -37.47386714
OS 34.23772934 -37.47664082
OS 34.22524778 -37.47664082
OS 34.2155399 -37.47525398
OS 34.20444518 -37.47525398
OS 34.19057678 -37.47386714
OS 34.17532154 -37.4724803
OS 34.1600663 -37.47109346
OS 34.1253953 -37.4655461
OS 34.08795062 -37.45722506
OS 34.05189278 -37.44613034
OS 34.01722178 -37.4308751
OS 34.01583494 -37.4308751
OS 34.01306126 -37.42810142
OS 34.00890074 -37.42532774
OS 34.00335338 -37.42255406
OS 33.98809814 -37.41145934
OS 33.97006922 -37.3962041
OS 33.94926662 -37.37678834
OS 33.92985086 -37.3545989
OS 33.9104351 -37.3268621
OS 33.89517986 -37.29635162
OS 33.89517986 -37.29496478
OS 33.89379302 -37.2921911
OS 33.89240618 -37.28664374
OS 33.8896325 -37.27970954
OS 33.88685882 -37.2713885
OS 33.88408514 -37.26029378
OS 33.87992462 -37.24781222
OS 33.87715094 -37.23255698
OS 33.87437726 -37.2159149
OS 33.87021674 -37.19788598
OS 33.86744306 -37.17847022
OS 33.86466938 -37.15766762
OS 33.8618957 -37.13409134
OS 33.86050886 -37.10912822
OS 33.85912202 -37.08277826
OS 33.85912202 -37.05504146
OS 33.85912202 -36.50030546
OS 33.9867113 -36.50030546
OS 33.9867113 -37.05504146
OS 33.9867113 -37.0564283
OS 33.9867113 -37.06058882
OS 33.9867113 -37.06752302
OS 33.9867113 -37.07584406
OS 33.98809814 -37.08555194
OS 33.98809814 -37.0980335
OS 33.98948498 -37.12438346
OS 33.99225866 -37.15489394
OS 33.99641918 -37.18540442
OS 34.00196654 -37.21452806
OS 34.00474022 -37.22700962
OS 34.00890074 -37.23949118
OS 34.01028758 -37.24226486
OS 34.01306126 -37.24919906
OS 34.01999546 -37.25890694
OS 34.0283165 -37.27277534
OS 34.03802438 -37.28664374
OS 34.05189278 -37.30189898
OS 34.06853486 -37.31715422
OS 34.08795062 -37.32963578
OS 34.0907243 -37.33102262
OS 34.0976585 -37.33518314
OS 34.11014006 -37.33934366
OS 34.12678214 -37.34489102
OS 34.1461979 -37.35182522
OS 34.17116102 -37.35598574
OS 34.19751098 -37.36014626
OS 34.22663462 -37.3615331
OS 34.24050302 -37.3615331
OS 34.24882406 -37.36014626
OS 34.26130562 -37.36014626
OS 34.27378718 -37.35875942
OS 34.30429766 -37.35321206
OS 34.33758182 -37.34627786
OS 34.36947914 -37.33518314
OS 34.39998962 -37.3199279
OS 34.41385802 -37.31022002
OS 34.42633958 -37.2991253
OS 34.42772642 -37.29773846
OS 34.42911326 -37.29635162
OS 34.43188694 -37.2921911
OS 34.43604746 -37.28664374
OS 34.44020798 -37.2783227
OS 34.44575534 -37.27000166
OS 34.4513027 -37.2575201
OS 34.45685006 -37.24503854
OS 34.46239742 -37.2297833
OS 34.46655794 -37.21175438
OS 34.4721053 -37.19095178
OS 34.47626582 -37.16876234
OS 34.48042634 -37.14379922
OS 34.48320002 -37.11744926
OS 34.4859737 -37.08693878
OS 34.4859737 -37.05504146
OS 34.4859737 -36.50030546
OS 34.61356298 -36.50030546
OS 34.61356298 -37.05504146
OE
OB 33.64416182 -37.45999874 I
OS 33.51241202 -37.45999874
OS 33.01037594 -36.70694462
OS 33.01037594 -37.45999874
OS 32.88833402 -37.45999874
OS 32.88833402 -36.50030546
OS 33.01869698 -36.50030546
OS 33.5221199 -37.25474642
OS 33.5221199 -36.50030546
OS 33.64416182 -36.50030546
OS 33.64416182 -37.45999874
OE
OB 38.19022334 -36.5016923 I
OS 38.2027049 -36.5016923
OS 38.23182854 -36.50307914
OS 38.26233902 -36.50723966
OS 38.29562318 -36.51140018
OS 38.32613366 -36.51833438
OS 38.3413889 -36.5224949
OS 38.35387046 -36.52665542
OS 38.3552573 -36.52665542
OS 38.35664414 -36.52804226
OS 38.36496518 -36.53220278
OS 38.37744674 -36.53775014
OS 38.39270198 -36.54745802
OS 38.40934406 -36.55993958
OS 38.42737298 -36.57658166
OS 38.44401506 -36.59599742
OS 38.46065714 -36.61818686
OS 38.46065714 -36.6195737
OS 38.46204398 -36.62096054
OS 38.46759134 -36.62928158
OS 38.4731387 -36.64314998
OS 38.48145974 -36.6611789
OS 38.48839394 -36.6819815
OS 38.49532814 -36.70694462
OS 38.49948866 -36.73329458
OS 38.5008755 -36.76241822
OS 38.5008755 -36.76380506
OS 38.5008755 -36.76657874
OS 38.5008755 -36.7721261
OS 38.49948866 -36.7790603
OS 38.49948866 -36.78876818
OS 38.49810182 -36.79847606
OS 38.49255446 -36.82205234
OS 38.48423342 -36.84978914
OS 38.4731387 -36.87891278
OS 38.45649662 -36.90803642
OS 38.4454019 -36.92190482
OS 38.43430718 -36.93577322
OS 38.43292034 -36.93716006
OS 38.4315335 -36.9385469
OS 38.42737298 -36.94270742
OS 38.42182562 -36.94686794
OS 38.41489142 -36.9524153
OS 38.40657038 -36.95796266
OS 38.39547566 -36.96489686
OS 38.38438094 -36.9732179
OS 38.37051254 -36.9801521
OS 38.3552573 -36.9870863
OS 38.33861522 -36.99540734
OS 38.3205863 -37.00234154
OS 38.2997837 -37.0078889
OS 38.2789811 -37.0148231
OS 38.25540482 -37.01898362
OS 38.2304417 -37.02314414
OS 38.23321538 -37.02453098
OS 38.23876274 -37.02730466
OS 38.24708378 -37.03285202
OS 38.2581785 -37.03839938
OS 38.28314162 -37.05365462
OS 38.29562318 -37.0633625
OS 38.3067179 -37.07168354
OS 38.30949158 -37.07445722
OS 38.31642578 -37.08139142
OS 38.3275205 -37.09248614
OS 38.3413889 -37.10635454
OS 38.35664414 -37.1257703
OS 38.37467306 -37.1465729
OS 38.39270198 -37.17153602
OS 38.41211774 -37.19927282
OS 38.5771517 -37.45999874
OS 38.41905194 -37.45999874
OS 38.2928495 -37.26029378
OS 38.2928495 -37.25890694
OS 38.29007582 -37.25613326
OS 38.28730214 -37.25197274
OS 38.28314162 -37.24642538
OS 38.27343374 -37.23117014
OS 38.26095218 -37.21175438
OS 38.24569694 -37.19095178
OS 38.2304417 -37.16876234
OS 38.21518646 -37.14795974
OS 38.20131806 -37.12854398
OS 38.19993122 -37.12715714
OS 38.1957707 -37.12160978
OS 38.1888365 -37.11328874
OS 38.17912862 -37.10358086
OS 38.15832602 -37.08277826
OS 38.1472313 -37.07307038
OS 38.13613658 -37.06474934
OS 38.13474974 -37.0633625
OS 38.13197606 -37.06197566
OS 38.1264287 -37.05920198
OS 38.11810766 -37.05504146
OS 38.10978662 -37.05088094
OS 38.10007874 -37.04672042
OS 38.0778893 -37.03978622
OS 38.07650246 -37.03978622
OS 38.07372878 -37.03839938
OS 38.06818142 -37.03839938
OS 38.06124722 -37.03701254
OS 38.05153934 -37.0356257
OS 38.04044462 -37.0356257
OS 38.02518938 -37.03423886
OS 37.86154226 -37.03423886
OS 37.86154226 -37.45999874
OS 37.73395298 -37.45999874
OS 37.73395298 -36.50030546
OS 38.17912862 -36.50030546
OS 38.19022334 -36.5016923
OE
OB 37.53424802 -36.61402634 I
OS 36.96703046 -36.61402634
OS 36.96703046 -36.90664958
OS 37.49819018 -36.90664958
OS 37.49819018 -37.02037046
OS 36.96703046 -37.02037046
OS 36.96703046 -37.34627786
OS 37.55643746 -37.34627786
OS 37.55643746 -37.45999874
OS 36.83944118 -37.45999874
OS 36.83944118 -36.50030546
OS 37.53424802 -36.50030546
OS 37.53424802 -36.61402634
OE
OB 36.32492354 -36.5016923 I
OS 36.33601826 -36.5016923
OS 36.36098138 -36.50446598
OS 36.38871818 -36.50723966
OS 36.41784182 -36.51278702
OS 36.44696546 -36.51972122
OS 36.47331542 -36.5294291
OS 36.47470226 -36.5294291
OS 36.4760891 -36.53081594
OS 36.48441014 -36.53497646
OS 36.4968917 -36.54191066
OS 36.5107601 -36.55161854
OS 36.52740218 -36.5641001
OS 36.5454311 -36.57935534
OS 36.56207318 -36.5987711
OS 36.57732842 -36.6195737
OS 36.57871526 -36.62234738
OS 36.58287578 -36.63066842
OS 36.58980998 -36.64176314
OS 36.59674418 -36.65840522
OS 36.60367838 -36.67782098
OS 36.61061258 -36.69862358
OS 36.6147731 -36.72219986
OS 36.61615994 -36.74577614
OS 36.61615994 -36.74854982
OS 36.61615994 -36.75548402
OS 36.6147731 -36.76796558
OS 36.61199942 -36.78322082
OS 36.6078389 -36.80124974
OS 36.6009047 -36.8206655
OS 36.59258366 -36.84008126
OS 36.58148894 -36.86088386
OS 36.5801021 -36.86365754
OS 36.57594158 -36.8692049
OS 36.56762054 -36.88029962
OS 36.55652582 -36.89139434
OS 36.54265742 -36.90526274
OS 36.52601534 -36.92051798
OS 36.50521274 -36.93438638
OS 36.48163646 -36.94825478
OS 36.4830233 -36.94825478
OS 36.48579698 -36.94964162
OS 36.4899575 -36.95102846
OS 36.49550486 -36.95380214
OS 36.51214694 -36.9593495
OS 36.5315627 -36.96905738
OS 36.5523653 -36.98153894
OS 36.57594158 -36.99679418
OS 36.59674418 -37.0148231
OS 36.61615994 -37.03701254
OS 36.61754678 -37.03978622
OS 36.62309414 -37.04810726
OS 36.63141518 -37.06058882
OS 36.63973622 -37.0772309
OS 36.64805726 -37.09942034
OS 36.6563783 -37.12299662
OS 36.66192566 -37.15073342
OS 36.6633125 -37.1812439
OS 36.6633125 -37.18263074
OS 36.6633125 -37.18401758
OS 36.6633125 -37.19233862
OS 36.66192566 -37.20620702
OS 36.65915198 -37.2228491
OS 36.6563783 -37.24226486
OS 36.65083094 -37.26306746
OS 36.64389674 -37.2852569
OS 36.63418886 -37.30744634
OS 36.63280202 -37.31022002
OS 36.6286415 -37.31715422
OS 36.62309414 -37.3268621
OS 36.6147731 -37.3407305
OS 36.60367838 -37.3545989
OS 36.59258366 -37.36985414
OS 36.57871526 -37.38510938
OS 36.56346002 -37.39759094
OS 36.56207318 -37.39897778
OS 36.55652582 -37.4031383
OS 36.54681794 -37.40868566
OS 36.53433638 -37.41423302
OS 36.51908114 -37.42255406
OS 36.50105222 -37.4308751
OS 36.48163646 -37.4378093
OS 36.45806018 -37.4447435
OS 36.4552865 -37.4447435
OS 36.44696546 -37.44751718
OS 36.43309706 -37.44890402
OS 36.41506814 -37.4516777
OS 36.3928787 -37.45445138
OS 36.36652874 -37.45722506
OS 36.3374051 -37.4586119
OS 36.30412094 -37.45999874
OS 35.93799518 -37.45999874
OS 35.93799518 -36.50030546
OS 36.31521566 -36.50030546
OS 36.32492354 -36.5016923
OE
OB 32.3849111 -36.61402634 I
OS 32.06871158 -36.61402634
OS 32.06871158 -37.45999874
OS 31.9411223 -37.45999874
OS 31.9411223 -36.61402634
OS 31.62492278 -36.61402634
OS 31.62492278 -36.50030546
OS 32.3849111 -36.50030546
OS 32.3849111 -36.61402634
OE
OB 30.62639798 -37.45999874 I
OS 30.48216662 -37.45999874
OS 30.36983258 -37.16876234
OS 29.96764898 -37.16876234
OS 29.86363598 -37.45999874
OS 29.7291125 -37.45999874
OS 30.09523826 -36.50030546
OS 30.23392226 -36.50030546
OS 30.62639798 -37.45999874
OE
OB 29.3546657 -36.5016923 I
OS 29.37824198 -36.50307914
OS 29.4032051 -36.50446598
OS 29.42678138 -36.50723966
OS 29.44758398 -36.51001334
OS 29.45035766 -36.51001334
OS 29.46006554 -36.51278702
OS 29.4725471 -36.5155607
OS 29.48918918 -36.51972122
OS 29.5072181 -36.52665542
OS 29.52663386 -36.53497646
OS 29.54743646 -36.54468434
OS 29.56546538 -36.55577906
OS 29.56823906 -36.5571659
OS 29.57378642 -36.56132642
OS 29.58210746 -36.56964746
OS 29.59320218 -36.57935534
OS 29.60568374 -36.5918369
OS 29.6181653 -36.60847898
OS 29.6320337 -36.6265079
OS 29.64312842 -36.6473105
OS 29.64451526 -36.65008418
OS 29.64728894 -36.65701838
OS 29.6528363 -36.66949994
OS 29.65838366 -36.68614202
OS 29.66254418 -36.70555778
OS 29.66809154 -36.72774722
OS 29.67086522 -36.75271034
OS 29.67225206 -36.7790603
OS 29.67225206 -36.78044714
OS 29.67225206 -36.78460766
OS 29.67225206 -36.79015502
OS 29.67086522 -36.7998629
OS 29.66947838 -36.80957078
OS 29.66809154 -36.82205234
OS 29.66531786 -36.83592074
OS 29.66254418 -36.85117598
OS 29.6528363 -36.8830733
OS 29.64728894 -36.89971538
OS 29.6389679 -36.9177443
OS 29.62926002 -36.93577322
OS 29.61955214 -36.9524153
OS 29.60707058 -36.96905738
OS 29.59320218 -36.98569946
OS 29.59181534 -36.9870863
OS 29.58904166 -36.98985998
OS 29.58488114 -36.9940205
OS 29.57794694 -36.99818102
OS 29.5696259 -37.00511522
OS 29.55853118 -37.01204942
OS 29.54466278 -37.02037046
OS 29.52940754 -37.02730466
OS 29.51137862 -37.0356257
OS 29.49057602 -37.04394674
OS 29.46838658 -37.05088094
OS 29.44203662 -37.0564283
OS 29.41429982 -37.06197566
OS 29.38378934 -37.06613618
OS 29.34911834 -37.06890986
OS 29.3130605 -37.0702967
OS 29.06758982 -37.0702967
OS 29.06758982 -37.45999874
OS 28.94000054 -37.45999874
OS 28.94000054 -36.50030546
OS 29.3338631 -36.50030546
OS 29.3546657 -36.5016923
OE
OB 31.18668134 -36.5016923 I
OS 31.1991629 -36.5016923
OS 31.22828654 -36.50307914
OS 31.25879702 -36.50723966
OS 31.29208118 -36.51140018
OS 31.32259166 -36.51833438
OS 31.3378469 -36.5224949
OS 31.35032846 -36.52665542
OS 31.3517153 -36.52665542
OS 31.35310214 -36.52804226
OS 31.36142318 -36.53220278
OS 31.37390474 -36.53775014
OS 31.38915998 -36.54745802
OS 31.40580206 -36.55993958
OS 31.42383098 -36.57658166
OS 31.44047306 -36.59599742
OS 31.45711514 -36.61818686
OS 31.45711514 -36.6195737
OS 31.45850198 -36.62096054
OS 31.46404934 -36.62928158
OS 31.4695967 -36.64314998
OS 31.47791774 -36.6611789
OS 31.48485194 -36.6819815
OS 31.49178614 -36.70694462
OS 31.49594666 -36.73329458
OS 31.4973335 -36.76241822
OS 31.4973335 -36.76380506
OS 31.4973335 -36.76657874
OS 31.4973335 -36.7721261
OS 31.49594666 -36.7790603
OS 31.49594666 -36.78876818
OS 31.49455982 -36.79847606
OS 31.48901246 -36.82205234
OS 31.48069142 -36.84978914
OS 31.4695967 -36.87891278
OS 31.45295462 -36.90803642
OS 31.4418599 -36.92190482
OS 31.43076518 -36.93577322
OS 31.42937834 -36.93716006
OS 31.4279915 -36.9385469
OS 31.42383098 -36.94270742
OS 31.41828362 -36.94686794
OS 31.41134942 -36.9524153
OS 31.40302838 -36.95796266
OS 31.39193366 -36.96489686
OS 31.38083894 -36.9732179
OS 31.36697054 -36.9801521
OS 31.3517153 -36.9870863
OS 31.33507322 -36.99540734
OS 31.3170443 -37.00234154
OS 31.2962417 -37.0078889
OS 31.2754391 -37.0148231
OS 31.25186282 -37.01898362
OS 31.2268997 -37.02314414
OS 31.22967338 -37.02453098
OS 31.23522074 -37.02730466
OS 31.24354178 -37.03285202
OS 31.2546365 -37.03839938
OS 31.27959962 -37.05365462
OS 31.29208118 -37.0633625
OS 31.3031759 -37.07168354
OS 31.30594958 -37.07445722
OS 31.31288378 -37.08139142
OS 31.3239785 -37.09248614
OS 31.3378469 -37.10635454
OS 31.35310214 -37.1257703
OS 31.37113106 -37.1465729
OS 31.38915998 -37.17153602
OS 31.40857574 -37.19927282
OS 31.5736097 -37.45999874
OS 31.41550994 -37.45999874
OS 31.2893075 -37.26029378
OS 31.2893075 -37.25890694
OS 31.28653382 -37.25613326
OS 31.28376014 -37.25197274
OS 31.27959962 -37.24642538
OS 31.26989174 -37.23117014
OS 31.25741018 -37.21175438
OS 31.24215494 -37.19095178
OS 31.2268997 -37.16876234
OS 31.21164446 -37.14795974
OS 31.19777606 -37.12854398
OS 31.19638922 -37.12715714
OS 31.1922287 -37.12160978
OS 31.1852945 -37.11328874
OS 31.17558662 -37.10358086
OS 31.15478402 -37.08277826
OS 31.1436893 -37.07307038
OS 31.13259458 -37.06474934
OS 31.13120774 -37.0633625
OS 31.12843406 -37.06197566
OS 31.1228867 -37.05920198
OS 31.11456566 -37.05504146
OS 31.10624462 -37.05088094
OS 31.09653674 -37.04672042
OS 31.0743473 -37.03978622
OS 31.07296046 -37.03978622
OS 31.07018678 -37.03839938
OS 31.06463942 -37.03839938
OS 31.05770522 -37.03701254
OS 31.04799734 -37.0356257
OS 31.03690262 -37.0356257
OS 31.02164738 -37.03423886
OS 30.85800026 -37.03423886
OS 30.85800026 -37.45999874
OS 30.73041098 -37.45999874
OS 30.73041098 -36.50030546
OS 31.17558662 -36.50030546
OS 31.18668134 -36.5016923
OE
OB 38.16387338 -36.60709214 H
OS 37.86154226 -36.60709214
OS 37.86154226 -36.9246785
OS 38.1472313 -36.9246785
OS 38.16387338 -36.92329166
OS 38.18328914 -36.92190482
OS 38.20547858 -36.92051798
OS 38.22766802 -36.9177443
OS 38.24985746 -36.91358378
OS 38.26927322 -36.90803642
OS 38.2720469 -36.90664958
OS 38.27759426 -36.9038759
OS 38.2859153 -36.89971538
OS 38.29701002 -36.89416802
OS 38.30949158 -36.88584698
OS 38.32197314 -36.8761391
OS 38.3344547 -36.86365754
OS 38.34416258 -36.84978914
OS 38.34554942 -36.8484023
OS 38.3483231 -36.84285494
OS 38.35248362 -36.8345339
OS 38.35803098 -36.82343918
OS 38.3621915 -36.81095762
OS 38.36635202 -36.79708922
OS 38.3691257 -36.78044714
OS 38.37051254 -36.76380506
OS 38.37051254 -36.76241822
OS 38.37051254 -36.76103138
OS 38.3691257 -36.75271034
OS 38.36773886 -36.74022878
OS 38.36496518 -36.7235867
OS 38.35803098 -36.70694462
OS 38.34970994 -36.68752886
OS 38.33722838 -36.66949994
OS 38.3205863 -36.65147102
OS 38.31781262 -36.65008418
OS 38.31087842 -36.64453682
OS 38.2997837 -36.63760262
OS 38.28175478 -36.62928158
OS 38.26095218 -36.62096054
OS 38.23321538 -36.61402634
OS 38.20131806 -36.60847898
OS 38.16387338 -36.60709214
OE
OB 29.34218414 -36.61402634 H
OS 29.06758982 -36.61402634
OS 29.06758982 -36.95657582
OS 29.32554206 -36.95657582
OS 29.33524994 -36.95518898
OS 29.34495782 -36.95518898
OS 29.35605254 -36.95380214
OS 29.3824025 -36.95102846
OS 29.41152614 -36.9454811
OS 29.44064978 -36.93716006
OS 29.46699974 -36.92606534
OS 29.4794813 -36.91913114
OS 29.48918918 -36.9108101
OS 29.49196286 -36.90803642
OS 29.49751022 -36.90248906
OS 29.50583126 -36.89139434
OS 29.51553914 -36.87752594
OS 29.52524702 -36.85949702
OS 29.53356806 -36.83730758
OS 29.53911542 -36.81234446
OS 29.5418891 -36.78322082
OS 29.5418891 -36.78183398
OS 29.5418891 -36.78044714
OS 29.5418891 -36.77351294
OS 29.54050226 -36.76103138
OS 29.53772858 -36.74716298
OS 29.5349549 -36.73190774
OS 29.52940754 -36.71387882
OS 29.5210865 -36.69723674
OS 29.51137862 -36.68059466
OS 29.50999178 -36.67920782
OS 29.50583126 -36.67366046
OS 29.49889706 -36.66672626
OS 29.49057602 -36.65701838
OS 29.47809446 -36.6473105
OS 29.46422606 -36.63898946
OS 29.44897082 -36.63066842
OS 29.4309419 -36.62373422
OS 29.42955506 -36.62373422
OS 29.4240077 -36.62234738
OS 29.41568666 -36.62096054
OS 29.40459194 -36.61818686
OS 29.38794986 -36.61680002
OS 29.36714726 -36.61541318
OS 29.34218414 -36.61402634
OE
OB 30.16180658 -36.60015794 H
OS 30.16180658 -36.60154478
OS 30.16041974 -36.60431846
OS 30.16041974 -36.60986582
OS 30.15764606 -36.61541318
OS 30.15625922 -36.62512106
OS 30.15348554 -36.63482894
OS 30.14793818 -36.65840522
OS 30.14100398 -36.68614202
OS 30.1312961 -36.7166525
OS 30.12158822 -36.74993666
OS 30.10910666 -36.78460766
OS 30.00509366 -37.06474934
OS 30.32961422 -37.06474934
OS 30.22976174 -36.80124974
OS 30.22976174 -36.7998629
OS 30.2283749 -36.79570238
OS 30.22560122 -36.78876818
OS 30.22282754 -36.78044714
OS 30.21866702 -36.77073926
OS 30.2145065 -36.7582577
OS 30.21034598 -36.7443893
OS 30.20479862 -36.7305209
OS 30.1937039 -36.69862358
OS 30.18260918 -36.66533942
OS 30.17151446 -36.63205526
OS 30.16180658 -36.60015794
OE
OB 31.16033138 -36.60709214 H
OS 30.85800026 -36.60709214
OS 30.85800026 -36.9246785
OS 31.1436893 -36.9246785
OS 31.16033138 -36.92329166
OS 31.17974714 -36.92190482
OS 31.20193658 -36.92051798
OS 31.22412602 -36.9177443
OS 31.24631546 -36.91358378
OS 31.26573122 -36.90803642
OS 31.2685049 -36.90664958
OS 31.27405226 -36.9038759
OS 31.2823733 -36.89971538
OS 31.29346802 -36.89416802
OS 31.30594958 -36.88584698
OS 31.31843114 -36.8761391
OS 31.3309127 -36.86365754
OS 31.34062058 -36.84978914
OS 31.34200742 -36.8484023
OS 31.3447811 -36.84285494
OS 31.34894162 -36.8345339
OS 31.35448898 -36.82343918
OS 31.3586495 -36.81095762
OS 31.36281002 -36.79708922
OS 31.3655837 -36.78044714
OS 31.36697054 -36.76380506
OS 31.36697054 -36.76241822
OS 31.36697054 -36.76103138
OS 31.3655837 -36.75271034
OS 31.36419686 -36.74022878
OS 31.36142318 -36.7235867
OS 31.35448898 -36.70694462
OS 31.34616794 -36.68752886
OS 31.33368638 -36.66949994
OS 31.3170443 -36.65147102
OS 31.31427062 -36.65008418
OS 31.30733642 -36.64453682
OS 31.2962417 -36.63760262
OS 31.27821278 -36.62928158
OS 31.25741018 -36.62096054
OS 31.22967338 -36.61402634
OS 31.19777606 -36.60847898
OS 31.16033138 -36.60709214
OE
OB 36.29302622 -36.61402634 H
OS 36.06558446 -36.61402634
OS 36.06558446 -36.90248906
OS 36.30134726 -36.90248906
OS 36.31937618 -36.90110222
OS 36.33879194 -36.89971538
OS 36.3582077 -36.89832854
OS 36.37762346 -36.89555486
OS 36.3928787 -36.89278118
OS 36.39565238 -36.89139434
OS 36.40119974 -36.8900075
OS 36.40952078 -36.88584698
OS 36.4206155 -36.88029962
OS 36.43171022 -36.87475226
OS 36.44419178 -36.86643122
OS 36.45667334 -36.8553365
OS 36.46638122 -36.84424178
OS 36.46776806 -36.84285494
OS 36.47054174 -36.83869442
OS 36.47470226 -36.83037338
OS 36.47886278 -36.8206655
OS 36.4830233 -36.80957078
OS 36.48718382 -36.79570238
OS 36.4899575 -36.7790603
OS 36.49134434 -36.76103138
OS 36.49134434 -36.7582577
OS 36.49134434 -36.75271034
OS 36.4899575 -36.7443893
OS 36.48857066 -36.73329458
OS 36.48579698 -36.71942618
OS 36.48163646 -36.70555778
OS 36.4760891 -36.69168938
OS 36.46776806 -36.67782098
OS 36.46638122 -36.67643414
OS 36.46360754 -36.67227362
OS 36.45806018 -36.66533942
OS 36.45112598 -36.65840522
OS 36.4414181 -36.65008418
OS 36.43032338 -36.64176314
OS 36.41645498 -36.6334421
OS 36.40119974 -36.62789474
OS 36.3998129 -36.62789474
OS 36.3928787 -36.62512106
OS 36.38317082 -36.62373422
OS 36.36791558 -36.62096054
OS 36.34711298 -36.61818686
OS 36.3235367 -36.61680002
OS 36.29302622 -36.61402634
OE
OB 36.31798934 -37.01620994 H
OS 36.06558446 -37.01620994
OS 36.06558446 -37.34627786
OS 36.33879194 -37.34627786
OS 36.36791558 -37.34489102
OS 36.38039714 -37.34350418
OS 36.39149186 -37.34211734
OS 36.3928787 -37.34211734
OS 36.39842606 -37.3407305
OS 36.4067471 -37.33934366
OS 36.41645498 -37.33656998
OS 36.44003126 -37.32824894
OS 36.46360754 -37.31715422
OS 36.46499438 -37.31576738
OS 36.4691549 -37.3129937
OS 36.47470226 -37.30883318
OS 36.48163646 -37.30328582
OS 36.48857066 -37.29496478
OS 36.49827854 -37.28664374
OS 36.50521274 -37.27554902
OS 36.51353378 -37.26306746
OS 36.51492062 -37.26168062
OS 36.51630746 -37.2575201
OS 36.51908114 -37.24919906
OS 36.52324166 -37.23949118
OS 36.52740218 -37.22839646
OS 36.53017586 -37.21452806
OS 36.5315627 -37.19788598
OS 36.53294954 -37.1812439
OS 36.53294954 -37.17847022
OS 36.53294954 -37.17292286
OS 36.5315627 -37.16182814
OS 36.52878902 -37.14934658
OS 36.52601534 -37.13547818
OS 36.52046798 -37.12022294
OS 36.51353378 -37.1049677
OS 36.5038259 -37.08971246
OS 36.50243906 -37.08832562
OS 36.49827854 -37.08277826
OS 36.49273118 -37.07584406
OS 36.48441014 -37.06752302
OS 36.47331542 -37.05781514
OS 36.45944702 -37.04810726
OS 36.44419178 -37.03978622
OS 36.42616286 -37.03285202
OS 36.42338918 -37.03146518
OS 36.41784182 -37.03007834
OS 36.40536026 -37.02730466
OS 36.39010502 -37.02453098
OS 36.37068926 -37.0217573
OS 36.34711298 -37.01898362
OS 36.31798934 -37.01620994
OE
SE
S P 0
OB 40.9056459 -38.32112732 I
OS 40.92136342 -38.32205188
OS 40.9380055 -38.32297644
OS 40.95372302 -38.32482556
OS 40.96759142 -38.32667468
OS 40.96944054 -38.32667468
OS 40.97591246 -38.3285238
OS 40.9842335 -38.33037292
OS 40.99532822 -38.3331466
OS 41.0073475 -38.3377694
OS 41.02029134 -38.34331676
OS 41.03415974 -38.34978868
OS 41.04617902 -38.35718516
OS 41.04802814 -38.35810972
OS 41.05172638 -38.3608834
OS 41.05727374 -38.36643076
OS 41.06467022 -38.37290268
OS 41.07299126 -38.38122372
OS 41.0813123 -38.39231844
OS 41.0905579 -38.40433772
OS 41.09795438 -38.41820612
OS 41.09887894 -38.42005524
OS 41.10072806 -38.42467804
OS 41.1044263 -38.43299908
OS 41.10812454 -38.4440938
OS 41.11089822 -38.45703764
OS 41.11459646 -38.4718306
OS 41.11644558 -38.48847268
OS 41.11737014 -38.50603932
OS 41.11737014 -38.50696388
OS 41.11737014 -38.50973756
OS 41.11737014 -38.5134358
OS 41.11644558 -38.51990772
OS 41.11552102 -38.52637964
OS 41.11459646 -38.53470068
OS 41.11274734 -38.54394628
OS 41.11089822 -38.55411644
OS 41.1044263 -38.57538132
OS 41.10072806 -38.58647604
OS 41.0951807 -38.59849532
OS 41.08870878 -38.6105146
OS 41.08223686 -38.62160932
OS 41.07391582 -38.63270404
OS 41.06467022 -38.64379876
OS 41.06374566 -38.64472332
OS 41.06189654 -38.64657244
OS 41.05912286 -38.64934612
OS 41.05450006 -38.6521198
OS 41.0489527 -38.6567426
OS 41.04155622 -38.6613654
OS 41.03231062 -38.66691276
OS 41.02214046 -38.67153556
OS 41.01012118 -38.67708292
OS 40.99625278 -38.68263028
OS 40.98145982 -38.68725308
OS 40.96389318 -38.69095132
OS 40.94540198 -38.69464956
OS 40.92506166 -38.69742324
OS 40.90194766 -38.69927236
OS 40.8779091 -38.70019692
OS 40.71426198 -38.70019692
OS 40.71426198 -38.95999828
OS 40.62920246 -38.95999828
OS 40.62920246 -38.32020276
OS 40.8917775 -38.32020276
OS 40.9056459 -38.32112732
OE
OB 40.49791494 -38.98403684 I
OS 40.49791494 -38.9849614
OS 40.49791494 -38.98773508
OS 40.49791494 -38.99235788
OS 40.49791494 -38.99790524
OS 40.49699038 -39.00530172
OS 40.49699038 -39.0126982
OS 40.49514126 -39.0311894
OS 40.49236758 -39.05060516
OS 40.48866934 -39.07094548
OS 40.48312198 -39.08851212
OS 40.47942374 -39.09683316
OS 40.4757255 -39.10330508
OS 40.4757255 -39.10422964
OS 40.47480094 -39.1051542
OS 40.47017814 -39.109777
OS 40.46278166 -39.11717348
OS 40.45353606 -39.12549452
OS 40.44059222 -39.13381556
OS 40.42395014 -39.14028748
OS 40.40453438 -39.14583484
OS 40.39343966 -39.1467594
OS 40.38142038 -39.14768396
OS 40.37587302 -39.14768396
OS 40.37032566 -39.1467594
OS 40.36200462 -39.1467594
OS 40.35275902 -39.14583484
OS 40.34258886 -39.14398572
OS 40.32039942 -39.13843836
OS 40.33519238 -39.07187004
OS 40.33611694 -39.07187004
OS 40.33889062 -39.0727946
OS 40.34351342 -39.07371916
OS 40.34813622 -39.07464372
OS 40.3601555 -39.0774174
OS 40.36570286 -39.07834196
OS 40.37494846 -39.07834196
OS 40.37957126 -39.0774174
OS 40.38511862 -39.07649284
OS 40.39066598 -39.07464372
OS 40.39621334 -39.07094548
OS 40.40268526 -39.06724724
OS 40.40730806 -39.06169988
OS 40.40823262 -39.06077532
OS 40.40915718 -39.05800164
OS 40.4110063 -39.05337884
OS 40.41377998 -39.04598236
OS 40.4156291 -39.0358122
OS 40.41655366 -39.02841572
OS 40.41747822 -39.0219438
OS 40.41840278 -39.01362276
OS 40.41840278 -39.0034526
OS 40.41932734 -38.99328244
OS 40.41932734 -38.98218772
OS 40.41932734 -38.49586916
OS 40.49791494 -38.49586916
OS 40.49791494 -38.98403684
OE
OB 41.51770462 -38.3100326 I
OS 41.52602566 -38.31095716
OS 41.53619582 -38.31188172
OS 41.54636598 -38.31280628
OS 41.55838526 -38.31557996
OS 41.58334838 -38.32112732
OS 41.61108518 -38.32944836
OS 41.62495358 -38.33499572
OS 41.63789742 -38.34146764
OS 41.65084126 -38.34978868
OS 41.6637851 -38.35810972
OS 41.66470966 -38.35903428
OS 41.66655878 -38.35995884
OS 41.67025702 -38.36273252
OS 41.67487982 -38.36735532
OS 41.67950262 -38.37197812
OS 41.68597454 -38.37845004
OS 41.69244646 -38.38584652
OS 41.69984294 -38.393243
OS 41.70723942 -38.4024886
OS 41.7146359 -38.41358332
OS 41.72295694 -38.42467804
OS 41.73035342 -38.43669732
OS 41.73682534 -38.45056572
OS 41.74422182 -38.46443412
OS 41.74976918 -38.47922708
OS 41.75531654 -38.49586916
OS 41.67210614 -38.51528492
OS 41.67210614 -38.51436036
OS 41.67118158 -38.51251124
OS 41.66933246 -38.508813
OS 41.66748334 -38.5041902
OS 41.66563422 -38.49864284
OS 41.66286054 -38.49124636
OS 41.65546406 -38.4764534
OS 41.64621846 -38.45981132
OS 41.63512374 -38.44316924
OS 41.62125534 -38.42745172
OS 41.60646238 -38.41358332
OS 41.60461326 -38.4117342
OS 41.5990659 -38.40803596
OS 41.5898203 -38.40341316
OS 41.57780102 -38.39694124
OS 41.5620835 -38.39139388
OS 41.54451686 -38.38584652
OS 41.52325198 -38.38214828
OS 41.50013798 -38.38122372
OS 41.4927415 -38.38122372
OS 41.4881187 -38.38214828
OS 41.48164678 -38.38214828
OS 41.4742503 -38.38307284
OS 41.45668366 -38.38584652
OS 41.4372679 -38.38954476
OS 41.41692758 -38.39601668
OS 41.3956627 -38.40526228
OS 41.37624694 -38.41728156
OS 41.37532238 -38.41728156
OS 41.37439782 -38.41913068
OS 41.3679259 -38.42375348
OS 41.35960486 -38.43114996
OS 41.3494347 -38.44224468
OS 41.33741542 -38.45611308
OS 41.3263207 -38.4718306
OS 41.31615054 -38.49124636
OS 41.30690494 -38.51251124
OS 41.30690494 -38.5134358
OS 41.30598038 -38.51528492
OS 41.30505582 -38.5180586
OS 41.30413126 -38.5226814
OS 41.30228214 -38.52822876
OS 41.30043302 -38.53470068
OS 41.29765934 -38.5504182
OS 41.2939611 -38.5689094
OS 41.29026286 -38.58924972
OS 41.28841374 -38.61143916
OS 41.28748918 -38.63547772
OS 41.28748918 -38.63640228
OS 41.28748918 -38.63917596
OS 41.28748918 -38.64379876
OS 41.28748918 -38.64934612
OS 41.28841374 -38.65581804
OS 41.28841374 -38.66413908
OS 41.2893383 -38.67338468
OS 41.29026286 -38.68355484
OS 41.29303654 -38.70574428
OS 41.29765934 -38.72978284
OS 41.3032067 -38.7538214
OS 41.31060318 -38.77785996
OS 41.31060318 -38.77878452
OS 41.31152774 -38.78063364
OS 41.31337686 -38.78340732
OS 41.31522598 -38.78803012
OS 41.32077334 -38.79912484
OS 41.32909438 -38.81206868
OS 41.33926454 -38.82686164
OS 41.35220838 -38.84257916
OS 41.36700134 -38.85644756
OS 41.38456798 -38.8693914
OS 41.38549254 -38.8693914
OS 41.38734166 -38.87031596
OS 41.39011534 -38.87216508
OS 41.39381358 -38.8740142
OS 41.39843638 -38.87586332
OS 41.40398374 -38.878637
OS 41.41692758 -38.88418436
OS 41.43356966 -38.88973172
OS 41.45206086 -38.89435452
OS 41.47240118 -38.89805276
OS 41.49366606 -38.89897732
OS 41.50013798 -38.89897732
OS 41.50568534 -38.89805276
OS 41.51215726 -38.89805276
OS 41.51862918 -38.8971282
OS 41.53527126 -38.89342996
OS 41.55468702 -38.88880716
OS 41.57410278 -38.88141068
OS 41.5944431 -38.87124052
OS 41.60461326 -38.86569316
OS 41.61385886 -38.85829668
OS 41.61478342 -38.85737212
OS 41.61570798 -38.85644756
OS 41.61848166 -38.85367388
OS 41.6221799 -38.8509002
OS 41.62587814 -38.8462774
OS 41.63050094 -38.84073004
OS 41.6360483 -38.83518268
OS 41.6406711 -38.8277862
OS 41.64621846 -38.81946516
OS 41.65269038 -38.81021956
OS 41.65823774 -38.80097396
OS 41.6637851 -38.78987924
OS 41.6684079 -38.77785996
OS 41.6730307 -38.76491612
OS 41.6776535 -38.75104772
OS 41.68135174 -38.73625476
OS 41.76641126 -38.75751964
OS 41.76641126 -38.7584442
OS 41.7654867 -38.76214244
OS 41.76363758 -38.7676898
OS 41.7608639 -38.77508628
OS 41.75809022 -38.78340732
OS 41.75439198 -38.79357748
OS 41.74976918 -38.8046722
OS 41.74422182 -38.81669148
OS 41.73127798 -38.84257916
OS 41.7146359 -38.86846684
OS 41.70446574 -38.88141068
OS 41.69429558 -38.89435452
OS 41.68320086 -38.90544924
OS 41.67025702 -38.91654396
OS 41.66933246 -38.91746852
OS 41.66748334 -38.91931764
OS 41.66286054 -38.92116676
OS 41.65823774 -38.924865
OS 41.65084126 -38.9294878
OS 41.64344478 -38.9341106
OS 41.63327462 -38.9387334
OS 41.62310446 -38.9433562
OS 41.61108518 -38.94890356
OS 41.59814134 -38.95352636
OS 41.58427294 -38.95814916
OS 41.56947998 -38.96277196
OS 41.55376246 -38.9664702
OS 41.53712038 -38.96831932
OS 41.51955374 -38.97016844
OS 41.50106254 -38.971093
OS 41.49089238 -38.971093
OS 41.4834959 -38.97016844
OS 41.47517486 -38.97016844
OS 41.4650047 -38.96924388
OS 41.45390998 -38.96739476
OS 41.44096614 -38.96554564
OS 41.4141539 -38.96092284
OS 41.3864171 -38.95352636
OS 41.3586803 -38.9433562
OS 41.34573646 -38.93688428
OS 41.33279262 -38.9294878
OS 41.33186806 -38.92856324
OS 41.33001894 -38.92763868
OS 41.3263207 -38.924865
OS 41.32262246 -38.92116676
OS 41.3170751 -38.91746852
OS 41.31060318 -38.91192116
OS 41.3032067 -38.90544924
OS 41.29581022 -38.89805276
OS 41.28841374 -38.88973172
OS 41.2800927 -38.88141068
OS 41.26345062 -38.8601458
OS 41.2477331 -38.83518268
OS 41.2338647 -38.80744588
OS 41.2338647 -38.80652132
OS 41.23201558 -38.80374764
OS 41.23109102 -38.79912484
OS 41.22831734 -38.79357748
OS 41.22646822 -38.786181
OS 41.22369454 -38.7769354
OS 41.2199963 -38.76676524
OS 41.21722262 -38.75567052
OS 41.21444894 -38.74365124
OS 41.2107507 -38.72978284
OS 41.2061279 -38.70112148
OS 41.20242966 -38.66876188
OS 41.20058054 -38.63547772
OS 41.20058054 -38.63455316
OS 41.20058054 -38.63085492
OS 41.20058054 -38.62530756
OS 41.2015051 -38.61883564
OS 41.2015051 -38.60959004
OS 41.20242966 -38.60034444
OS 41.20335422 -38.58832516
OS 41.20520334 -38.57630588
OS 41.20982614 -38.54949364
OS 41.21629806 -38.51990772
OS 41.22554366 -38.4903218
OS 41.2384875 -38.46166044
OS 41.23941206 -38.46073588
OS 41.24033662 -38.4579622
OS 41.24218574 -38.45426396
OS 41.24588398 -38.44964116
OS 41.24958222 -38.44316924
OS 41.25420502 -38.43577276
OS 41.2662243 -38.41913068
OS 41.28194182 -38.40063948
OS 41.30043302 -38.38214828
OS 41.3216979 -38.36365708
OS 41.34666102 -38.34793956
OS 41.34758558 -38.347015
OS 41.35035926 -38.34609044
OS 41.3540575 -38.34424132
OS 41.3586803 -38.34146764
OS 41.36607678 -38.33869396
OS 41.37347326 -38.33592028
OS 41.38271886 -38.33222204
OS 41.39288902 -38.3285238
OS 41.40398374 -38.32482556
OS 41.41600302 -38.32112732
OS 41.4418907 -38.31557996
OS 41.47147662 -38.31095716
OS 41.5019871 -38.30910804
OS 41.5112327 -38.30910804
OS 41.51770462 -38.3100326
OE
OB 42.90454462 -39.1375138 I
OS 42.38401734 -39.1375138
OS 42.38401734 -39.08111564
OS 42.90454462 -39.08111564
OS 42.90454462 -39.1375138
OE
OB 42.12514054 -38.32112732 I
OS 42.13253702 -38.32112732
OS 42.1491791 -38.32297644
OS 42.1676703 -38.32482556
OS 42.18708606 -38.3285238
OS 42.20650182 -38.3331466
OS 42.22406846 -38.33961852
OS 42.22499302 -38.33961852
OS 42.22591758 -38.34054308
OS 42.23146494 -38.34331676
OS 42.23978598 -38.34793956
OS 42.24903158 -38.35441148
OS 42.2601263 -38.36273252
OS 42.27214558 -38.37290268
OS 42.2832403 -38.38584652
OS 42.29341046 -38.39971492
OS 42.29433502 -38.40156404
OS 42.2971087 -38.4071114
OS 42.3017315 -38.41450788
OS 42.3063543 -38.4256026
OS 42.3109771 -38.43854644
OS 42.3155999 -38.45241484
OS 42.31837358 -38.46813236
OS 42.31929814 -38.48384988
OS 42.31929814 -38.485699
OS 42.31929814 -38.4903218
OS 42.31837358 -38.49864284
OS 42.31652446 -38.508813
OS 42.31375078 -38.52083228
OS 42.30912798 -38.53377612
OS 42.30358062 -38.54671996
OS 42.29618414 -38.56058836
OS 42.29525958 -38.56243748
OS 42.2924859 -38.56613572
OS 42.28693854 -38.5735322
OS 42.27954206 -38.58092868
OS 42.27029646 -38.59017428
OS 42.25920174 -38.60034444
OS 42.24533334 -38.60959004
OS 42.22961582 -38.61883564
OS 42.23054038 -38.61883564
OS 42.2323895 -38.6197602
OS 42.23516318 -38.62068476
OS 42.23886142 -38.62253388
OS 42.24995614 -38.62623212
OS 42.26289998 -38.63270404
OS 42.27676838 -38.64102508
OS 42.2924859 -38.65119524
OS 42.3063543 -38.66321452
OS 42.31929814 -38.67800748
OS 42.3202227 -38.6798566
OS 42.32392094 -38.68540396
OS 42.3294683 -38.693725
OS 42.33501566 -38.70481972
OS 42.34056302 -38.71961268
OS 42.34611038 -38.7353302
OS 42.34980862 -38.7538214
OS 42.35073318 -38.77416172
OS 42.35073318 -38.77508628
OS 42.35073318 -38.77601084
OS 42.35073318 -38.7815582
OS 42.34980862 -38.7908038
OS 42.3479595 -38.80189852
OS 42.34611038 -38.81484236
OS 42.34241214 -38.82871076
OS 42.33778934 -38.84350372
OS 42.33131742 -38.85829668
OS 42.33039286 -38.8601458
OS 42.32761918 -38.8647686
OS 42.32392094 -38.87124052
OS 42.31837358 -38.88048612
OS 42.3109771 -38.88973172
OS 42.30358062 -38.89990188
OS 42.29433502 -38.91007204
OS 42.28416486 -38.91839308
OS 42.2832403 -38.91931764
OS 42.27954206 -38.92209132
OS 42.27307014 -38.92578956
OS 42.2647491 -38.9294878
OS 42.25457894 -38.93503516
OS 42.24255966 -38.94058252
OS 42.22961582 -38.94520532
OS 42.2138983 -38.94982812
OS 42.21204918 -38.94982812
OS 42.20650182 -38.95167724
OS 42.19725622 -38.9526018
OS 42.18523694 -38.95445092
OS 42.17044398 -38.95630004
OS 42.15287734 -38.95814916
OS 42.13346158 -38.95907372
OS 42.11127214 -38.95999828
OS 41.8671883 -38.95999828
OS 41.8671883 -38.32020276
OS 42.11866862 -38.32020276
OS 42.12514054 -38.32112732
OE
OB 40.30745558 -38.48662356 I
OS 40.31762574 -38.48847268
OS 40.32964502 -38.49217092
OS 40.34258886 -38.49679372
OS 40.35738182 -38.50326564
OS 40.37309934 -38.51158668
OS 40.34443798 -38.58370236
OS 40.34351342 -38.5827778
OS 40.33981518 -38.58092868
OS 40.33426782 -38.578155
OS 40.32687134 -38.57538132
OS 40.3185503 -38.57260764
OS 40.30838014 -38.56983396
OS 40.29820998 -38.56798484
OS 40.28803982 -38.56706028
OS 40.28341702 -38.56706028
OS 40.27879422 -38.56798484
OS 40.2723223 -38.5689094
OS 40.26585038 -38.57075852
OS 40.25752934 -38.5735322
OS 40.2492083 -38.57723044
OS 40.24181182 -38.5827778
OS 40.24088726 -38.58370236
OS 40.23811358 -38.58555148
OS 40.2353399 -38.58924972
OS 40.2307171 -38.59387252
OS 40.2260943 -38.60034444
OS 40.2214715 -38.60774092
OS 40.2168487 -38.61606196
OS 40.21315046 -38.62623212
OS 40.2122259 -38.62808124
OS 40.21130134 -38.6336286
OS 40.20945222 -38.64194964
OS 40.20667854 -38.65304436
OS 40.20390486 -38.66691276
OS 40.20205574 -38.68263028
OS 40.20113118 -38.69927236
OS 40.20020662 -38.71776356
OS 40.20020662 -38.95999828
OS 40.12161902 -38.95999828
OS 40.12161902 -38.49586916
OS 40.19281014 -38.49586916
OS 40.19281014 -38.56613572
OS 40.1937347 -38.56521116
OS 40.19743294 -38.55873924
OS 40.20205574 -38.5504182
OS 40.20945222 -38.54024804
OS 40.2168487 -38.53007788
OS 40.22516974 -38.51898316
OS 40.23349078 -38.50973756
OS 40.24181182 -38.50234108
OS 40.24273638 -38.50141652
OS 40.24551006 -38.4995674
OS 40.25105742 -38.49679372
OS 40.25660478 -38.49402004
OS 40.26400126 -38.49124636
OS 40.27324686 -38.48847268
OS 40.28249246 -38.48662356
OS 40.29266262 -38.485699
OS 40.29913454 -38.485699
OS 40.30745558 -38.48662356
OE
OB 39.48829542 -38.95999828 I
OS 39.3986131 -38.95999828
OS 39.3986131 -38.87031596
OS 39.48829542 -38.87031596
OS 39.48829542 -38.95999828
OE
OB 38.6404739 -38.95999828 I
OS 38.55171614 -38.95999828
OS 38.30393406 -38.32020276
OS 38.39639006 -38.32020276
OS 38.56281086 -38.78525644
OS 38.56281086 -38.786181
OS 38.56373542 -38.78803012
OS 38.56465998 -38.7908038
OS 38.5665091 -38.79450204
OS 38.56743366 -38.8000494
OS 38.56928278 -38.80559676
OS 38.57390558 -38.81946516
OS 38.57945294 -38.83518268
OS 38.5850003 -38.85274932
OS 38.59609502 -38.88973172
OS 38.59609502 -38.88880716
OS 38.59701958 -38.88695804
OS 38.59794414 -38.88418436
OS 38.5988687 -38.88048612
OS 38.60164238 -38.87031596
OS 38.60626518 -38.85644756
OS 38.61088798 -38.84073004
OS 38.61643534 -38.8231634
OS 38.62290726 -38.8046722
OS 38.63030374 -38.78525644
OS 38.80412102 -38.32020276
OS 38.8901051 -38.32020276
OS 38.6404739 -38.95999828
OE
OB 39.27564662 -38.42745172 I
OS 39.25438174 -38.54671996
OS 39.20538006 -38.54671996
OS 39.1859643 -38.42745172
OS 39.1859643 -38.32020276
OS 39.27564662 -38.32020276
OS 39.27564662 -38.42745172
OE
OB 40.49791494 -38.4117342 I
OS 40.41932734 -38.4117342
OS 40.41932734 -38.32020276
OS 40.49791494 -38.32020276
OS 40.49791494 -38.4117342
OE
OB 39.84517558 -38.48662356 I
OS 39.8516475 -38.48754812
OS 39.8655159 -38.48939724
OS 39.88215798 -38.49309548
OS 39.89972462 -38.49864284
OS 39.91729126 -38.50696388
OS 39.9348579 -38.51713404
OS 39.93578246 -38.51713404
OS 39.93670702 -38.51898316
OS 39.94225438 -38.5226814
OS 39.95057542 -38.53007788
OS 39.96074558 -38.53932348
OS 39.9718403 -38.55134276
OS 39.98293502 -38.56613572
OS 39.99402974 -38.58370236
OS 40.00327534 -38.60311812
OS 40.00327534 -38.60404268
OS 40.0041999 -38.6058918
OS 40.00512446 -38.60866548
OS 40.00697358 -38.61236372
OS 40.0088227 -38.61791108
OS 40.01067182 -38.624383
OS 40.01529462 -38.63917596
OS 40.01991742 -38.65766716
OS 40.02361566 -38.67800748
OS 40.02638934 -38.70112148
OS 40.0273139 -38.72516004
OS 40.0273139 -38.7260846
OS 40.0273139 -38.72793372
OS 40.0273139 -38.73163196
OS 40.0273139 -38.73717932
OS 40.02638934 -38.74365124
OS 40.02638934 -38.75104772
OS 40.02454022 -38.7676898
OS 40.02084198 -38.78803012
OS 40.01621918 -38.809295
OS 40.00974726 -38.83148444
OS 40.00142622 -38.85367388
OS 40.00142622 -38.85459844
OS 40.00050166 -38.85644756
OS 39.99865254 -38.85922124
OS 39.99680342 -38.86291948
OS 39.9903315 -38.87308964
OS 39.98201046 -38.88603348
OS 39.9718403 -38.89990188
OS 39.95889646 -38.91377028
OS 39.9441035 -38.92763868
OS 39.92653686 -38.94058252
OS 39.9256123 -38.94058252
OS 39.92468774 -38.94150708
OS 39.92191406 -38.9433562
OS 39.91821582 -38.94520532
OS 39.90897022 -38.94982812
OS 39.89602638 -38.95537548
OS 39.88030886 -38.96092284
OS 39.86366678 -38.96554564
OS 39.84425102 -38.96924388
OS 39.82483526 -38.97016844
OS 39.81836334 -38.97016844
OS 39.81096686 -38.96924388
OS 39.80172126 -38.96831932
OS 39.79062654 -38.9664702
OS 39.77860726 -38.96369652
OS 39.76658798 -38.95999828
OS 39.7545687 -38.95445092
OS 39.75364414 -38.95352636
OS 39.74902134 -38.95167724
OS 39.74347398 -38.947979
OS 39.7360775 -38.94243164
OS 39.72868102 -38.93688428
OS 39.71943542 -38.9294878
OS 39.71111438 -38.92116676
OS 39.7037179 -38.91192116
OS 39.7037179 -39.1375138
OS 39.6251303 -39.1375138
OS 39.6251303 -38.49586916
OS 39.69632142 -38.49586916
OS 39.69632142 -38.55689012
OS 39.69724598 -38.555041
OS 39.70094422 -38.55134276
OS 39.70556702 -38.54487084
OS 39.7129635 -38.53747436
OS 39.72128454 -38.52822876
OS 39.73053014 -38.51990772
OS 39.74162486 -38.51158668
OS 39.75271958 -38.5041902
OS 39.7545687 -38.50326564
OS 39.75826694 -38.50141652
OS 39.76566342 -38.49864284
OS 39.77490902 -38.4949446
OS 39.78600374 -38.49124636
OS 39.79894758 -38.48847268
OS 39.81374054 -38.48662356
OS 39.83038262 -38.485699
OS 39.84055278 -38.485699
OS 39.84517558 -38.48662356
OE
OB 44.92193454 -38.40988508 I
OS 44.84334694 -38.40988508
OS 44.84334694 -38.32020276
OS 44.92193454 -38.32020276
OS 44.92193454 -38.40988508
OE
OB 45.24553054 -38.48662356 I
OS 45.25385158 -38.48754812
OS 45.26309718 -38.48939724
OS 45.27326734 -38.49124636
OS 45.28528662 -38.49309548
OS 45.31024974 -38.50141652
OS 45.32319358 -38.50603932
OS 45.33613742 -38.51251124
OS 45.34908126 -38.51898316
OS 45.3620251 -38.52822876
OS 45.37404438 -38.53747436
OS 45.38606366 -38.54856908
OS 45.38698822 -38.54949364
OS 45.38883734 -38.55134276
OS 45.39161102 -38.555041
OS 45.39530926 -38.5596638
OS 45.39993206 -38.56613572
OS 45.40547942 -38.57445676
OS 45.41102678 -38.58370236
OS 45.41657414 -38.59387252
OS 45.4221215 -38.60496724
OS 45.42766886 -38.61883564
OS 45.43321622 -38.63270404
OS 45.43783902 -38.64842156
OS 45.44153726 -38.66506364
OS 45.44431094 -38.68263028
OS 45.44616006 -38.70112148
OS 45.44708462 -38.7214618
OS 45.44708462 -38.72238636
OS 45.44708462 -38.72516004
OS 45.44708462 -38.72978284
OS 45.44708462 -38.73625476
OS 45.44616006 -38.74365124
OS 45.4452355 -38.75289684
OS 45.4452355 -38.76214244
OS 45.44338638 -38.7723126
OS 45.4406127 -38.7954266
OS 45.43506534 -38.8185406
OS 45.42859342 -38.8416546
OS 45.41934782 -38.86291948
OS 45.41934782 -38.86384404
OS 45.41842326 -38.8647686
OS 45.41657414 -38.86754228
OS 45.41472502 -38.87124052
OS 45.4082531 -38.88048612
OS 45.39993206 -38.89158084
OS 45.38883734 -38.90452468
OS 45.37496894 -38.91746852
OS 45.35925142 -38.93041236
OS 45.34076022 -38.94243164
OS 45.33983566 -38.94243164
OS 45.3389111 -38.9433562
OS 45.33613742 -38.94520532
OS 45.33151462 -38.94705444
OS 45.32689182 -38.94890356
OS 45.32134446 -38.95075268
OS 45.30747606 -38.95630004
OS 45.29175854 -38.96092284
OS 45.27234278 -38.96554564
OS 45.25200246 -38.96924388
OS 45.22981302 -38.97016844
OS 45.22056742 -38.97016844
OS 45.21317094 -38.96924388
OS 45.2048499 -38.96831932
OS 45.1956043 -38.9664702
OS 45.18450958 -38.96462108
OS 45.17341486 -38.96277196
OS 45.14845174 -38.95537548
OS 45.13458334 -38.94982812
OS 45.1216395 -38.94428076
OS 45.10869566 -38.93688428
OS 45.09575182 -38.92856324
OS 45.08373254 -38.91931764
OS 45.07171326 -38.90822292
OS 45.0707887 -38.90729836
OS 45.06893958 -38.90544924
OS 45.0661659 -38.901751
OS 45.06246766 -38.89620364
OS 45.05784486 -38.88973172
OS 45.05322206 -38.88233524
OS 45.0476747 -38.87308964
OS 45.04212734 -38.86199492
OS 45.03657998 -38.84997564
OS 45.03103262 -38.83610724
OS 45.02640982 -38.82131428
OS 45.02178702 -38.80559676
OS 45.01808878 -38.78803012
OS 45.0153151 -38.76953892
OS 45.01346598 -38.7491986
OS 45.01254142 -38.72793372
OS 45.01254142 -38.7260846
OS 45.01254142 -38.72238636
OS 45.01346598 -38.71591444
OS 45.01346598 -38.70666884
OS 45.01439054 -38.69649868
OS 45.01623966 -38.68355484
OS 45.01808878 -38.670611
OS 45.02178702 -38.65581804
OS 45.02548526 -38.64102508
OS 45.03010806 -38.62530756
OS 45.03565542 -38.60866548
OS 45.0430519 -38.59294796
OS 45.05044838 -38.578155
OS 45.06061854 -38.56336204
OS 45.0707887 -38.54949364
OS 45.08373254 -38.53747436
OS 45.0846571 -38.5365498
OS 45.08650622 -38.53562524
OS 45.09020446 -38.53285156
OS 45.09482726 -38.52915332
OS 45.10037462 -38.52545508
OS 45.1077711 -38.52083228
OS 45.11516758 -38.51620948
OS 45.12441318 -38.51158668
OS 45.13458334 -38.50696388
OS 45.14567806 -38.50234108
OS 45.17064118 -38.49402004
OS 45.19930254 -38.48754812
OS 45.2140955 -38.48662356
OS 45.22981302 -38.485699
OS 45.23905862 -38.485699
OS 45.24553054 -38.48662356
OE
OB 44.92193454 -38.95999828 I
OS 44.84334694 -38.95999828
OS 44.84334694 -38.49586916
OS 44.92193454 -38.49586916
OS 44.92193454 -38.95999828
OE
OB 46.10722046 -38.42745172 I
OS 46.08595558 -38.54671996
OS 46.0369539 -38.54671996
OS 46.01753814 -38.42745172
OS 46.01753814 -38.32020276
OS 46.10722046 -38.32020276
OS 46.10722046 -38.42745172
OE
OB 45.77160518 -38.48662356 I
OS 45.78177534 -38.48754812
OS 45.79379462 -38.48939724
OS 45.80673846 -38.49217092
OS 45.82060686 -38.49586916
OS 45.8335507 -38.50141652
OS 45.83539982 -38.50234108
OS 45.83909806 -38.5041902
OS 45.84556998 -38.50696388
OS 45.85296646 -38.51158668
OS 45.86221206 -38.51713404
OS 45.8705331 -38.52453052
OS 45.87885414 -38.531927
OS 45.88625062 -38.5411726
OS 45.88717518 -38.54209716
OS 45.8890243 -38.5457954
OS 45.89179798 -38.5504182
OS 45.89642078 -38.55689012
OS 45.90011902 -38.56613572
OS 45.90381726 -38.57538132
OS 45.90844006 -38.58647604
OS 45.91121374 -38.59849532
OS 45.91121374 -38.59941988
OS 45.9121383 -38.60311812
OS 45.91306286 -38.60866548
OS 45.91398742 -38.61606196
OS 45.91398742 -38.62715668
OS 45.91491198 -38.64010052
OS 45.91583654 -38.65581804
OS 45.91583654 -38.6752338
OS 45.91583654 -38.95999828
OS 45.83724894 -38.95999828
OS 45.83724894 -38.67893204
OS 45.83724894 -38.67800748
OS 45.83724894 -38.67708292
OS 45.83724894 -38.670611
OS 45.83724894 -38.66228996
OS 45.83632438 -38.6521198
OS 45.83539982 -38.64010052
OS 45.8335507 -38.62808124
OS 45.83077702 -38.61698652
OS 45.82800334 -38.60681636
OS 45.82800334 -38.6058918
OS 45.82615422 -38.60311812
OS 45.82338054 -38.59849532
OS 45.82060686 -38.59294796
OS 45.81598406 -38.5874006
OS 45.8104367 -38.58092868
OS 45.80304022 -38.57445676
OS 45.79471918 -38.5689094
OS 45.79379462 -38.56798484
OS 45.79102094 -38.56613572
OS 45.78547358 -38.5642866
OS 45.77900166 -38.56151292
OS 45.77160518 -38.55873924
OS 45.76235958 -38.55596556
OS 45.75126486 -38.555041
OS 45.74017014 -38.55411644
OS 45.73554734 -38.55411644
OS 45.7318491 -38.555041
OS 45.7226035 -38.55596556
OS 45.71058422 -38.55781468
OS 45.69764038 -38.56243748
OS 45.68284742 -38.56798484
OS 45.66805446 -38.57538132
OS 45.65418606 -38.58647604
OS 45.65233694 -38.58832516
OS 45.6486387 -38.59294796
OS 45.64586502 -38.5966462
OS 45.64309134 -38.601269
OS 45.6393931 -38.60681636
OS 45.63661942 -38.61328828
OS 45.63292118 -38.62068476
OS 45.62922294 -38.62993036
OS 45.62644926 -38.64010052
OS 45.62367558 -38.65119524
OS 45.62182646 -38.66321452
OS 45.61997734 -38.67615836
OS 45.61812822 -38.69187588
OS 45.61812822 -38.7075934
OS 45.61812822 -38.95999828
OS 45.53954062 -38.95999828
OS 45.53954062 -38.49586916
OS 45.60980718 -38.49586916
OS 45.60980718 -38.56243748
OS 45.61073174 -38.56151292
OS 45.61258086 -38.55873924
OS 45.61535454 -38.555041
OS 45.61905278 -38.5504182
OS 45.62460014 -38.54487084
OS 45.63107206 -38.53839892
OS 45.63846854 -38.53100244
OS 45.64771414 -38.52360596
OS 45.65695974 -38.51713404
OS 45.66805446 -38.50973756
OS 45.68007374 -38.50326564
OS 45.69301758 -38.49771828
OS 45.70781054 -38.49309548
OS 45.7226035 -38.48939724
OS 45.73924558 -38.48662356
OS 45.75681222 -38.485699
OS 45.7642087 -38.485699
OS 45.77160518 -38.48662356
OE
OB 44.2756671 -38.95999828 I
OS 44.1970795 -38.95999828
OS 44.1970795 -38.49586916
OS 44.2756671 -38.49586916
OS 44.2756671 -38.95999828
OE
OB 43.4574315 -38.48662356 I
OS 43.46482798 -38.48754812
OS 43.47407358 -38.48939724
OS 43.48424374 -38.49124636
OS 43.49626302 -38.49402004
OS 43.50735774 -38.49679372
OS 43.52030158 -38.50141652
OS 43.53232086 -38.50603932
OS 43.5452647 -38.51251124
OS 43.55820854 -38.51990772
OS 43.57115238 -38.52822876
OS 43.58317166 -38.53839892
OS 43.59426638 -38.54949364
OS 43.59519094 -38.5504182
OS 43.59704006 -38.55226732
OS 43.59981374 -38.55596556
OS 43.60351198 -38.56151292
OS 43.60813478 -38.56798484
OS 43.61275758 -38.57538132
OS 43.61830494 -38.58462692
OS 43.6238523 -38.59572164
OS 43.62939966 -38.60774092
OS 43.63494702 -38.62068476
OS 43.63956982 -38.63547772
OS 43.64419262 -38.65119524
OS 43.64789086 -38.66876188
OS 43.65066454 -38.68725308
OS 43.65251366 -38.70666884
OS 43.65343822 -38.72793372
OS 43.65343822 -38.72885828
OS 43.65343822 -38.73255652
OS 43.65343822 -38.73902844
OS 43.65251366 -38.74827404
OS 43.30580366 -38.74827404
OS 43.30580366 -38.7491986
OS 43.30580366 -38.75197228
OS 43.30672822 -38.75567052
OS 43.30672822 -38.76121788
OS 43.30765278 -38.7676898
OS 43.3095019 -38.77508628
OS 43.31227558 -38.79172836
OS 43.31782294 -38.81021956
OS 43.32521942 -38.83055988
OS 43.33538958 -38.84905108
OS 43.34833342 -38.86569316
OS 43.34925798 -38.86569316
OS 43.35018254 -38.86754228
OS 43.3557299 -38.87216508
OS 43.36405094 -38.878637
OS 43.37514566 -38.88510892
OS 43.38993862 -38.8925054
OS 43.4065807 -38.89897732
OS 43.4250719 -38.90360012
OS 43.43524206 -38.90452468
OS 43.44633678 -38.90544924
OS 43.45373326 -38.90544924
OS 43.4620543 -38.90452468
OS 43.47222446 -38.90267556
OS 43.48331918 -38.89990188
OS 43.49626302 -38.89620364
OS 43.5082823 -38.89065628
OS 43.52030158 -38.8832598
OS 43.52122614 -38.88233524
OS 43.52584894 -38.878637
OS 43.5313963 -38.87308964
OS 43.53786822 -38.86569316
OS 43.5452647 -38.855523
OS 43.55358574 -38.84257916
OS 43.56190678 -38.8277862
OS 43.56930326 -38.81021956
OS 43.65066454 -38.82038972
OS 43.65066454 -38.82131428
OS 43.64973998 -38.8231634
OS 43.64881542 -38.82686164
OS 43.6469663 -38.832409
OS 43.64419262 -38.83795636
OS 43.64141894 -38.84535284
OS 43.63402246 -38.86107036
OS 43.62477686 -38.878637
OS 43.61183302 -38.8971282
OS 43.59704006 -38.91469484
OS 43.57854886 -38.93133692
OS 43.5776243 -38.93133692
OS 43.57577518 -38.93318604
OS 43.5730015 -38.93503516
OS 43.56930326 -38.93780884
OS 43.5637559 -38.94058252
OS 43.55820854 -38.9433562
OS 43.55081206 -38.94705444
OS 43.54249102 -38.95075268
OS 43.53324542 -38.95445092
OS 43.52399982 -38.95814916
OS 43.50088582 -38.96369652
OS 43.47499814 -38.96831932
OS 43.44633678 -38.97016844
OS 43.43616662 -38.97016844
OS 43.4296947 -38.96924388
OS 43.42137366 -38.96831932
OS 43.4112035 -38.9664702
OS 43.40010878 -38.96462108
OS 43.3880895 -38.96277196
OS 43.36220182 -38.95537548
OS 43.34833342 -38.94982812
OS 43.33538958 -38.94428076
OS 43.32152118 -38.93688428
OS 43.30857734 -38.92856324
OS 43.29655806 -38.91931764
OS 43.28453878 -38.90822292
OS 43.28361422 -38.90729836
OS 43.2817651 -38.90544924
OS 43.27899142 -38.901751
OS 43.27529318 -38.89620364
OS 43.27067038 -38.88973172
OS 43.26604758 -38.88233524
OS 43.26050022 -38.87308964
OS 43.25495286 -38.86291948
OS 43.2494055 -38.8509002
OS 43.24385814 -38.83795636
OS 43.23923534 -38.8231634
OS 43.23461254 -38.80744588
OS 43.2309143 -38.7908038
OS 43.22814062 -38.7723126
OS 43.2262915 -38.75289684
OS 43.22536694 -38.73255652
OS 43.22536694 -38.73163196
OS 43.22536694 -38.72700916
OS 43.22536694 -38.7214618
OS 43.2262915 -38.71314076
OS 43.22721606 -38.7029706
OS 43.22814062 -38.69187588
OS 43.22998974 -38.67893204
OS 43.23276342 -38.6659882
OS 43.2401599 -38.63640228
OS 43.2447827 -38.62160932
OS 43.25033006 -38.6058918
OS 43.25772654 -38.59109884
OS 43.26604758 -38.57723044
OS 43.27529318 -38.56336204
OS 43.28546334 -38.5504182
OS 43.2863879 -38.54949364
OS 43.28823702 -38.54764452
OS 43.29193526 -38.54487084
OS 43.29655806 -38.54024804
OS 43.30210542 -38.53562524
OS 43.3095019 -38.53007788
OS 43.31782294 -38.52360596
OS 43.3279931 -38.5180586
OS 43.33816326 -38.51158668
OS 43.35018254 -38.50603932
OS 43.36312638 -38.50049196
OS 43.37699478 -38.49586916
OS 43.39178774 -38.49124636
OS 43.40750526 -38.48847268
OS 43.42414734 -38.48662356
OS 43.44171398 -38.485699
OS 43.45095958 -38.485699
OS 43.4574315 -38.48662356
OE
OB 43.13938286 -38.48662356 I
OS 43.14955302 -38.48847268
OS 43.1615723 -38.49217092
OS 43.17451614 -38.49679372
OS 43.1893091 -38.50326564
OS 43.20502662 -38.51158668
OS 43.17636526 -38.58370236
OS 43.1754407 -38.5827778
OS 43.17174246 -38.58092868
OS 43.1661951 -38.578155
OS 43.15879862 -38.57538132
OS 43.15047758 -38.57260764
OS 43.14030742 -38.56983396
OS 43.13013726 -38.56798484
OS 43.1199671 -38.56706028
OS 43.1153443 -38.56706028
OS 43.1107215 -38.56798484
OS 43.10424958 -38.5689094
OS 43.09777766 -38.57075852
OS 43.08945662 -38.5735322
OS 43.08113558 -38.57723044
OS 43.0737391 -38.5827778
OS 43.07281454 -38.58370236
OS 43.07004086 -38.58555148
OS 43.06726718 -38.58924972
OS 43.06264438 -38.59387252
OS 43.05802158 -38.60034444
OS 43.05339878 -38.60774092
OS 43.04877598 -38.61606196
OS 43.04507774 -38.62623212
OS 43.04415318 -38.62808124
OS 43.04322862 -38.6336286
OS 43.0413795 -38.64194964
OS 43.03860582 -38.65304436
OS 43.03583214 -38.66691276
OS 43.03398302 -38.68263028
OS 43.03305846 -38.69927236
OS 43.0321339 -38.71776356
OS 43.0321339 -38.95999828
OS 42.9535463 -38.95999828
OS 42.9535463 -38.49586916
OS 43.02473742 -38.49586916
OS 43.02473742 -38.56613572
OS 43.02566198 -38.56521116
OS 43.02936022 -38.55873924
OS 43.03398302 -38.5504182
OS 43.0413795 -38.54024804
OS 43.04877598 -38.53007788
OS 43.05709702 -38.51898316
OS 43.06541806 -38.50973756
OS 43.0737391 -38.50234108
OS 43.07466366 -38.50141652
OS 43.07743734 -38.4995674
OS 43.0829847 -38.49679372
OS 43.08853206 -38.49402004
OS 43.09592854 -38.49124636
OS 43.10517414 -38.48847268
OS 43.11441974 -38.48662356
OS 43.1245899 -38.485699
OS 43.13106182 -38.485699
OS 43.13938286 -38.48662356
OE
OB 43.95022198 -38.95999828 I
OS 43.87533262 -38.95999828
OS 43.70059078 -38.49586916
OS 43.78380118 -38.49586916
OS 43.88365366 -38.77416172
OS 43.88365366 -38.77508628
OS 43.88457822 -38.77601084
OS 43.88550278 -38.77878452
OS 43.88642734 -38.7815582
OS 43.88920102 -38.7908038
OS 43.89289926 -38.80282308
OS 43.89752206 -38.81669148
OS 43.90306942 -38.832409
OS 43.90769222 -38.84997564
OS 43.91323958 -38.86754228
OS 43.91416414 -38.86569316
OS 43.9150887 -38.86107036
OS 43.91786238 -38.85367388
OS 43.92063606 -38.84257916
OS 43.92525886 -38.83055988
OS 43.92988166 -38.81484236
OS 43.93635358 -38.79820028
OS 43.9428255 -38.77970908
OS 44.04545166 -38.49586916
OS 44.12681294 -38.49586916
OS 43.95022198 -38.95999828
OE
OB 44.2756671 -38.40988508 I
OS 44.1970795 -38.40988508
OS 44.1970795 -38.32020276
OS 44.2756671 -38.32020276
OS 44.2756671 -38.40988508
OE
OB 44.5669035 -38.48662356 I
OS 44.5807719 -38.48754812
OS 44.59556486 -38.48939724
OS 44.61128238 -38.49309548
OS 44.62792446 -38.49679372
OS 44.64364198 -38.50234108
OS 44.64456654 -38.50234108
OS 44.6454911 -38.50326564
OS 44.6501139 -38.50511476
OS 44.65751038 -38.508813
OS 44.66675598 -38.5134358
OS 44.67692614 -38.51990772
OS 44.6870963 -38.5273042
OS 44.6963419 -38.53562524
OS 44.70466294 -38.54487084
OS 44.7055875 -38.5457954
OS 44.70743662 -38.54949364
OS 44.71113486 -38.55596556
OS 44.71575766 -38.56336204
OS 44.72038046 -38.57445676
OS 44.72500326 -38.58647604
OS 44.7287015 -38.60034444
OS 44.73239974 -38.61606196
OS 44.65566126 -38.62623212
OS 44.65566126 -38.624383
OS 44.6547367 -38.62068476
OS 44.65288758 -38.61421284
OS 44.6501139 -38.6058918
OS 44.6454911 -38.59757076
OS 44.63994374 -38.58832516
OS 44.63347182 -38.57907956
OS 44.62422622 -38.57075852
OS 44.62330166 -38.56983396
OS 44.61960342 -38.56798484
OS 44.61405606 -38.5642866
OS 44.60573502 -38.56058836
OS 44.59648942 -38.55689012
OS 44.58447014 -38.55319188
OS 44.56967718 -38.55134276
OS 44.55395966 -38.5504182
OS 44.54471406 -38.5504182
OS 44.53546846 -38.55134276
OS 44.52344918 -38.55226732
OS 44.5114299 -38.555041
OS 44.49848606 -38.55781468
OS 44.48646678 -38.56243748
OS 44.47629662 -38.5689094
OS 44.47537206 -38.56983396
OS 44.47259838 -38.57168308
OS 44.46890014 -38.57538132
OS 44.4652019 -38.58092868
OS 44.4605791 -38.58647604
OS 44.45688086 -38.59387252
OS 44.45410718 -38.60219356
OS 44.45318262 -38.6105146
OS 44.45318262 -38.61143916
OS 44.45318262 -38.61328828
OS 44.45410718 -38.61606196
OS 44.45410718 -38.6197602
OS 44.45688086 -38.6290058
OS 44.46242822 -38.6382514
OS 44.46335278 -38.63917596
OS 44.46427734 -38.64010052
OS 44.46612646 -38.6428742
OS 44.4698247 -38.64564788
OS 44.47352294 -38.64842156
OS 44.4790703 -38.6521198
OS 44.48554222 -38.65489348
OS 44.4929387 -38.65859172
OS 44.49386326 -38.65859172
OS 44.49571238 -38.65951628
OS 44.49941062 -38.66044084
OS 44.50588254 -38.66321452
OS 44.51512814 -38.6659882
OS 44.52714742 -38.66876188
OS 44.5345439 -38.67153556
OS 44.54286494 -38.67338468
OS 44.55211054 -38.67615836
OS 44.5622807 -38.67893204
OS 44.56320526 -38.67893204
OS 44.56597894 -38.6798566
OS 44.57060174 -38.68078116
OS 44.5761491 -38.68263028
OS 44.58262102 -38.6844794
OS 44.59094206 -38.68632852
OS 44.6085087 -38.69187588
OS 44.62792446 -38.69742324
OS 44.64734022 -38.70389516
OS 44.66490686 -38.71036708
OS 44.67230334 -38.71314076
OS 44.67877526 -38.71591444
OS 44.68062438 -38.716839
OS 44.68432262 -38.71868812
OS 44.68986998 -38.7214618
OS 44.69819102 -38.7260846
OS 44.70651206 -38.73163196
OS 44.7148331 -38.73902844
OS 44.72315414 -38.74734948
OS 44.73055062 -38.75659508
OS 44.73147518 -38.75751964
OS 44.7333243 -38.76121788
OS 44.73702254 -38.76676524
OS 44.74072078 -38.77508628
OS 44.74349446 -38.78525644
OS 44.7471927 -38.79635116
OS 44.74904182 -38.809295
OS 44.74996638 -38.82408796
OS 44.74996638 -38.82593708
OS 44.74996638 -38.83055988
OS 44.74904182 -38.83795636
OS 44.7471927 -38.84812652
OS 44.74441902 -38.85922124
OS 44.73979622 -38.87124052
OS 44.73424886 -38.88510892
OS 44.72685238 -38.89805276
OS 44.72592782 -38.89990188
OS 44.72222958 -38.90360012
OS 44.71760678 -38.91007204
OS 44.7102103 -38.91746852
OS 44.70004014 -38.92578956
OS 44.68894542 -38.93503516
OS 44.67600158 -38.9433562
OS 44.66028406 -38.95167724
OS 44.6593595 -38.95167724
OS 44.65843494 -38.9526018
OS 44.65288758 -38.95445092
OS 44.64364198 -38.9572246
OS 44.6316227 -38.96092284
OS 44.61682974 -38.96462108
OS 44.60018766 -38.96739476
OS 44.58262102 -38.96924388
OS 44.5622807 -38.97016844
OS 44.55395966 -38.97016844
OS 44.54748774 -38.96924388
OS 44.54009126 -38.96924388
OS 44.53084566 -38.96831932
OS 44.52160006 -38.96739476
OS 44.5114299 -38.96554564
OS 44.48924046 -38.96092284
OS 44.46612646 -38.95445092
OS 44.44393702 -38.94520532
OS 44.43376686 -38.93965796
OS 44.42452126 -38.93318604
OS 44.4235967 -38.93226148
OS 44.42267214 -38.93133692
OS 44.41712478 -38.92578956
OS 44.40880374 -38.91746852
OS 44.39955814 -38.90452468
OS 44.38938798 -38.88880716
OS 44.37921782 -38.87031596
OS 44.37089678 -38.84720196
OS 44.36442486 -38.82131428
OS 44.4420879 -38.809295
OS 44.4420879 -38.81021956
OS 44.4420879 -38.81114412
OS 44.44393702 -38.81669148
OS 44.44578614 -38.82593708
OS 44.44948438 -38.83610724
OS 44.45410718 -38.84720196
OS 44.45965454 -38.85922124
OS 44.46797558 -38.87124052
OS 44.47814574 -38.88141068
OS 44.47999486 -38.88233524
OS 44.4836931 -38.88510892
OS 44.49108958 -38.88880716
OS 44.50033518 -38.89342996
OS 44.51235446 -38.89805276
OS 44.52622286 -38.901751
OS 44.54286494 -38.90452468
OS 44.5622807 -38.90544924
OS 44.5715263 -38.90544924
OS 44.5807719 -38.90452468
OS 44.59279118 -38.90267556
OS 44.60573502 -38.89990188
OS 44.61960342 -38.89620364
OS 44.6316227 -38.89158084
OS 44.64271742 -38.88418436
OS 44.64364198 -38.8832598
OS 44.64734022 -38.88048612
OS 44.65103846 -38.87586332
OS 44.65658582 -38.8693914
OS 44.66120862 -38.86199492
OS 44.66583142 -38.85274932
OS 44.6686051 -38.84350372
OS 44.66952966 -38.832409
OS 44.66952966 -38.83148444
OS 44.66952966 -38.8277862
OS 44.6686051 -38.8231634
OS 44.66675598 -38.81669148
OS 44.6639823 -38.81021956
OS 44.6593595 -38.80374764
OS 44.65381214 -38.79635116
OS 44.6454911 -38.7908038
OS 44.64456654 -38.78987924
OS 44.64179286 -38.78895468
OS 44.63717006 -38.786181
OS 44.62977358 -38.78340732
OS 44.61867886 -38.77970908
OS 44.61220694 -38.7769354
OS 44.60481046 -38.77508628
OS 44.59648942 -38.7723126
OS 44.58724382 -38.76953892
OS 44.57707366 -38.76676524
OS 44.56505438 -38.76399156
OS 44.56412982 -38.76399156
OS 44.56135614 -38.763067
OS 44.55673334 -38.76214244
OS 44.55118598 -38.76029332
OS 44.5437895 -38.7584442
OS 44.53546846 -38.75567052
OS 44.51790182 -38.75104772
OS 44.4975615 -38.7445758
OS 44.47814574 -38.73902844
OS 44.45965454 -38.73255652
OS 44.4513335 -38.72885828
OS 44.44486158 -38.7260846
OS 44.44301246 -38.72516004
OS 44.43931422 -38.72331092
OS 44.43376686 -38.71961268
OS 44.42637038 -38.71498988
OS 44.41804934 -38.70851796
OS 44.4097283 -38.70112148
OS 44.40140726 -38.69280044
OS 44.39401078 -38.68263028
OS 44.39308622 -38.68170572
OS 44.3912371 -38.67800748
OS 44.38846342 -38.67153556
OS 44.38568974 -38.66413908
OS 44.38291606 -38.65489348
OS 44.38014238 -38.64379876
OS 44.37829326 -38.63270404
OS 44.3773687 -38.6197602
OS 44.3773687 -38.61791108
OS 44.3773687 -38.61421284
OS 44.37829326 -38.60866548
OS 44.37921782 -38.60034444
OS 44.38106694 -38.5920234
OS 44.38291606 -38.58185324
OS 44.3866143 -38.57260764
OS 44.3912371 -38.56243748
OS 44.39216166 -38.56151292
OS 44.39401078 -38.55781468
OS 44.39678446 -38.55319188
OS 44.40140726 -38.54671996
OS 44.40695462 -38.54024804
OS 44.41342654 -38.531927
OS 44.42082302 -38.52453052
OS 44.43006862 -38.5180586
OS 44.43099318 -38.51713404
OS 44.43376686 -38.51620948
OS 44.4374651 -38.5134358
OS 44.44301246 -38.51066212
OS 44.45040894 -38.50696388
OS 44.45872998 -38.50326564
OS 44.46890014 -38.4995674
OS 44.47999486 -38.49586916
OS 44.48184398 -38.4949446
OS 44.48554222 -38.49402004
OS 44.49201414 -38.49217092
OS 44.50033518 -38.4903218
OS 44.51050534 -38.48847268
OS 44.52160006 -38.48754812
OS 44.5345439 -38.485699
OS 44.55673334 -38.485699
OS 44.5669035 -38.48662356
OE
OB 33.15968222 -38.32112732 I
OS 33.17539974 -38.32205188
OS 33.19204182 -38.32297644
OS 33.20775934 -38.32482556
OS 33.22162774 -38.32667468
OS 33.22347686 -38.32667468
OS 33.22994878 -38.3285238
OS 33.23826982 -38.33037292
OS 33.24936454 -38.3331466
OS 33.26138382 -38.3377694
OS 33.27432766 -38.34331676
OS 33.28819606 -38.34978868
OS 33.30021534 -38.35718516
OS 33.30206446 -38.35810972
OS 33.3057627 -38.3608834
OS 33.31131006 -38.36643076
OS 33.31870654 -38.37290268
OS 33.32702758 -38.38122372
OS 33.33534862 -38.39231844
OS 33.34459422 -38.40433772
OS 33.3519907 -38.41820612
OS 33.35291526 -38.42005524
OS 33.35476438 -38.42467804
OS 33.35846262 -38.43299908
OS 33.36216086 -38.4440938
OS 33.36493454 -38.45703764
OS 33.36863278 -38.4718306
OS 33.3704819 -38.48847268
OS 33.37140646 -38.50603932
OS 33.37140646 -38.50696388
OS 33.37140646 -38.50973756
OS 33.37140646 -38.5134358
OS 33.3704819 -38.51990772
OS 33.36955734 -38.52637964
OS 33.36863278 -38.53470068
OS 33.36678366 -38.54394628
OS 33.36493454 -38.55411644
OS 33.35846262 -38.57538132
OS 33.35476438 -38.58647604
OS 33.34921702 -38.59849532
OS 33.3427451 -38.6105146
OS 33.33627318 -38.62160932
OS 33.32795214 -38.63270404
OS 33.31870654 -38.64379876
OS 33.31778198 -38.64472332
OS 33.31593286 -38.64657244
OS 33.31315918 -38.64934612
OS 33.30853638 -38.6521198
OS 33.30298902 -38.6567426
OS 33.29559254 -38.6613654
OS 33.28634694 -38.66691276
OS 33.27617678 -38.67153556
OS 33.2641575 -38.67708292
OS 33.2502891 -38.68263028
OS 33.23549614 -38.68725308
OS 33.2179295 -38.69095132
OS 33.1994383 -38.69464956
OS 33.17909798 -38.69742324
OS 33.15598398 -38.69927236
OS 33.13194542 -38.70019692
OS 32.9682983 -38.70019692
OS 32.9682983 -38.95999828
OS 32.88323878 -38.95999828
OS 32.88323878 -38.32020276
OS 33.14581382 -38.32020276
OS 33.15968222 -38.32112732
OE
OB 32.75195126 -38.98403684 I
OS 32.75195126 -38.9849614
OS 32.75195126 -38.98773508
OS 32.75195126 -38.99235788
OS 32.75195126 -38.99790524
OS 32.7510267 -39.00530172
OS 32.7510267 -39.0126982
OS 32.74917758 -39.0311894
OS 32.7464039 -39.05060516
OS 32.74270566 -39.07094548
OS 32.7371583 -39.08851212
OS 32.73346006 -39.09683316
OS 32.72976182 -39.10330508
OS 32.72976182 -39.10422964
OS 32.72883726 -39.1051542
OS 32.72421446 -39.109777
OS 32.71681798 -39.11717348
OS 32.70757238 -39.12549452
OS 32.69462854 -39.13381556
OS 32.67798646 -39.14028748
OS 32.6585707 -39.14583484
OS 32.64747598 -39.1467594
OS 32.6354567 -39.14768396
OS 32.62990934 -39.14768396
OS 32.62436198 -39.1467594
OS 32.61604094 -39.1467594
OS 32.60679534 -39.14583484
OS 32.59662518 -39.14398572
OS 32.57443574 -39.13843836
OS 32.5892287 -39.07187004
OS 32.59015326 -39.07187004
OS 32.59292694 -39.0727946
OS 32.59754974 -39.07371916
OS 32.60217254 -39.07464372
OS 32.61419182 -39.0774174
OS 32.61973918 -39.07834196
OS 32.62898478 -39.07834196
OS 32.63360758 -39.0774174
OS 32.63915494 -39.07649284
OS 32.6447023 -39.07464372
OS 32.65024966 -39.07094548
OS 32.65672158 -39.06724724
OS 32.66134438 -39.06169988
OS 32.66226894 -39.06077532
OS 32.6631935 -39.05800164
OS 32.66504262 -39.05337884
OS 32.6678163 -39.04598236
OS 32.66966542 -39.0358122
OS 32.67058998 -39.02841572
OS 32.67151454 -39.0219438
OS 32.6724391 -39.01362276
OS 32.6724391 -39.0034526
OS 32.67336366 -38.99328244
OS 32.67336366 -38.98218772
OS 32.67336366 -38.49586916
OS 32.75195126 -38.49586916
OS 32.75195126 -38.98403684
OE
OB 33.77174094 -38.3100326 I
OS 33.78006198 -38.31095716
OS 33.79023214 -38.31188172
OS 33.8004023 -38.31280628
OS 33.81242158 -38.31557996
OS 33.8373847 -38.32112732
OS 33.8651215 -38.32944836
OS 33.8789899 -38.33499572
OS 33.89193374 -38.34146764
OS 33.90487758 -38.34978868
OS 33.91782142 -38.35810972
OS 33.91874598 -38.35903428
OS 33.9205951 -38.35995884
OS 33.92429334 -38.36273252
OS 33.92891614 -38.36735532
OS 33.93353894 -38.37197812
OS 33.94001086 -38.37845004
OS 33.94648278 -38.38584652
OS 33.95387926 -38.393243
OS 33.96127574 -38.4024886
OS 33.96867222 -38.41358332
OS 33.97699326 -38.42467804
OS 33.98438974 -38.43669732
OS 33.99086166 -38.45056572
OS 33.99825814 -38.46443412
OS 34.0038055 -38.47922708
OS 34.00935286 -38.49586916
OS 33.92614246 -38.51528492
OS 33.92614246 -38.51436036
OS 33.9252179 -38.51251124
OS 33.92336878 -38.508813
OS 33.92151966 -38.5041902
OS 33.91967054 -38.49864284
OS 33.91689686 -38.49124636
OS 33.90950038 -38.4764534
OS 33.90025478 -38.45981132
OS 33.88916006 -38.44316924
OS 33.87529166 -38.42745172
OS 33.8604987 -38.41358332
OS 33.85864958 -38.4117342
OS 33.85310222 -38.40803596
OS 33.84385662 -38.40341316
OS 33.83183734 -38.39694124
OS 33.81611982 -38.39139388
OS 33.79855318 -38.38584652
OS 33.7772883 -38.38214828
OS 33.7541743 -38.38122372
OS 33.74677782 -38.38122372
OS 33.74215502 -38.38214828
OS 33.7356831 -38.38214828
OS 33.72828662 -38.38307284
OS 33.71071998 -38.38584652
OS 33.69130422 -38.38954476
OS 33.6709639 -38.39601668
OS 33.64969902 -38.40526228
OS 33.63028326 -38.41728156
OS 33.6293587 -38.41728156
OS 33.62843414 -38.41913068
OS 33.62196222 -38.42375348
OS 33.61364118 -38.43114996
OS 33.60347102 -38.44224468
OS 33.59145174 -38.45611308
OS 33.58035702 -38.4718306
OS 33.57018686 -38.49124636
OS 33.56094126 -38.51251124
OS 33.56094126 -38.5134358
OS 33.5600167 -38.51528492
OS 33.55909214 -38.5180586
OS 33.55816758 -38.5226814
OS 33.55631846 -38.52822876
OS 33.55446934 -38.53470068
OS 33.55169566 -38.5504182
OS 33.54799742 -38.5689094
OS 33.54429918 -38.58924972
OS 33.54245006 -38.61143916
OS 33.5415255 -38.63547772
OS 33.5415255 -38.63640228
OS 33.5415255 -38.63917596
OS 33.5415255 -38.64379876
OS 33.5415255 -38.64934612
OS 33.54245006 -38.65581804
OS 33.54245006 -38.66413908
OS 33.54337462 -38.67338468
OS 33.54429918 -38.68355484
OS 33.54707286 -38.70574428
OS 33.55169566 -38.72978284
OS 33.55724302 -38.7538214
OS 33.5646395 -38.77785996
OS 33.5646395 -38.77878452
OS 33.56556406 -38.78063364
OS 33.56741318 -38.78340732
OS 33.5692623 -38.78803012
OS 33.57480966 -38.79912484
OS 33.5831307 -38.81206868
OS 33.59330086 -38.82686164
OS 33.6062447 -38.84257916
OS 33.62103766 -38.85644756
OS 33.6386043 -38.8693914
OS 33.63952886 -38.8693914
OS 33.64137798 -38.87031596
OS 33.64415166 -38.87216508
OS 33.6478499 -38.8740142
OS 33.6524727 -38.87586332
OS 33.65802006 -38.878637
OS 33.6709639 -38.88418436
OS 33.68760598 -38.88973172
OS 33.70609718 -38.89435452
OS 33.7264375 -38.89805276
OS 33.74770238 -38.89897732
OS 33.7541743 -38.89897732
OS 33.75972166 -38.89805276
OS 33.76619358 -38.89805276
OS 33.7726655 -38.8971282
OS 33.78930758 -38.89342996
OS 33.80872334 -38.88880716
OS 33.8281391 -38.88141068
OS 33.84847942 -38.87124052
OS 33.85864958 -38.86569316
OS 33.86789518 -38.85829668
OS 33.86881974 -38.85737212
OS 33.8697443 -38.85644756
OS 33.87251798 -38.85367388
OS 33.87621622 -38.8509002
OS 33.87991446 -38.8462774
OS 33.88453726 -38.84073004
OS 33.89008462 -38.83518268
OS 33.89470742 -38.8277862
OS 33.90025478 -38.81946516
OS 33.9067267 -38.81021956
OS 33.91227406 -38.80097396
OS 33.91782142 -38.78987924
OS 33.92244422 -38.77785996
OS 33.92706702 -38.76491612
OS 33.93168982 -38.75104772
OS 33.93538806 -38.73625476
OS 34.02044758 -38.75751964
OS 34.02044758 -38.7584442
OS 34.01952302 -38.76214244
OS 34.0176739 -38.7676898
OS 34.01490022 -38.77508628
OS 34.01212654 -38.78340732
OS 34.0084283 -38.79357748
OS 34.0038055 -38.8046722
OS 33.99825814 -38.81669148
OS 33.9853143 -38.84257916
OS 33.96867222 -38.86846684
OS 33.95850206 -38.88141068
OS 33.9483319 -38.89435452
OS 33.93723718 -38.90544924
OS 33.92429334 -38.91654396
OS 33.92336878 -38.91746852
OS 33.92151966 -38.91931764
OS 33.91689686 -38.92116676
OS 33.91227406 -38.924865
OS 33.90487758 -38.9294878
OS 33.8974811 -38.9341106
OS 33.88731094 -38.9387334
OS 33.87714078 -38.9433562
OS 33.8651215 -38.94890356
OS 33.85217766 -38.95352636
OS 33.83830926 -38.95814916
OS 33.8235163 -38.96277196
OS 33.80779878 -38.9664702
OS 33.7911567 -38.96831932
OS 33.77359006 -38.97016844
OS 33.75509886 -38.971093
OS 33.7449287 -38.971093
OS 33.73753222 -38.97016844
OS 33.72921118 -38.97016844
OS 33.71904102 -38.96924388
OS 33.7079463 -38.96739476
OS 33.69500246 -38.96554564
OS 33.66819022 -38.96092284
OS 33.64045342 -38.95352636
OS 33.61271662 -38.9433562
OS 33.59977278 -38.93688428
OS 33.58682894 -38.9294878
OS 33.58590438 -38.92856324
OS 33.58405526 -38.92763868
OS 33.58035702 -38.924865
OS 33.57665878 -38.92116676
OS 33.57111142 -38.91746852
OS 33.5646395 -38.91192116
OS 33.55724302 -38.90544924
OS 33.54984654 -38.89805276
OS 33.54245006 -38.88973172
OS 33.53412902 -38.88141068
OS 33.51748694 -38.8601458
OS 33.50176942 -38.83518268
OS 33.48790102 -38.80744588
OS 33.48790102 -38.80652132
OS 33.4860519 -38.80374764
OS 33.48512734 -38.79912484
OS 33.48235366 -38.79357748
OS 33.48050454 -38.786181
OS 33.47773086 -38.7769354
OS 33.47403262 -38.76676524
OS 33.47125894 -38.75567052
OS 33.46848526 -38.74365124
OS 33.46478702 -38.72978284
OS 33.46016422 -38.70112148
OS 33.45646598 -38.66876188
OS 33.45461686 -38.63547772
OS 33.45461686 -38.63455316
OS 33.45461686 -38.63085492
OS 33.45461686 -38.62530756
OS 33.45554142 -38.61883564
OS 33.45554142 -38.60959004
OS 33.45646598 -38.60034444
OS 33.45739054 -38.58832516
OS 33.45923966 -38.57630588
OS 33.46386246 -38.54949364
OS 33.47033438 -38.51990772
OS 33.47957998 -38.4903218
OS 33.49252382 -38.46166044
OS 33.49344838 -38.46073588
OS 33.49437294 -38.4579622
OS 33.49622206 -38.45426396
OS 33.4999203 -38.44964116
OS 33.50361854 -38.44316924
OS 33.50824134 -38.43577276
OS 33.52026062 -38.41913068
OS 33.53597814 -38.40063948
OS 33.55446934 -38.38214828
OS 33.57573422 -38.36365708
OS 33.60069734 -38.34793956
OS 33.6016219 -38.347015
OS 33.60439558 -38.34609044
OS 33.60809382 -38.34424132
OS 33.61271662 -38.34146764
OS 33.6201131 -38.33869396
OS 33.62750958 -38.33592028
OS 33.63675518 -38.33222204
OS 33.64692534 -38.3285238
OS 33.65802006 -38.32482556
OS 33.67003934 -38.32112732
OS 33.69592702 -38.31557996
OS 33.72551294 -38.31095716
OS 33.75602342 -38.30910804
OS 33.76526902 -38.30910804
OS 33.77174094 -38.3100326
OE
OB 35.15858094 -39.1375138 I
OS 34.63805366 -39.1375138
OS 34.63805366 -39.08111564
OS 35.15858094 -39.08111564
OS 35.15858094 -39.1375138
OE
OB 34.37917686 -38.32112732 I
OS 34.38657334 -38.32112732
OS 34.40321542 -38.32297644
OS 34.42170662 -38.32482556
OS 34.44112238 -38.3285238
OS 34.46053814 -38.3331466
OS 34.47810478 -38.33961852
OS 34.47902934 -38.33961852
OS 34.4799539 -38.34054308
OS 34.48550126 -38.34331676
OS 34.4938223 -38.34793956
OS 34.5030679 -38.35441148
OS 34.51416262 -38.36273252
OS 34.5261819 -38.37290268
OS 34.53727662 -38.38584652
OS 34.54744678 -38.39971492
OS 34.54837134 -38.40156404
OS 34.55114502 -38.4071114
OS 34.55576782 -38.41450788
OS 34.56039062 -38.4256026
OS 34.56501342 -38.43854644
OS 34.56963622 -38.45241484
OS 34.5724099 -38.46813236
OS 34.57333446 -38.48384988
OS 34.57333446 -38.485699
OS 34.57333446 -38.4903218
OS 34.5724099 -38.49864284
OS 34.57056078 -38.508813
OS 34.5677871 -38.52083228
OS 34.5631643 -38.53377612
OS 34.55761694 -38.54671996
OS 34.55022046 -38.56058836
OS 34.5492959 -38.56243748
OS 34.54652222 -38.56613572
OS 34.54097486 -38.5735322
OS 34.53357838 -38.58092868
OS 34.52433278 -38.59017428
OS 34.51323806 -38.60034444
OS 34.49936966 -38.60959004
OS 34.48365214 -38.61883564
OS 34.4845767 -38.61883564
OS 34.48642582 -38.6197602
OS 34.4891995 -38.62068476
OS 34.49289774 -38.62253388
OS 34.50399246 -38.62623212
OS 34.5169363 -38.63270404
OS 34.5308047 -38.64102508
OS 34.54652222 -38.65119524
OS 34.56039062 -38.66321452
OS 34.57333446 -38.67800748
OS 34.57425902 -38.6798566
OS 34.57795726 -38.68540396
OS 34.58350462 -38.693725
OS 34.58905198 -38.70481972
OS 34.59459934 -38.71961268
OS 34.6001467 -38.7353302
OS 34.60384494 -38.7538214
OS 34.6047695 -38.77416172
OS 34.6047695 -38.77508628
OS 34.6047695 -38.77601084
OS 34.6047695 -38.7815582
OS 34.60384494 -38.7908038
OS 34.60199582 -38.80189852
OS 34.6001467 -38.81484236
OS 34.59644846 -38.82871076
OS 34.59182566 -38.84350372
OS 34.58535374 -38.85829668
OS 34.58442918 -38.8601458
OS 34.5816555 -38.8647686
OS 34.57795726 -38.87124052
OS 34.5724099 -38.88048612
OS 34.56501342 -38.88973172
OS 34.55761694 -38.89990188
OS 34.54837134 -38.91007204
OS 34.53820118 -38.91839308
OS 34.53727662 -38.91931764
OS 34.53357838 -38.92209132
OS 34.52710646 -38.92578956
OS 34.51878542 -38.9294878
OS 34.50861526 -38.93503516
OS 34.49659598 -38.94058252
OS 34.48365214 -38.94520532
OS 34.46793462 -38.94982812
OS 34.4660855 -38.94982812
OS 34.46053814 -38.95167724
OS 34.45129254 -38.9526018
OS 34.43927326 -38.95445092
OS 34.4244803 -38.95630004
OS 34.40691366 -38.95814916
OS 34.3874979 -38.95907372
OS 34.36530846 -38.95999828
OS 34.12122462 -38.95999828
OS 34.12122462 -38.32020276
OS 34.37270494 -38.32020276
OS 34.37917686 -38.32112732
OE
OB 31.74233174 -38.95999828 I
OS 31.65264942 -38.95999828
OS 31.65264942 -38.87031596
OS 31.74233174 -38.87031596
OS 31.74233174 -38.95999828
OE
OB 31.52968294 -38.42745172 I
OS 31.50841806 -38.54671996
OS 31.45941638 -38.54671996
OS 31.44000062 -38.42745172
OS 31.44000062 -38.32020276
OS 31.52968294 -38.32020276
OS 31.52968294 -38.42745172
OE
OB 32.0992119 -38.48662356 I
OS 32.10568382 -38.48754812
OS 32.11955222 -38.48939724
OS 32.1361943 -38.49309548
OS 32.15376094 -38.49864284
OS 32.17132758 -38.50696388
OS 32.18889422 -38.51713404
OS 32.18981878 -38.51713404
OS 32.19074334 -38.51898316
OS 32.1962907 -38.5226814
OS 32.20461174 -38.53007788
OS 32.2147819 -38.53932348
OS 32.22587662 -38.55134276
OS 32.23697134 -38.56613572
OS 32.24806606 -38.58370236
OS 32.25731166 -38.60311812
OS 32.25731166 -38.60404268
OS 32.25823622 -38.6058918
OS 32.25916078 -38.60866548
OS 32.2610099 -38.61236372
OS 32.26285902 -38.61791108
OS 32.26470814 -38.624383
OS 32.26933094 -38.63917596
OS 32.27395374 -38.65766716
OS 32.27765198 -38.67800748
OS 32.28042566 -38.70112148
OS 32.28135022 -38.72516004
OS 32.28135022 -38.7260846
OS 32.28135022 -38.72793372
OS 32.28135022 -38.73163196
OS 32.28135022 -38.73717932
OS 32.28042566 -38.74365124
OS 32.28042566 -38.75104772
OS 32.27857654 -38.7676898
OS 32.2748783 -38.78803012
OS 32.2702555 -38.809295
OS 32.26378358 -38.83148444
OS 32.25546254 -38.85367388
OS 32.25546254 -38.85459844
OS 32.25453798 -38.85644756
OS 32.25268886 -38.85922124
OS 32.25083974 -38.86291948
OS 32.24436782 -38.87308964
OS 32.23604678 -38.88603348
OS 32.22587662 -38.89990188
OS 32.21293278 -38.91377028
OS 32.19813982 -38.92763868
OS 32.18057318 -38.94058252
OS 32.17964862 -38.94058252
OS 32.17872406 -38.94150708
OS 32.17595038 -38.9433562
OS 32.17225214 -38.94520532
OS 32.16300654 -38.94982812
OS 32.1500627 -38.95537548
OS 32.13434518 -38.96092284
OS 32.1177031 -38.96554564
OS 32.09828734 -38.96924388
OS 32.07887158 -38.97016844
OS 32.07239966 -38.97016844
OS 32.06500318 -38.96924388
OS 32.05575758 -38.96831932
OS 32.04466286 -38.9664702
OS 32.03264358 -38.96369652
OS 32.0206243 -38.95999828
OS 32.00860502 -38.95445092
OS 32.00768046 -38.95352636
OS 32.00305766 -38.95167724
OS 31.9975103 -38.947979
OS 31.99011382 -38.94243164
OS 31.98271734 -38.93688428
OS 31.97347174 -38.9294878
OS 31.9651507 -38.92116676
OS 31.95775422 -38.91192116
OS 31.95775422 -39.1375138
OS 31.87916662 -39.1375138
OS 31.87916662 -38.49586916
OS 31.95035774 -38.49586916
OS 31.95035774 -38.55689012
OS 31.9512823 -38.555041
OS 31.95498054 -38.55134276
OS 31.95960334 -38.54487084
OS 31.96699982 -38.53747436
OS 31.97532086 -38.52822876
OS 31.98456646 -38.51990772
OS 31.99566118 -38.51158668
OS 32.0067559 -38.5041902
OS 32.00860502 -38.50326564
OS 32.01230326 -38.50141652
OS 32.01969974 -38.49864284
OS 32.02894534 -38.4949446
OS 32.04004006 -38.49124636
OS 32.0529839 -38.48847268
OS 32.06777686 -38.48662356
OS 32.08441894 -38.485699
OS 32.0945891 -38.485699
OS 32.0992119 -38.48662356
OE
OB 32.5614919 -38.48662356 I
OS 32.57166206 -38.48847268
OS 32.58368134 -38.49217092
OS 32.59662518 -38.49679372
OS 32.61141814 -38.50326564
OS 32.62713566 -38.51158668
OS 32.5984743 -38.58370236
OS 32.59754974 -38.5827778
OS 32.5938515 -38.58092868
OS 32.58830414 -38.578155
OS 32.58090766 -38.57538132
OS 32.57258662 -38.57260764
OS 32.56241646 -38.56983396
OS 32.5522463 -38.56798484
OS 32.54207614 -38.56706028
OS 32.53745334 -38.56706028
OS 32.53283054 -38.56798484
OS 32.52635862 -38.5689094
OS 32.5198867 -38.57075852
OS 32.51156566 -38.5735322
OS 32.50324462 -38.57723044
OS 32.49584814 -38.5827778
OS 32.49492358 -38.58370236
OS 32.4921499 -38.58555148
OS 32.48937622 -38.58924972
OS 32.48475342 -38.59387252
OS 32.48013062 -38.60034444
OS 32.47550782 -38.60774092
OS 32.47088502 -38.61606196
OS 32.46718678 -38.62623212
OS 32.46626222 -38.62808124
OS 32.46533766 -38.6336286
OS 32.46348854 -38.64194964
OS 32.46071486 -38.65304436
OS 32.45794118 -38.66691276
OS 32.45609206 -38.68263028
OS 32.4551675 -38.69927236
OS 32.45424294 -38.71776356
OS 32.45424294 -38.95999828
OS 32.37565534 -38.95999828
OS 32.37565534 -38.49586916
OS 32.44684646 -38.49586916
OS 32.44684646 -38.56613572
OS 32.44777102 -38.56521116
OS 32.45146926 -38.55873924
OS 32.45609206 -38.5504182
OS 32.46348854 -38.54024804
OS 32.47088502 -38.53007788
OS 32.47920606 -38.51898316
OS 32.4875271 -38.50973756
OS 32.49584814 -38.50234108
OS 32.4967727 -38.50141652
OS 32.49954638 -38.4995674
OS 32.50509374 -38.49679372
OS 32.5106411 -38.49402004
OS 32.51803758 -38.49124636
OS 32.52728318 -38.48847268
OS 32.53652878 -38.48662356
OS 32.54669894 -38.485699
OS 32.55317086 -38.485699
OS 32.5614919 -38.48662356
OE
OB 32.75195126 -38.4117342 I
OS 32.67336366 -38.4117342
OS 32.67336366 -38.32020276
OS 32.75195126 -38.32020276
OS 32.75195126 -38.4117342
OE
OB 36.56668582 -38.95999828 I
OS 36.47885262 -38.95999828
OS 36.1441619 -38.4579622
OS 36.1441619 -38.95999828
OS 36.06280062 -38.95999828
OS 36.06280062 -38.32020276
OS 36.14970926 -38.32020276
OS 36.48532454 -38.8231634
OS 36.48532454 -38.32020276
OS 36.56668582 -38.32020276
OS 36.56668582 -38.95999828
OE
OB 35.74382742 -38.32112732 I
OS 35.75954494 -38.32205188
OS 35.77618702 -38.32297644
OS 35.79190454 -38.32482556
OS 35.80577294 -38.32667468
OS 35.80762206 -38.32667468
OS 35.81409398 -38.3285238
OS 35.82241502 -38.33037292
OS 35.83350974 -38.3331466
OS 35.84552902 -38.3377694
OS 35.85847286 -38.34331676
OS 35.87234126 -38.34978868
OS 35.88436054 -38.35718516
OS 35.88620966 -38.35810972
OS 35.8899079 -38.3608834
OS 35.89545526 -38.36643076
OS 35.90285174 -38.37290268
OS 35.91117278 -38.38122372
OS 35.91949382 -38.39231844
OS 35.92873942 -38.40433772
OS 35.9361359 -38.41820612
OS 35.93706046 -38.42005524
OS 35.93890958 -38.42467804
OS 35.94260782 -38.43299908
OS 35.94630606 -38.4440938
OS 35.94907974 -38.45703764
OS 35.95277798 -38.4718306
OS 35.9546271 -38.48847268
OS 35.95555166 -38.50603932
OS 35.95555166 -38.50696388
OS 35.95555166 -38.50973756
OS 35.95555166 -38.5134358
OS 35.9546271 -38.51990772
OS 35.95370254 -38.52637964
OS 35.95277798 -38.53470068
OS 35.95092886 -38.54394628
OS 35.94907974 -38.55411644
OS 35.94260782 -38.57538132
OS 35.93890958 -38.58647604
OS 35.93336222 -38.59849532
OS 35.9268903 -38.6105146
OS 35.92041838 -38.62160932
OS 35.91209734 -38.63270404
OS 35.90285174 -38.64379876
OS 35.90192718 -38.64472332
OS 35.90007806 -38.64657244
OS 35.89730438 -38.64934612
OS 35.89268158 -38.6521198
OS 35.88713422 -38.6567426
OS 35.87973774 -38.6613654
OS 35.87049214 -38.66691276
OS 35.86032198 -38.67153556
OS 35.8483027 -38.67708292
OS 35.8344343 -38.68263028
OS 35.81964134 -38.68725308
OS 35.8020747 -38.69095132
OS 35.7835835 -38.69464956
OS 35.76324318 -38.69742324
OS 35.74012918 -38.69927236
OS 35.71609062 -38.70019692
OS 35.5524435 -38.70019692
OS 35.5524435 -38.95999828
OS 35.46738398 -38.95999828
OS 35.46738398 -38.32020276
OS 35.72995902 -38.32020276
OS 35.74382742 -38.32112732
OE
OB 36.76916446 -38.42745172 I
OS 36.74789958 -38.54671996
OS 36.6988979 -38.54671996
OS 36.67948214 -38.42745172
OS 36.67948214 -38.32020276
OS 36.76916446 -38.32020276
OS 36.76916446 -38.42745172
OE
OB 38.2382903 -38.39601668 I
OS 37.86014526 -38.39601668
OS 37.86014526 -38.59109884
OS 38.21425174 -38.59109884
OS 38.21425174 -38.66691276
OS 37.86014526 -38.66691276
OS 37.86014526 -38.88418436
OS 38.25308326 -38.88418436
OS 38.25308326 -38.95999828
OS 37.77508574 -38.95999828
OS 37.77508574 -38.32020276
OS 38.2382903 -38.32020276
OS 38.2382903 -38.39601668
OE
OB 37.4339231 -38.32112732 I
OS 37.44224414 -38.32112732
OS 37.4616599 -38.32205188
OS 37.48200022 -38.32482556
OS 37.50418966 -38.32759924
OS 37.52452998 -38.33222204
OS 37.53470014 -38.33499572
OS 37.54302118 -38.3377694
OS 37.54394574 -38.3377694
OS 37.5448703 -38.33869396
OS 37.55041766 -38.34146764
OS 37.5587387 -38.34516588
OS 37.56890886 -38.3516378
OS 37.58000358 -38.35995884
OS 37.59202286 -38.37105356
OS 37.60311758 -38.3839974
OS 37.6142123 -38.39879036
OS 37.6142123 -38.39971492
OS 37.61513686 -38.40063948
OS 37.6188351 -38.40618684
OS 37.62253334 -38.41543244
OS 37.6280807 -38.42745172
OS 37.6327035 -38.44132012
OS 37.6373263 -38.4579622
OS 37.64009998 -38.47552884
OS 37.64102454 -38.4949446
OS 37.64102454 -38.49586916
OS 37.64102454 -38.49771828
OS 37.64102454 -38.50141652
OS 37.64009998 -38.50603932
OS 37.64009998 -38.51251124
OS 37.63917542 -38.51898316
OS 37.63547718 -38.53470068
OS 37.62992982 -38.55319188
OS 37.62253334 -38.57260764
OS 37.61143862 -38.5920234
OS 37.60404214 -38.601269
OS 37.59664566 -38.6105146
OS 37.5957211 -38.61143916
OS 37.59479654 -38.61236372
OS 37.59202286 -38.6151374
OS 37.58832462 -38.61791108
OS 37.58370182 -38.62160932
OS 37.57815446 -38.62530756
OS 37.57075798 -38.62993036
OS 37.5633615 -38.63547772
OS 37.5541159 -38.64010052
OS 37.54394574 -38.64472332
OS 37.53285102 -38.65027068
OS 37.52083174 -38.65489348
OS 37.50696334 -38.65859172
OS 37.49309494 -38.66321452
OS 37.47737742 -38.6659882
OS 37.46073534 -38.66876188
OS 37.46258446 -38.66968644
OS 37.4662827 -38.67153556
OS 37.47183006 -38.6752338
OS 37.47922654 -38.67893204
OS 37.49586862 -38.6891022
OS 37.50418966 -38.69557412
OS 37.51158614 -38.70112148
OS 37.51343526 -38.7029706
OS 37.51805806 -38.7075934
OS 37.52545454 -38.71498988
OS 37.53470014 -38.72423548
OS 37.5448703 -38.73717932
OS 37.55688958 -38.75104772
OS 37.56890886 -38.7676898
OS 37.5818527 -38.786181
OS 37.69187534 -38.95999828
OS 37.5864755 -38.95999828
OS 37.50234054 -38.82686164
OS 37.50234054 -38.82593708
OS 37.50049142 -38.82408796
OS 37.4986423 -38.82131428
OS 37.49586862 -38.81761604
OS 37.4893967 -38.80744588
OS 37.48107566 -38.79450204
OS 37.4709055 -38.78063364
OS 37.46073534 -38.76584068
OS 37.45056518 -38.75197228
OS 37.44131958 -38.73902844
OS 37.44039502 -38.73810388
OS 37.43762134 -38.73440564
OS 37.43299854 -38.72885828
OS 37.42652662 -38.72238636
OS 37.41265822 -38.70851796
OS 37.40526174 -38.70204604
OS 37.39786526 -38.69649868
OS 37.3969407 -38.69557412
OS 37.39509158 -38.69464956
OS 37.39139334 -38.69280044
OS 37.38584598 -38.69002676
OS 37.38029862 -38.68725308
OS 37.3738267 -38.6844794
OS 37.35903374 -38.6798566
OS 37.35810918 -38.6798566
OS 37.35626006 -38.67893204
OS 37.35256182 -38.67893204
OS 37.34793902 -38.67800748
OS 37.3414671 -38.67708292
OS 37.33407062 -38.67708292
OS 37.32390046 -38.67615836
OS 37.21480238 -38.67615836
OS 37.21480238 -38.95999828
OS 37.12974286 -38.95999828
OS 37.12974286 -38.32020276
OS 37.42652662 -38.32020276
OS 37.4339231 -38.32112732
OE
OB 35.31760526 -38.95999828 I
OS 35.23254574 -38.95999828
OS 35.23254574 -38.32020276
OS 35.31760526 -38.32020276
OS 35.31760526 -38.95999828
OE
OB 42.12051774 -38.66413908 H
OS 41.95224782 -38.66413908
OS 41.95224782 -38.88418436
OS 42.13438614 -38.88418436
OS 42.1538019 -38.8832598
OS 42.16212294 -38.88233524
OS 42.16951942 -38.88141068
OS 42.17044398 -38.88141068
OS 42.17414222 -38.88048612
OS 42.17968958 -38.87956156
OS 42.1861615 -38.87771244
OS 42.20187902 -38.87216508
OS 42.21759654 -38.8647686
OS 42.2185211 -38.86384404
OS 42.22129478 -38.86199492
OS 42.22499302 -38.85922124
OS 42.22961582 -38.855523
OS 42.23423862 -38.84997564
OS 42.24071054 -38.84442828
OS 42.24533334 -38.8370318
OS 42.2508807 -38.82871076
OS 42.25180526 -38.8277862
OS 42.25272982 -38.82501252
OS 42.25457894 -38.81946516
OS 42.25735262 -38.81299324
OS 42.2601263 -38.80559676
OS 42.26197542 -38.79635116
OS 42.26289998 -38.78525644
OS 42.26382454 -38.77416172
OS 42.26382454 -38.7723126
OS 42.26382454 -38.76861436
OS 42.26289998 -38.76121788
OS 42.26105086 -38.75289684
OS 42.25920174 -38.74365124
OS 42.2555035 -38.73348108
OS 42.2508807 -38.72331092
OS 42.24440878 -38.71314076
OS 42.24348422 -38.7122162
OS 42.24071054 -38.70851796
OS 42.2370123 -38.70389516
OS 42.23146494 -38.6983478
OS 42.22406846 -38.69187588
OS 42.21482286 -38.68540396
OS 42.2046527 -38.6798566
OS 42.19263342 -38.6752338
OS 42.1907843 -38.67430924
OS 42.18708606 -38.67338468
OS 42.17876502 -38.67153556
OS 42.16859486 -38.66968644
OS 42.15565102 -38.66783732
OS 42.1399335 -38.6659882
OS 42.12051774 -38.66413908
OE
OB 45.22981302 -38.5504182 H
OS 45.22426566 -38.5504182
OS 45.21964286 -38.55134276
OS 45.2094727 -38.55226732
OS 45.1956043 -38.55596556
OS 45.17988678 -38.56151292
OS 45.1632447 -38.5689094
OS 45.14752718 -38.58000412
OS 45.13920614 -38.5874006
OS 45.13180966 -38.59479708
OS 45.13180966 -38.59572164
OS 45.12996054 -38.5966462
OS 45.12811142 -38.59941988
OS 45.12533774 -38.60311812
OS 45.12256406 -38.60774092
OS 45.11979038 -38.61328828
OS 45.11609214 -38.62068476
OS 45.1123939 -38.62808124
OS 45.10869566 -38.63732684
OS 45.10499742 -38.64657244
OS 45.10222374 -38.65766716
OS 45.09945006 -38.66968644
OS 45.09667638 -38.68263028
OS 45.09482726 -38.69649868
OS 45.0939027 -38.7122162
OS 45.09297814 -38.72793372
OS 45.09297814 -38.72885828
OS 45.09297814 -38.73163196
OS 45.09297814 -38.73625476
OS 45.0939027 -38.74272668
OS 45.0939027 -38.75012316
OS 45.09482726 -38.7584442
OS 45.09760094 -38.77785996
OS 45.10222374 -38.8000494
OS 45.10962022 -38.82223884
OS 45.11886582 -38.84350372
OS 45.12533774 -38.85274932
OS 45.13180966 -38.86199492
OS 45.13273422 -38.86199492
OS 45.13365878 -38.86384404
OS 45.13920614 -38.86846684
OS 45.14752718 -38.87586332
OS 45.1586219 -38.8832598
OS 45.1724903 -38.89158084
OS 45.18913238 -38.89897732
OS 45.20854814 -38.90360012
OS 45.2187183 -38.90452468
OS 45.22981302 -38.90544924
OS 45.23536038 -38.90544924
OS 45.23998318 -38.90452468
OS 45.25015334 -38.90267556
OS 45.26402174 -38.89990188
OS 45.2788147 -38.89435452
OS 45.29545678 -38.88695804
OS 45.3111743 -38.87586332
OS 45.31949534 -38.86846684
OS 45.32689182 -38.86107036
OS 45.32781638 -38.8601458
OS 45.32874094 -38.85922124
OS 45.33059006 -38.85644756
OS 45.33336374 -38.85274932
OS 45.33613742 -38.84812652
OS 45.33983566 -38.84257916
OS 45.3435339 -38.83518268
OS 45.34723214 -38.8277862
OS 45.35093038 -38.8185406
OS 45.35370406 -38.80837044
OS 45.3574023 -38.79727572
OS 45.36017598 -38.78525644
OS 45.36294966 -38.77138804
OS 45.36479878 -38.75751964
OS 45.3666479 -38.74180212
OS 45.3666479 -38.72516004
OS 45.3666479 -38.72423548
OS 45.3666479 -38.7214618
OS 45.3666479 -38.716839
OS 45.36572334 -38.71129164
OS 45.36572334 -38.70389516
OS 45.36479878 -38.69557412
OS 45.3620251 -38.67615836
OS 45.3574023 -38.65581804
OS 45.35000582 -38.6336286
OS 45.33983566 -38.61328828
OS 45.3342883 -38.60311812
OS 45.32689182 -38.59479708
OS 45.32689182 -38.59387252
OS 45.3250427 -38.59294796
OS 45.31949534 -38.5874006
OS 45.3111743 -38.58092868
OS 45.30007958 -38.57260764
OS 45.28621118 -38.5642866
OS 45.2695691 -38.55689012
OS 45.2510779 -38.55226732
OS 45.24090774 -38.55134276
OS 45.22981302 -38.5504182
OE
OB 32.07702246 -38.54764452 H
OS 32.07239966 -38.54764452
OS 32.06870142 -38.54856908
OS 32.05945582 -38.5504182
OS 32.04743654 -38.55319188
OS 32.03356814 -38.55873924
OS 32.01877518 -38.56706028
OS 32.01045414 -38.57260764
OS 32.00305766 -38.57907956
OS 31.99566118 -38.58647604
OS 31.9882647 -38.59479708
OS 31.9882647 -38.59572164
OS 31.98641558 -38.5966462
OS 31.98456646 -38.59941988
OS 31.98271734 -38.60311812
OS 31.97994366 -38.60866548
OS 31.97624542 -38.61421284
OS 31.97254718 -38.62160932
OS 31.9697735 -38.6290058
OS 31.96607526 -38.6382514
OS 31.96237702 -38.64842156
OS 31.95960334 -38.65951628
OS 31.9559051 -38.67153556
OS 31.95405598 -38.68540396
OS 31.95220686 -38.69927236
OS 31.95035774 -38.71406532
OS 31.95035774 -38.7307074
OS 31.95035774 -38.73163196
OS 31.95035774 -38.73440564
OS 31.95035774 -38.73902844
OS 31.9512823 -38.74550036
OS 31.9512823 -38.75289684
OS 31.95220686 -38.76121788
OS 31.95498054 -38.78063364
OS 31.95960334 -38.80282308
OS 31.9651507 -38.82408796
OS 31.9743963 -38.84535284
OS 31.97994366 -38.85459844
OS 31.98641558 -38.86291948
OS 31.9882647 -38.8647686
OS 31.9928875 -38.8693914
OS 32.00028398 -38.87678788
OS 32.01045414 -38.88418436
OS 32.02339798 -38.89158084
OS 32.03819094 -38.89897732
OS 32.05483302 -38.90360012
OS 32.06407862 -38.90452468
OS 32.07332422 -38.90544924
OS 32.07887158 -38.90544924
OS 32.08256982 -38.90452468
OS 32.09181542 -38.90267556
OS 32.10475926 -38.89990188
OS 32.11862766 -38.89435452
OS 32.13342062 -38.88695804
OS 32.14821358 -38.87586332
OS 32.15561006 -38.8693914
OS 32.16300654 -38.86199492
OS 32.16300654 -38.86107036
OS 32.16485566 -38.8601458
OS 32.16670478 -38.85737212
OS 32.1685539 -38.85367388
OS 32.17225214 -38.84905108
OS 32.17502582 -38.84257916
OS 32.17872406 -38.83610724
OS 32.1824223 -38.8277862
OS 32.18519598 -38.81946516
OS 32.18889422 -38.80837044
OS 32.19259246 -38.79727572
OS 32.19536614 -38.78525644
OS 32.19721526 -38.77138804
OS 32.19906438 -38.75659508
OS 32.2009135 -38.74087756
OS 32.2009135 -38.72423548
OS 32.2009135 -38.72331092
OS 32.2009135 -38.72053724
OS 32.2009135 -38.71591444
OS 32.19998894 -38.70944252
OS 32.19998894 -38.70204604
OS 32.19906438 -38.693725
OS 32.1962907 -38.67430924
OS 32.1916679 -38.65304436
OS 32.18519598 -38.63177948
OS 32.17595038 -38.6105146
OS 32.17040302 -38.60034444
OS 32.1639311 -38.5920234
OS 32.1639311 -38.59109884
OS 32.16208198 -38.59017428
OS 32.15745918 -38.58462692
OS 32.1500627 -38.578155
OS 32.13989254 -38.56983396
OS 32.1269487 -38.56151292
OS 32.11215574 -38.55411644
OS 32.09551366 -38.54949364
OS 32.08626806 -38.54856908
OS 32.07702246 -38.54764452
OE
OB 42.10387566 -38.39601668 H
OS 41.95224782 -38.39601668
OS 41.95224782 -38.58832516
OS 42.10942302 -38.58832516
OS 42.1214423 -38.5874006
OS 42.13438614 -38.58647604
OS 42.14732998 -38.58555148
OS 42.16027382 -38.58370236
OS 42.17044398 -38.58185324
OS 42.1722931 -38.58092868
OS 42.17599134 -38.58000412
OS 42.1815387 -38.57723044
OS 42.18893518 -38.5735322
OS 42.19633166 -38.56983396
OS 42.2046527 -38.5642866
OS 42.21297374 -38.55689012
OS 42.21944566 -38.54949364
OS 42.22037022 -38.54856908
OS 42.22221934 -38.5457954
OS 42.22499302 -38.54024804
OS 42.2277667 -38.53377612
OS 42.23054038 -38.52637964
OS 42.23331406 -38.51713404
OS 42.23516318 -38.50603932
OS 42.23608774 -38.49402004
OS 42.23608774 -38.49217092
OS 42.23608774 -38.48847268
OS 42.23516318 -38.48292532
OS 42.23423862 -38.47552884
OS 42.2323895 -38.46628324
OS 42.22961582 -38.45703764
OS 42.22591758 -38.44779204
OS 42.22037022 -38.43854644
OS 42.21944566 -38.43762188
OS 42.21759654 -38.4348482
OS 42.2138983 -38.4302254
OS 42.2092755 -38.4256026
OS 42.20280358 -38.42005524
OS 42.1954071 -38.41450788
OS 42.1861615 -38.40896052
OS 42.17599134 -38.40526228
OS 42.17506678 -38.40526228
OS 42.17044398 -38.40341316
OS 42.16397206 -38.4024886
OS 42.1538019 -38.40063948
OS 42.1399335 -38.39879036
OS 42.12421598 -38.3978658
OS 42.10387566 -38.39601668
OE
OB 37.41635646 -38.39139388 H
OS 37.21480238 -38.39139388
OS 37.21480238 -38.60311812
OS 37.40526174 -38.60311812
OS 37.41635646 -38.60219356
OS 37.4293003 -38.601269
OS 37.44409326 -38.60034444
OS 37.45888622 -38.59849532
OS 37.47367918 -38.59572164
OS 37.48662302 -38.5920234
OS 37.48847214 -38.59109884
OS 37.49217038 -38.58924972
OS 37.49771774 -38.58647604
OS 37.50511422 -38.5827778
OS 37.51343526 -38.57723044
OS 37.5217563 -38.57075852
OS 37.53007734 -38.56243748
OS 37.53654926 -38.55319188
OS 37.53747382 -38.55226732
OS 37.53932294 -38.54856908
OS 37.54209662 -38.54302172
OS 37.54579486 -38.53562524
OS 37.54856854 -38.5273042
OS 37.55134222 -38.5180586
OS 37.55319134 -38.50696388
OS 37.5541159 -38.49586916
OS 37.5541159 -38.4949446
OS 37.5541159 -38.49402004
OS 37.55319134 -38.48847268
OS 37.55226678 -38.48015164
OS 37.55041766 -38.46905692
OS 37.54579486 -38.4579622
OS 37.5402475 -38.44501836
OS 37.53192646 -38.43299908
OS 37.52083174 -38.4209798
OS 37.51898262 -38.42005524
OS 37.51435982 -38.416357
OS 37.50696334 -38.4117342
OS 37.49494406 -38.40618684
OS 37.48107566 -38.40063948
OS 37.46258446 -38.39601668
OS 37.44131958 -38.39231844
OS 37.41635646 -38.39139388
OE
OB 39.82298614 -38.54764452 H
OS 39.81836334 -38.54764452
OS 39.8146651 -38.54856908
OS 39.8054195 -38.5504182
OS 39.79340022 -38.55319188
OS 39.77953182 -38.55873924
OS 39.76473886 -38.56706028
OS 39.75641782 -38.57260764
OS 39.74902134 -38.57907956
OS 39.74162486 -38.58647604
OS 39.73422838 -38.59479708
OS 39.73422838 -38.59572164
OS 39.73237926 -38.5966462
OS 39.73053014 -38.59941988
OS 39.72868102 -38.60311812
OS 39.72590734 -38.60866548
OS 39.7222091 -38.61421284
OS 39.71851086 -38.62160932
OS 39.71573718 -38.6290058
OS 39.71203894 -38.6382514
OS 39.7083407 -38.64842156
OS 39.70556702 -38.65951628
OS 39.70186878 -38.67153556
OS 39.70001966 -38.68540396
OS 39.69817054 -38.69927236
OS 39.69632142 -38.71406532
OS 39.69632142 -38.7307074
OS 39.69632142 -38.73163196
OS 39.69632142 -38.73440564
OS 39.69632142 -38.73902844
OS 39.69724598 -38.74550036
OS 39.69724598 -38.75289684
OS 39.69817054 -38.76121788
OS 39.70094422 -38.78063364
OS 39.70556702 -38.80282308
OS 39.71111438 -38.82408796
OS 39.72035998 -38.84535284
OS 39.72590734 -38.85459844
OS 39.73237926 -38.86291948
OS 39.73422838 -38.8647686
OS 39.73885118 -38.8693914
OS 39.74624766 -38.87678788
OS 39.75641782 -38.88418436
OS 39.76936166 -38.89158084
OS 39.78415462 -38.89897732
OS 39.8007967 -38.90360012
OS 39.8100423 -38.90452468
OS 39.8192879 -38.90544924
OS 39.82483526 -38.90544924
OS 39.8285335 -38.90452468
OS 39.8377791 -38.90267556
OS 39.85072294 -38.89990188
OS 39.86459134 -38.89435452
OS 39.8793843 -38.88695804
OS 39.89417726 -38.87586332
OS 39.90157374 -38.8693914
OS 39.90897022 -38.86199492
OS 39.90897022 -38.86107036
OS 39.91081934 -38.8601458
OS 39.91266846 -38.85737212
OS 39.91451758 -38.85367388
OS 39.91821582 -38.84905108
OS 39.9209895 -38.84257916
OS 39.92468774 -38.83610724
OS 39.92838598 -38.8277862
OS 39.93115966 -38.81946516
OS 39.9348579 -38.80837044
OS 39.93855614 -38.79727572
OS 39.94132982 -38.78525644
OS 39.94317894 -38.77138804
OS 39.94502806 -38.75659508
OS 39.94687718 -38.74087756
OS 39.94687718 -38.72423548
OS 39.94687718 -38.72331092
OS 39.94687718 -38.72053724
OS 39.94687718 -38.71591444
OS 39.94595262 -38.70944252
OS 39.94595262 -38.70204604
OS 39.94502806 -38.693725
OS 39.94225438 -38.67430924
OS 39.93763158 -38.65304436
OS 39.93115966 -38.63177948
OS 39.92191406 -38.6105146
OS 39.9163667 -38.60034444
OS 39.90989478 -38.5920234
OS 39.90989478 -38.59109884
OS 39.90804566 -38.59017428
OS 39.90342286 -38.58462692
OS 39.89602638 -38.578155
OS 39.88585622 -38.56983396
OS 39.87291238 -38.56151292
OS 39.85811942 -38.55411644
OS 39.84147734 -38.54949364
OS 39.83223174 -38.54856908
OS 39.82298614 -38.54764452
OE
OB 35.73550638 -38.39601668 H
OS 35.5524435 -38.39601668
OS 35.5524435 -38.624383
OS 35.72441166 -38.624383
OS 35.73088358 -38.62345844
OS 35.7373555 -38.62345844
OS 35.74475198 -38.62253388
OS 35.76231862 -38.62068476
OS 35.78173438 -38.61698652
OS 35.80115014 -38.61143916
OS 35.81871678 -38.60404268
OS 35.82703782 -38.59941988
OS 35.83350974 -38.59387252
OS 35.83535886 -38.5920234
OS 35.8390571 -38.58832516
OS 35.84460446 -38.58092868
OS 35.85107638 -38.57168308
OS 35.8575483 -38.5596638
OS 35.86309566 -38.54487084
OS 35.8667939 -38.52822876
OS 35.86864302 -38.508813
OS 35.86864302 -38.50788844
OS 35.86864302 -38.50696388
OS 35.86864302 -38.50234108
OS 35.86771846 -38.49402004
OS 35.86586934 -38.48477444
OS 35.86402022 -38.47460428
OS 35.86032198 -38.462585
OS 35.85477462 -38.45149028
OS 35.8483027 -38.44039556
OS 35.84737814 -38.439471
OS 35.84460446 -38.43577276
OS 35.83998166 -38.43114996
OS 35.8344343 -38.42467804
OS 35.82611326 -38.41820612
OS 35.81686766 -38.41265876
OS 35.8066975 -38.4071114
OS 35.79467822 -38.4024886
OS 35.79375366 -38.4024886
OS 35.79005542 -38.40156404
OS 35.78450806 -38.40063948
OS 35.77711158 -38.39879036
OS 35.76601686 -38.3978658
OS 35.75214846 -38.39694124
OS 35.73550638 -38.39601668
OE
OB 43.44263854 -38.5504182 H
OS 43.43709118 -38.5504182
OS 43.43339294 -38.55134276
OS 43.42322278 -38.55226732
OS 43.4112035 -38.555041
OS 43.39641054 -38.5596638
OS 43.38069302 -38.56613572
OS 43.36590006 -38.57538132
OS 43.3511071 -38.5874006
OS 43.34925798 -38.58924972
OS 43.34555974 -38.59387252
OS 43.33908782 -38.60219356
OS 43.3326159 -38.61328828
OS 43.32521942 -38.62623212
OS 43.3187475 -38.6428742
OS 43.31320014 -38.66228996
OS 43.31042646 -38.68355484
OS 43.57022782 -38.68355484
OS 43.57022782 -38.68263028
OS 43.57022782 -38.68078116
OS 43.56930326 -38.67800748
OS 43.56930326 -38.67430924
OS 43.56745414 -38.66321452
OS 43.56468046 -38.65119524
OS 43.56005766 -38.63640228
OS 43.55543486 -38.62253388
OS 43.54803838 -38.60866548
OS 43.53971734 -38.5966462
OS 43.53971734 -38.59572164
OS 43.53786822 -38.59479708
OS 43.53324542 -38.58924972
OS 43.52492438 -38.58185324
OS 43.51382966 -38.5735322
OS 43.49996126 -38.56521116
OS 43.48331918 -38.55781468
OS 43.46390342 -38.55226732
OS 43.45373326 -38.55134276
OS 43.44263854 -38.5504182
OE
OB 34.35791198 -38.39601668 H
OS 34.20628414 -38.39601668
OS 34.20628414 -38.58832516
OS 34.36345934 -38.58832516
OS 34.37547862 -38.5874006
OS 34.38842246 -38.58647604
OS 34.4013663 -38.58555148
OS 34.41431014 -38.58370236
OS 34.4244803 -38.58185324
OS 34.42632942 -38.58092868
OS 34.43002766 -38.58000412
OS 34.43557502 -38.57723044
OS 34.4429715 -38.5735322
OS 34.45036798 -38.56983396
OS 34.45868902 -38.5642866
OS 34.46701006 -38.55689012
OS 34.47348198 -38.54949364
OS 34.47440654 -38.54856908
OS 34.47625566 -38.5457954
OS 34.47902934 -38.54024804
OS 34.48180302 -38.53377612
OS 34.4845767 -38.52637964
OS 34.48735038 -38.51713404
OS 34.4891995 -38.50603932
OS 34.49012406 -38.49402004
OS 34.49012406 -38.49217092
OS 34.49012406 -38.48847268
OS 34.4891995 -38.48292532
OS 34.48827494 -38.47552884
OS 34.48642582 -38.46628324
OS 34.48365214 -38.45703764
OS 34.4799539 -38.44779204
OS 34.47440654 -38.43854644
OS 34.47348198 -38.43762188
OS 34.47163286 -38.4348482
OS 34.46793462 -38.4302254
OS 34.46331182 -38.4256026
OS 34.4568399 -38.42005524
OS 34.44944342 -38.41450788
OS 34.44019782 -38.40896052
OS 34.43002766 -38.40526228
OS 34.4291031 -38.40526228
OS 34.4244803 -38.40341316
OS 34.41800838 -38.4024886
OS 34.40783822 -38.40063948
OS 34.39396982 -38.39879036
OS 34.3782523 -38.3978658
OS 34.35791198 -38.39601668
OE
OB 40.89732486 -38.39601668 H
OS 40.71426198 -38.39601668
OS 40.71426198 -38.624383
OS 40.88623014 -38.624383
OS 40.89270206 -38.62345844
OS 40.89917398 -38.62345844
OS 40.90657046 -38.62253388
OS 40.9241371 -38.62068476
OS 40.94355286 -38.61698652
OS 40.96296862 -38.61143916
OS 40.98053526 -38.60404268
OS 40.9888563 -38.59941988
OS 40.99532822 -38.59387252
OS 40.99717734 -38.5920234
OS 41.00087558 -38.58832516
OS 41.00642294 -38.58092868
OS 41.01289486 -38.57168308
OS 41.01936678 -38.5596638
OS 41.02491414 -38.54487084
OS 41.02861238 -38.52822876
OS 41.0304615 -38.508813
OS 41.0304615 -38.50788844
OS 41.0304615 -38.50696388
OS 41.0304615 -38.50234108
OS 41.02953694 -38.49402004
OS 41.02768782 -38.48477444
OS 41.0258387 -38.47460428
OS 41.02214046 -38.462585
OS 41.0165931 -38.45149028
OS 41.01012118 -38.44039556
OS 41.00919662 -38.439471
OS 41.00642294 -38.43577276
OS 41.00180014 -38.43114996
OS 40.99625278 -38.42467804
OS 40.98793174 -38.41820612
OS 40.97868614 -38.41265876
OS 40.96851598 -38.4071114
OS 40.9564967 -38.4024886
OS 40.95557214 -38.4024886
OS 40.9518739 -38.40156404
OS 40.94632654 -38.40063948
OS 40.93893006 -38.39879036
OS 40.92783534 -38.3978658
OS 40.91396694 -38.39694124
OS 40.89732486 -38.39601668
OE
OB 33.15136118 -38.39601668 H
OS 32.9682983 -38.39601668
OS 32.9682983 -38.624383
OS 33.14026646 -38.624383
OS 33.14673838 -38.62345844
OS 33.1532103 -38.62345844
OS 33.16060678 -38.62253388
OS 33.17817342 -38.62068476
OS 33.19758918 -38.61698652
OS 33.21700494 -38.61143916
OS 33.23457158 -38.60404268
OS 33.24289262 -38.59941988
OS 33.24936454 -38.59387252
OS 33.25121366 -38.5920234
OS 33.2549119 -38.58832516
OS 33.26045926 -38.58092868
OS 33.26693118 -38.57168308
OS 33.2734031 -38.5596638
OS 33.27895046 -38.54487084
OS 33.2826487 -38.52822876
OS 33.28449782 -38.508813
OS 33.28449782 -38.50788844
OS 33.28449782 -38.50696388
OS 33.28449782 -38.50234108
OS 33.28357326 -38.49402004
OS 33.28172414 -38.48477444
OS 33.27987502 -38.47460428
OS 33.27617678 -38.462585
OS 33.27062942 -38.45149028
OS 33.2641575 -38.44039556
OS 33.26323294 -38.439471
OS 33.26045926 -38.43577276
OS 33.25583646 -38.43114996
OS 33.2502891 -38.42467804
OS 33.24196806 -38.41820612
OS 33.23272246 -38.41265876
OS 33.2225523 -38.4071114
OS 33.21053302 -38.4024886
OS 33.20960846 -38.4024886
OS 33.20591022 -38.40156404
OS 33.20036286 -38.40063948
OS 33.19296638 -38.39879036
OS 33.18187166 -38.3978658
OS 33.16800326 -38.39694124
OS 33.15136118 -38.39601668
OE
OB 34.37455406 -38.66413908 H
OS 34.20628414 -38.66413908
OS 34.20628414 -38.88418436
OS 34.38842246 -38.88418436
OS 34.40783822 -38.8832598
OS 34.41615926 -38.88233524
OS 34.42355574 -38.88141068
OS 34.4244803 -38.88141068
OS 34.42817854 -38.88048612
OS 34.4337259 -38.87956156
OS 34.44019782 -38.87771244
OS 34.45591534 -38.87216508
OS 34.47163286 -38.8647686
OS 34.47255742 -38.86384404
OS 34.4753311 -38.86199492
OS 34.47902934 -38.85922124
OS 34.48365214 -38.855523
OS 34.48827494 -38.84997564
OS 34.49474686 -38.84442828
OS 34.49936966 -38.8370318
OS 34.50491702 -38.82871076
OS 34.50584158 -38.8277862
OS 34.50676614 -38.82501252
OS 34.50861526 -38.81946516
OS 34.51138894 -38.81299324
OS 34.51416262 -38.80559676
OS 34.51601174 -38.79635116
OS 34.5169363 -38.78525644
OS 34.51786086 -38.77416172
OS 34.51786086 -38.7723126
OS 34.51786086 -38.76861436
OS 34.5169363 -38.76121788
OS 34.51508718 -38.75289684
OS 34.51323806 -38.74365124
OS 34.50953982 -38.73348108
OS 34.50491702 -38.72331092
OS 34.4984451 -38.71314076
OS 34.49752054 -38.7122162
OS 34.49474686 -38.70851796
OS 34.49104862 -38.70389516
OS 34.48550126 -38.6983478
OS 34.47810478 -38.69187588
OS 34.46885918 -38.68540396
OS 34.45868902 -38.6798566
OS 34.44666974 -38.6752338
OS 34.44482062 -38.67430924
OS 34.44112238 -38.67338468
OS 34.43280134 -38.67153556
OS 34.42263118 -38.66968644
OS 34.40968734 -38.66783732
OS 34.39396982 -38.6659882
OS 34.37455406 -38.66413908
OE
SE
S P 0
OB 48.49040086 -36.61402634 I
OS 48.17420134 -36.61402634
OS 48.17420134 -37.45999874
OS 48.04661206 -37.45999874
OS 48.04661206 -36.61402634
OS 47.73041254 -36.61402634
OS 47.73041254 -36.50030546
OS 48.49040086 -36.50030546
OS 48.49040086 -36.61402634
OE
OB 47.69990206 -37.45999874 I
OS 47.5556707 -37.45999874
OS 47.44333666 -37.16876234
OS 47.04115306 -37.16876234
OS 46.93714006 -37.45999874
OS 46.80261658 -37.45999874
OS 47.16874234 -36.50030546
OS 47.30742634 -36.50030546
OS 47.69990206 -37.45999874
OE
OB 49.31834434 -36.61402634 I
OS 48.75112678 -36.61402634
OS 48.75112678 -36.90664958
OS 49.2822865 -36.90664958
OS 49.2822865 -37.02037046
OS 48.75112678 -37.02037046
OS 48.75112678 -37.34627786
OS 49.34053378 -37.34627786
OS 49.34053378 -37.45999874
OS 48.6235375 -37.45999874
OS 48.6235375 -36.50030546
OS 49.31834434 -36.50030546
OS 49.31834434 -36.61402634
OE
OB 46.33386466 -36.5016923 I
OS 46.36160146 -36.50307914
OS 46.38933826 -36.50585282
OS 46.41707506 -36.51001334
OS 46.44065134 -36.51417386
OS 46.44203818 -36.51417386
OS 46.44481186 -36.5155607
OS 46.44897238 -36.5155607
OS 46.45451974 -36.51833438
OS 46.46977498 -36.5224949
OS 46.48919074 -36.5294291
OS 46.51138018 -36.53913698
OS 46.53495646 -36.55161854
OS 46.55853274 -36.56548694
OS 46.58072218 -36.58351586
OS 46.58210902 -36.5849027
OS 46.58349586 -36.58628954
OS 46.58765638 -36.59045006
OS 46.59320374 -36.59461058
OS 46.60707214 -36.60847898
OS 46.62371422 -36.62789474
OS 46.64174314 -36.65147102
OS 46.6611589 -36.67920782
OS 46.67918782 -36.71110514
OS 46.69444306 -36.74716298
OS 46.69444306 -36.74854982
OS 46.6958299 -36.7513235
OS 46.69860358 -36.75687086
OS 46.69999042 -36.7651919
OS 46.70415094 -36.77489978
OS 46.70692462 -36.7859945
OS 46.7096983 -36.79847606
OS 46.71385882 -36.8137313
OS 46.71801934 -36.82898654
OS 46.72079302 -36.84701546
OS 46.72772722 -36.88584698
OS 46.73188774 -36.92883902
OS 46.73327458 -36.97599158
OS 46.73327458 -36.97737842
OS 46.73327458 -36.9801521
OS 46.73327458 -36.9870863
OS 46.73327458 -36.9940205
OS 46.73188774 -37.00372838
OS 46.73188774 -37.0148231
OS 46.7305009 -37.04117306
OS 46.72634038 -37.07168354
OS 46.72217986 -37.10358086
OS 46.71524566 -37.13686502
OS 46.70692462 -37.17014918
OS 46.70692462 -37.17153602
OS 46.70553778 -37.1743097
OS 46.70415094 -37.17847022
OS 46.7027641 -37.18401758
OS 46.69721674 -37.19927282
OS 46.6888957 -37.21868858
OS 46.68057466 -37.24087802
OS 46.66947994 -37.26306746
OS 46.65561154 -37.28664374
OS 46.64174314 -37.30883318
OS 46.6403563 -37.31160686
OS 46.63480894 -37.31854106
OS 46.6264879 -37.32824894
OS 46.61539318 -37.3407305
OS 46.60291162 -37.3545989
OS 46.58765638 -37.3684673
OS 46.57240114 -37.38372254
OS 46.55437222 -37.3962041
OS 46.55159854 -37.39759094
OS 46.54605118 -37.40175146
OS 46.5363433 -37.40729882
OS 46.5224749 -37.41423302
OS 46.50583282 -37.42255406
OS 46.48641706 -37.42948826
OS 46.46422762 -37.4378093
OS 46.4392645 -37.4447435
OS 46.43649082 -37.4447435
OS 46.4323303 -37.44613034
OS 46.42816978 -37.44751718
OS 46.41430138 -37.44890402
OS 46.39488562 -37.4516777
OS 46.37269618 -37.45445138
OS 46.34634622 -37.45722506
OS 46.31722258 -37.4586119
OS 46.28532526 -37.45999874
OS 45.9400021 -37.45999874
OS 45.9400021 -36.50030546
OS 46.30890154 -36.50030546
OS 46.33386466 -36.5016923
OE
OB 46.28948578 -36.61402634 H
OS 46.06759138 -36.61402634
OS 46.06759138 -37.34627786
OS 46.29503314 -37.34627786
OS 46.30474102 -37.34489102
OS 46.32554362 -37.34350418
OS 46.3491199 -37.34211734
OS 46.37408302 -37.33934366
OS 46.39904614 -37.33518314
OS 46.41984874 -37.32963578
OS 46.42262242 -37.32824894
OS 46.42955662 -37.3268621
OS 46.4392645 -37.32270158
OS 46.45174606 -37.31715422
OS 46.46561446 -37.30883318
OS 46.47948286 -37.30051214
OS 46.49335126 -37.29080426
OS 46.50721966 -37.27970954
OS 46.5086065 -37.27693586
OS 46.51415386 -37.2713885
OS 46.5224749 -37.26168062
OS 46.53218278 -37.24781222
OS 46.5432775 -37.2297833
OS 46.55575906 -37.2089807
OS 46.56685378 -37.18540442
OS 46.57656166 -37.15905446
OS 46.57656166 -37.15766762
OS 46.5779485 -37.15489394
OS 46.57933534 -37.15073342
OS 46.58072218 -37.14518606
OS 46.58210902 -37.13825186
OS 46.5848827 -37.12854398
OS 46.58765638 -37.1188361
OS 46.59043006 -37.10774138
OS 46.59459058 -37.08000458
OS 46.5987511 -37.04810726
OS 46.60152478 -37.01204942
OS 46.60291162 -36.9732179
OS 46.60291162 -36.97183106
OS 46.60291162 -36.9662837
OS 46.60291162 -36.9593495
OS 46.60152478 -36.94825478
OS 46.60152478 -36.93577322
OS 46.60013794 -36.92190482
OS 46.5987511 -36.90526274
OS 46.59736426 -36.88862066
OS 46.59043006 -36.85117598
OS 46.58210902 -36.81234446
OS 46.56962746 -36.77628662
OS 46.56130642 -36.7582577
OS 46.55298538 -36.74300246
OS 46.55298538 -36.74161562
OS 46.5502117 -36.73884194
OS 46.54743802 -36.73468142
OS 46.54466434 -36.72913406
OS 46.53356962 -36.71526566
OS 46.51970122 -36.69862358
OS 46.5016723 -36.68059466
OS 46.4808697 -36.66256574
OS 46.45729342 -36.6473105
OS 46.4323303 -36.63482894
OS 46.42955662 -36.6334421
OS 46.42262242 -36.63205526
OS 46.41014086 -36.62789474
OS 46.39211194 -36.62373422
OS 46.3699225 -36.62096054
OS 46.3421857 -36.61680002
OS 46.32554362 -36.61541318
OS 46.3075147 -36.61541318
OS 46.28948578 -36.61402634
OE
OB 47.23531066 -36.60015794 H
OS 47.23531066 -36.60154478
OS 47.23392382 -36.60431846
OS 47.23392382 -36.60986582
OS 47.23115014 -36.61541318
OS 47.2297633 -36.62512106
OS 47.22698962 -36.63482894
OS 47.22144226 -36.65840522
OS 47.21450806 -36.68614202
OS 47.20480018 -36.7166525
OS 47.1950923 -36.74993666
OS 47.18261074 -36.78460766
OS 47.07859774 -37.06474934
OS 47.4031183 -37.06474934
OS 47.30326582 -36.80124974
OS 47.30326582 -36.7998629
OS 47.30187898 -36.79570238
OS 47.2991053 -36.78876818
OS 47.29633162 -36.78044714
OS 47.2921711 -36.77073926
OS 47.28801058 -36.7582577
OS 47.28385006 -36.7443893
OS 47.2783027 -36.7305209
OS 47.26720798 -36.69862358
OS 47.25611326 -36.66533942
OS 47.24501854 -36.63205526
OS 47.23531066 -36.60015794
OE
SE
S P 0
OB 53.64989524 -38.94890356 I
OS 53.57130764 -38.94890356
OS 53.57130764 -38.4487166
OS 53.57038308 -38.44964116
OS 53.56576028 -38.4533394
OS 53.56021292 -38.45888676
OS 53.55096732 -38.46535868
OS 53.54079716 -38.47367972
OS 53.52785332 -38.48292532
OS 53.51306036 -38.49309548
OS 53.49641828 -38.50326564
OS 53.49549372 -38.50326564
OS 53.49456916 -38.5041902
OS 53.4890218 -38.50788844
OS 53.4797762 -38.51251124
OS 53.46868148 -38.5180586
OS 53.45573764 -38.52453052
OS 53.44186924 -38.53100244
OS 53.42800084 -38.53747436
OS 53.41413244 -38.54302172
OS 53.41413244 -38.4672078
OS 53.415057 -38.4672078
OS 53.41690612 -38.46535868
OS 53.42060436 -38.46443412
OS 53.42522716 -38.46166044
OS 53.43077452 -38.45888676
OS 53.43724644 -38.45518852
OS 53.45296396 -38.44594292
OS 53.47145516 -38.43577276
OS 53.48994636 -38.42282892
OS 53.50936212 -38.40803596
OS 53.52877788 -38.39231844
OS 53.52970244 -38.39139388
OS 53.530627 -38.39046932
OS 53.53340068 -38.38769564
OS 53.53709892 -38.38492196
OS 53.54541996 -38.37567636
OS 53.55651468 -38.36458164
OS 53.5676094 -38.3516378
OS 53.57962868 -38.33684484
OS 53.58979884 -38.32205188
OS 53.59904444 -38.30633436
OS 53.64989524 -38.30633436
OS 53.64989524 -38.94890356
OE
OB 54.07334372 -38.30725892 I
OS 54.0807402 -38.30818348
OS 54.08906124 -38.30910804
OS 54.09830684 -38.3100326
OS 54.10755244 -38.31280628
OS 54.12974188 -38.31835364
OS 54.15193132 -38.32667468
OS 54.16302604 -38.33222204
OS 54.17412076 -38.33869396
OS 54.18429092 -38.347015
OS 54.19446108 -38.35533604
OS 54.19538564 -38.3562606
OS 54.1963102 -38.35718516
OS 54.19908388 -38.35995884
OS 54.20278212 -38.36365708
OS 54.20648036 -38.36920444
OS 54.21110316 -38.3747518
OS 54.22034876 -38.3886202
OS 54.22959436 -38.40618684
OS 54.2379154 -38.42652716
OS 54.24438732 -38.44964116
OS 54.24531188 -38.46166044
OS 54.24623644 -38.47460428
OS 54.24623644 -38.47552884
OS 54.24623644 -38.4764534
OS 54.24623644 -38.48200076
OS 54.24531188 -38.4903218
OS 54.24346276 -38.50049196
OS 54.24068908 -38.5134358
OS 54.23606628 -38.52637964
OS 54.23051892 -38.53932348
OS 54.22219788 -38.55226732
OS 54.22127332 -38.55411644
OS 54.21757508 -38.55781468
OS 54.21202772 -38.56336204
OS 54.20463124 -38.57075852
OS 54.19446108 -38.57907956
OS 54.1824418 -38.5874006
OS 54.1685734 -38.59572164
OS 54.15193132 -38.60311812
OS 54.15285588 -38.60311812
OS 54.154705 -38.60404268
OS 54.15747868 -38.60496724
OS 54.16117692 -38.60681636
OS 54.17227164 -38.61143916
OS 54.18521548 -38.61791108
OS 54.19908388 -38.62715668
OS 54.21387684 -38.63732684
OS 54.22774524 -38.65027068
OS 54.24068908 -38.66506364
OS 54.24068908 -38.6659882
OS 54.24161364 -38.66691276
OS 54.24531188 -38.67246012
OS 54.25085924 -38.68170572
OS 54.2564066 -38.693725
OS 54.26195396 -38.70851796
OS 54.26750132 -38.7260846
OS 54.27119956 -38.74550036
OS 54.27212412 -38.76676524
OS 54.27212412 -38.7676898
OS 54.27212412 -38.77046348
OS 54.27212412 -38.77508628
OS 54.27119956 -38.78063364
OS 54.270275 -38.78710556
OS 54.26935044 -38.7954266
OS 54.26750132 -38.8046722
OS 54.26472764 -38.81484236
OS 54.25825572 -38.83610724
OS 54.25363292 -38.84812652
OS 54.247161 -38.85922124
OS 54.24068908 -38.87124052
OS 54.2332926 -38.88233524
OS 54.224047 -38.89342996
OS 54.21387684 -38.90452468
OS 54.21295228 -38.90544924
OS 54.21110316 -38.90729836
OS 54.20832948 -38.91007204
OS 54.20370668 -38.91284572
OS 54.19723476 -38.91746852
OS 54.19076284 -38.92209132
OS 54.1824418 -38.92671412
OS 54.1731962 -38.93226148
OS 54.16302604 -38.93780884
OS 54.15100676 -38.94243164
OS 54.13806292 -38.94705444
OS 54.12511908 -38.95167724
OS 54.11032612 -38.95445092
OS 54.0946086 -38.9572246
OS 54.07889108 -38.95907372
OS 54.06132444 -38.95999828
OS 54.05207884 -38.95999828
OS 54.04560692 -38.95907372
OS 54.03728588 -38.95814916
OS 54.02804028 -38.9572246
OS 54.01787012 -38.95537548
OS 54.0067754 -38.9526018
OS 53.98181228 -38.94612988
OS 53.96886844 -38.94150708
OS 53.95684916 -38.93688428
OS 53.94390532 -38.93041236
OS 53.93096148 -38.92301588
OS 53.9189422 -38.91469484
OS 53.90784748 -38.90452468
OS 53.90692292 -38.90360012
OS 53.9050738 -38.901751
OS 53.90230012 -38.89897732
OS 53.89860188 -38.89435452
OS 53.89490364 -38.88880716
OS 53.88935628 -38.88233524
OS 53.88473348 -38.87493876
OS 53.87918612 -38.86569316
OS 53.87363876 -38.85644756
OS 53.86901596 -38.84535284
OS 53.85977036 -38.82223884
OS 53.85607212 -38.80837044
OS 53.85329844 -38.79450204
OS 53.85144932 -38.77970908
OS 53.85052476 -38.76491612
OS 53.85052476 -38.76399156
OS 53.85052476 -38.76214244
OS 53.85052476 -38.7584442
OS 53.85144932 -38.75474596
OS 53.85144932 -38.7491986
OS 53.85237388 -38.74272668
OS 53.854223 -38.72793372
OS 53.85792124 -38.71129164
OS 53.8634686 -38.69464956
OS 53.87178964 -38.67708292
OS 53.8819598 -38.66044084
OS 53.8819598 -38.65951628
OS 53.88380892 -38.65859172
OS 53.88750716 -38.65396892
OS 53.89490364 -38.64657244
OS 53.9050738 -38.63732684
OS 53.91801764 -38.62808124
OS 53.93373516 -38.61791108
OS 53.9513018 -38.60959004
OS 53.97256668 -38.60311812
OS 53.97164212 -38.60311812
OS 53.97071756 -38.60219356
OS 53.96794388 -38.601269
OS 53.96424564 -38.59941988
OS 53.9559246 -38.59572164
OS 53.94482988 -38.59017428
OS 53.9328106 -38.5827778
OS 53.92079132 -38.5735322
OS 53.9096966 -38.56336204
OS 53.89952644 -38.55226732
OS 53.89860188 -38.5504182
OS 53.8958282 -38.54671996
OS 53.89212996 -38.53932348
OS 53.88843172 -38.53007788
OS 53.88380892 -38.5180586
OS 53.88011068 -38.5041902
OS 53.877337 -38.48847268
OS 53.87641244 -38.4718306
OS 53.87641244 -38.47090604
OS 53.87641244 -38.46905692
OS 53.87641244 -38.46535868
OS 53.877337 -38.45981132
OS 53.87826156 -38.45426396
OS 53.87918612 -38.44686748
OS 53.88288436 -38.43114996
OS 53.88843172 -38.41265876
OS 53.89767732 -38.393243
OS 53.90322468 -38.38307284
OS 53.9096966 -38.37290268
OS 53.91801764 -38.36365708
OS 53.92633868 -38.35441148
OS 53.92726324 -38.35348692
OS 53.92911236 -38.35256236
OS 53.93188604 -38.34978868
OS 53.93558428 -38.347015
OS 53.94020708 -38.34331676
OS 53.946679 -38.33961852
OS 53.95407548 -38.33499572
OS 53.96147196 -38.33037292
OS 53.97071756 -38.32575012
OS 53.98088772 -38.32112732
OS 53.99198244 -38.31742908
OS 54.00400172 -38.31373084
OS 54.0298894 -38.30818348
OS 54.04468236 -38.30725892
OS 54.05947532 -38.30633436
OS 54.06779636 -38.30633436
OS 54.07334372 -38.30725892
OE
OB 53.23846604 -38.94890356 I
OS 53.14878372 -38.94890356
OS 53.14878372 -38.85922124
OS 53.23846604 -38.85922124
OS 53.23846604 -38.94890356
OE
OB 53.00177868 -38.39231844 I
OS 52.74567556 -38.39231844
OS 52.71146684 -38.56521116
OS 52.7123914 -38.5642866
OS 52.71424052 -38.56336204
OS 52.7170142 -38.56151292
OS 52.721637 -38.55873924
OS 52.72718436 -38.55596556
OS 52.73365628 -38.55226732
OS 52.74844924 -38.54487084
OS 52.76694044 -38.53747436
OS 52.78728076 -38.53100244
OS 52.8094702 -38.52637964
OS 52.82056492 -38.52453052
OS 52.84090524 -38.52453052
OS 52.8464526 -38.52545508
OS 52.85384908 -38.52637964
OS 52.86217012 -38.5273042
OS 52.87141572 -38.52915332
OS 52.88158588 -38.531927
OS 52.90377532 -38.53839892
OS 52.9157946 -38.54302172
OS 52.92781388 -38.54949364
OS 52.93983316 -38.55596556
OS 52.95185244 -38.56336204
OS 52.96294716 -38.57260764
OS 52.97404188 -38.5827778
OS 52.97496644 -38.58370236
OS 52.97681556 -38.58555148
OS 52.97958924 -38.58832516
OS 52.98328748 -38.59294796
OS 52.98791028 -38.59941988
OS 52.99253308 -38.6058918
OS 52.99808044 -38.61421284
OS 53.0036278 -38.62345844
OS 53.0082506 -38.6336286
OS 53.01379796 -38.64472332
OS 53.01842076 -38.65766716
OS 53.02304356 -38.670611
OS 53.0267418 -38.6844794
OS 53.02951548 -38.70019692
OS 53.0313646 -38.71591444
OS 53.03228916 -38.73255652
OS 53.03228916 -38.73348108
OS 53.03228916 -38.73625476
OS 53.03228916 -38.74087756
OS 53.0313646 -38.74734948
OS 53.03044004 -38.75474596
OS 53.02951548 -38.763067
OS 53.02766636 -38.77323716
OS 53.02581724 -38.78340732
OS 53.02026988 -38.80744588
OS 53.01102428 -38.832409
OS 53.00547692 -38.84535284
OS 52.99808044 -38.85737212
OS 52.99068396 -38.87031596
OS 52.98143836 -38.88233524
OS 52.9805138 -38.8832598
OS 52.97866468 -38.88603348
OS 52.97496644 -38.88973172
OS 52.97034364 -38.89435452
OS 52.96387172 -38.89990188
OS 52.95647524 -38.90729836
OS 52.94722964 -38.91377028
OS 52.93705948 -38.92116676
OS 52.92596476 -38.92856324
OS 52.91302092 -38.93503516
OS 52.89915252 -38.94150708
OS 52.88435956 -38.947979
OS 52.86864204 -38.9526018
OS 52.8510754 -38.95630004
OS 52.8325842 -38.95907372
OS 52.81316844 -38.95999828
OS 52.8048474 -38.95999828
OS 52.79837548 -38.95907372
OS 52.790979 -38.95814916
OS 52.78265796 -38.9572246
OS 52.7724878 -38.95630004
OS 52.76231764 -38.95352636
OS 52.73920364 -38.947979
OS 52.71608964 -38.93965796
OS 52.70407036 -38.9341106
OS 52.69205108 -38.92763868
OS 52.68095636 -38.9202422
OS 52.66986164 -38.91192116
OS 52.66893708 -38.9109966
OS 52.66708796 -38.91007204
OS 52.66523884 -38.9063738
OS 52.6615406 -38.90267556
OS 52.6569178 -38.89805276
OS 52.652295 -38.8925054
OS 52.64674764 -38.88510892
OS 52.64212484 -38.87678788
OS 52.63657748 -38.86846684
OS 52.63103012 -38.85829668
OS 52.62085996 -38.83610724
OS 52.61253892 -38.81021956
OS 52.60976524 -38.79635116
OS 52.60791612 -38.7815582
OS 52.69020196 -38.77508628
OS 52.69020196 -38.77601084
OS 52.69020196 -38.77785996
OS 52.69112652 -38.78063364
OS 52.69205108 -38.78525644
OS 52.69482476 -38.7954266
OS 52.698523 -38.809295
OS 52.70407036 -38.8231634
OS 52.71146684 -38.83888092
OS 52.72071244 -38.85274932
OS 52.73180716 -38.86569316
OS 52.73365628 -38.86661772
OS 52.73735452 -38.87031596
OS 52.744751 -38.87493876
OS 52.75492116 -38.88048612
OS 52.76601588 -38.88603348
OS 52.77988428 -38.89065628
OS 52.7956018 -38.89435452
OS 52.81316844 -38.89527908
OS 52.8187158 -38.89527908
OS 52.82241404 -38.89435452
OS 52.83350876 -38.89342996
OS 52.8464526 -38.88973172
OS 52.86217012 -38.88510892
OS 52.87788764 -38.87771244
OS 52.89452972 -38.86661772
OS 52.9019262 -38.8601458
OS 52.90932268 -38.85274932
OS 52.91024724 -38.85182476
OS 52.9111718 -38.8509002
OS 52.91302092 -38.84812652
OS 52.9157946 -38.84535284
OS 52.92226652 -38.83518268
OS 52.929663 -38.82223884
OS 52.93613492 -38.80652132
OS 52.94260684 -38.78710556
OS 52.94722964 -38.76399156
OS 52.94907876 -38.75197228
OS 52.94907876 -38.73902844
OS 52.94907876 -38.73810388
OS 52.94907876 -38.73625476
OS 52.94907876 -38.73255652
OS 52.9481542 -38.72793372
OS 52.9481542 -38.72238636
OS 52.94722964 -38.71591444
OS 52.94445596 -38.70112148
OS 52.93983316 -38.68355484
OS 52.93336124 -38.6659882
OS 52.92411564 -38.64934612
OS 52.9111718 -38.6336286
OS 52.9111718 -38.63270404
OS 52.90932268 -38.63177948
OS 52.90469988 -38.62715668
OS 52.89637884 -38.62068476
OS 52.88528412 -38.61328828
OS 52.87049116 -38.60681636
OS 52.85384908 -38.60034444
OS 52.83443332 -38.59572164
OS 52.8233386 -38.59387252
OS 52.80577196 -38.59387252
OS 52.79837548 -38.59479708
OS 52.78912988 -38.59572164
OS 52.77803516 -38.59849532
OS 52.76694044 -38.601269
OS 52.75492116 -38.6058918
OS 52.74290188 -38.61143916
OS 52.74197732 -38.61236372
OS 52.73827908 -38.61421284
OS 52.73273172 -38.61883564
OS 52.72533524 -38.62345844
OS 52.71793876 -38.62993036
OS 52.71054228 -38.6382514
OS 52.70222124 -38.64657244
OS 52.69574932 -38.6567426
OS 52.62178452 -38.64657244
OS 52.68373004 -38.31742908
OS 53.00177868 -38.31742908
OS 53.00177868 -38.39231844
OE
OB 53.23846604 -38.57445676 I
OS 53.14878372 -38.57445676
OS 53.14878372 -38.48477444
OS 53.23846604 -38.48477444
OS 53.23846604 -38.57445676
OE
OB 54.48199924 -38.57445676 I
OS 54.39231692 -38.57445676
OS 54.39231692 -38.48477444
OS 54.48199924 -38.48477444
OS 54.48199924 -38.57445676
OE
OB 56.14990548 -38.3100326 I
OS 56.165623 -38.31095716
OS 56.18226508 -38.31188172
OS 56.1979826 -38.31373084
OS 56.211851 -38.31557996
OS 56.21370012 -38.31557996
OS 56.22017204 -38.31742908
OS 56.22849308 -38.3192782
OS 56.2395878 -38.32205188
OS 56.25160708 -38.32667468
OS 56.26455092 -38.33222204
OS 56.27841932 -38.33869396
OS 56.2904386 -38.34609044
OS 56.29228772 -38.347015
OS 56.29598596 -38.34978868
OS 56.30153332 -38.35533604
OS 56.3089298 -38.36180796
OS 56.31725084 -38.370129
OS 56.32557188 -38.38122372
OS 56.33481748 -38.393243
OS 56.34221396 -38.4071114
OS 56.34313852 -38.40896052
OS 56.34498764 -38.41358332
OS 56.34868588 -38.42190436
OS 56.35238412 -38.43299908
OS 56.3551578 -38.44594292
OS 56.35885604 -38.46073588
OS 56.36070516 -38.47737796
OS 56.36162972 -38.4949446
OS 56.36162972 -38.49586916
OS 56.36162972 -38.49864284
OS 56.36162972 -38.50234108
OS 56.36070516 -38.508813
OS 56.3597806 -38.51528492
OS 56.35885604 -38.52360596
OS 56.35700692 -38.53285156
OS 56.3551578 -38.54302172
OS 56.34868588 -38.5642866
OS 56.34498764 -38.57538132
OS 56.33944028 -38.5874006
OS 56.33296836 -38.59941988
OS 56.32649644 -38.6105146
OS 56.3181754 -38.62160932
OS 56.3089298 -38.63270404
OS 56.30800524 -38.6336286
OS 56.30615612 -38.63547772
OS 56.30338244 -38.6382514
OS 56.29875964 -38.64102508
OS 56.29321228 -38.64564788
OS 56.2858158 -38.65027068
OS 56.2765702 -38.65581804
OS 56.26640004 -38.66044084
OS 56.25438076 -38.6659882
OS 56.24051236 -38.67153556
OS 56.2257194 -38.67615836
OS 56.20815276 -38.6798566
OS 56.18966156 -38.68355484
OS 56.16932124 -38.68632852
OS 56.14620724 -38.68817764
OS 56.12216868 -38.6891022
OS 55.95852156 -38.6891022
OS 55.95852156 -38.94890356
OS 55.87346204 -38.94890356
OS 55.87346204 -38.30910804
OS 56.13603708 -38.30910804
OS 56.14990548 -38.3100326
OE
OB 57.07723916 -38.94890356 I
OS 56.99587788 -38.94890356
OS 56.99587788 -38.41358332
OS 56.80911676 -38.94890356
OS 56.73330284 -38.94890356
OS 56.54839084 -38.40433772
OS 56.54839084 -38.94890356
OS 56.46702956 -38.94890356
OS 56.46702956 -38.30910804
OS 56.59369428 -38.30910804
OS 56.74532212 -38.763067
OS 56.74532212 -38.76399156
OS 56.74624668 -38.76584068
OS 56.74717124 -38.76861436
OS 56.74902036 -38.77323716
OS 56.7527186 -38.78433188
OS 56.7573414 -38.79820028
OS 56.7619642 -38.8139178
OS 56.76751156 -38.82963532
OS 56.77213436 -38.84442828
OS 56.7758326 -38.85737212
OS 56.77675716 -38.855523
OS 56.77768172 -38.8509002
OS 56.7804554 -38.84257916
OS 56.78415364 -38.83148444
OS 56.78877644 -38.81669148
OS 56.79524836 -38.79912484
OS 56.80172028 -38.77878452
OS 56.81004132 -38.75474596
OS 56.96351828 -38.30910804
OS 57.07723916 -38.30910804
OS 57.07723916 -38.94890356
OE
OB 55.39084172 -38.94890356 I
OS 55.31225412 -38.94890356
OS 55.31225412 -38.4487166
OS 55.31132956 -38.44964116
OS 55.30670676 -38.4533394
OS 55.3011594 -38.45888676
OS 55.2919138 -38.46535868
OS 55.28174364 -38.47367972
OS 55.2687998 -38.48292532
OS 55.25400684 -38.49309548
OS 55.23736476 -38.50326564
OS 55.2364402 -38.50326564
OS 55.23551564 -38.5041902
OS 55.22996828 -38.50788844
OS 55.22072268 -38.51251124
OS 55.20962796 -38.5180586
OS 55.19668412 -38.52453052
OS 55.18281572 -38.53100244
OS 55.16894732 -38.53747436
OS 55.15507892 -38.54302172
OS 55.15507892 -38.4672078
OS 55.15600348 -38.4672078
OS 55.1578526 -38.46535868
OS 55.16155084 -38.46443412
OS 55.16617364 -38.46166044
OS 55.171721 -38.45888676
OS 55.17819292 -38.45518852
OS 55.19391044 -38.44594292
OS 55.21240164 -38.43577276
OS 55.23089284 -38.42282892
OS 55.2503086 -38.40803596
OS 55.26972436 -38.39231844
OS 55.27064892 -38.39139388
OS 55.27157348 -38.39046932
OS 55.27434716 -38.38769564
OS 55.2780454 -38.38492196
OS 55.28636644 -38.37567636
OS 55.29746116 -38.36458164
OS 55.30855588 -38.3516378
OS 55.32057516 -38.33684484
OS 55.33074532 -38.32205188
OS 55.33999092 -38.30633436
OS 55.39084172 -38.30633436
OS 55.39084172 -38.94890356
OE
OB 54.48199924 -38.94890356 I
OS 54.39231692 -38.94890356
OS 54.39231692 -38.85922124
OS 54.48199924 -38.85922124
OS 54.48199924 -38.94890356
OE
OB 54.825011 -38.30725892 I
OS 54.83703028 -38.30910804
OS 54.85089868 -38.31188172
OS 54.86569164 -38.31557996
OS 54.88140916 -38.32020276
OS 54.89620212 -38.32759924
OS 54.89712668 -38.32759924
OS 54.89805124 -38.3285238
OS 54.90267404 -38.33129748
OS 54.91007052 -38.33592028
OS 54.91931612 -38.3423922
OS 54.92948628 -38.3516378
OS 54.940581 -38.36180796
OS 54.95075116 -38.37382724
OS 54.96092132 -38.38769564
OS 54.96184588 -38.38954476
OS 54.96554412 -38.39416756
OS 54.96924236 -38.4024886
OS 54.97571428 -38.41450788
OS 54.98126164 -38.42837628
OS 54.98865812 -38.4440938
OS 54.99513004 -38.462585
OS 55.0006774 -38.48292532
OS 55.0006774 -38.48384988
OS 55.00160196 -38.485699
OS 55.00252652 -38.48847268
OS 55.00345108 -38.49309548
OS 55.00437564 -38.49864284
OS 55.0053002 -38.50511476
OS 55.00714932 -38.5134358
OS 55.00807388 -38.5226814
OS 55.009923 -38.53285156
OS 55.01084756 -38.54394628
OS 55.01177212 -38.55689012
OS 55.01362124 -38.56983396
OS 55.0145458 -38.58462692
OS 55.0145458 -38.59941988
OS 55.01547036 -38.61606196
OS 55.01547036 -38.6336286
OS 55.01547036 -38.63455316
OS 55.01547036 -38.6382514
OS 55.01547036 -38.64472332
OS 55.01547036 -38.6521198
OS 55.0145458 -38.66228996
OS 55.0145458 -38.67338468
OS 55.01362124 -38.68540396
OS 55.01269668 -38.6983478
OS 55.009923 -38.72793372
OS 55.0053002 -38.7584442
OS 54.99975284 -38.78803012
OS 54.9960546 -38.80189852
OS 54.9914318 -38.81576692
OS 54.9914318 -38.81669148
OS 54.99050724 -38.8185406
OS 54.98865812 -38.82223884
OS 54.986809 -38.82686164
OS 54.98495988 -38.83333356
OS 54.98126164 -38.83980548
OS 54.97386516 -38.855523
OS 54.96461956 -38.87216508
OS 54.95260028 -38.89065628
OS 54.93873188 -38.90729836
OS 54.9220898 -38.92301588
OS 54.92116524 -38.92301588
OS 54.92024068 -38.924865
OS 54.917467 -38.92671412
OS 54.91376876 -38.92856324
OS 54.90914596 -38.93133692
OS 54.90452316 -38.93503516
OS 54.89065476 -38.94150708
OS 54.87401268 -38.947979
OS 54.85459692 -38.95445092
OS 54.83148292 -38.95814916
OS 54.8065198 -38.95999828
OS 54.7972742 -38.95999828
OS 54.79080228 -38.95907372
OS 54.7834058 -38.95814916
OS 54.7741602 -38.95630004
OS 54.76399004 -38.95445092
OS 54.75289532 -38.95167724
OS 54.7418006 -38.947979
OS 54.72978132 -38.94428076
OS 54.71776204 -38.9387334
OS 54.70574276 -38.93226148
OS 54.69372348 -38.924865
OS 54.6817042 -38.9156194
OS 54.67060948 -38.90544924
OS 54.66043932 -38.89435452
OS 54.65951476 -38.89342996
OS 54.65766564 -38.89065628
OS 54.65489196 -38.88603348
OS 54.65026916 -38.878637
OS 54.64564636 -38.87031596
OS 54.64102356 -38.85922124
OS 54.63455164 -38.8462774
OS 54.62900428 -38.83148444
OS 54.62345692 -38.81484236
OS 54.61790956 -38.7954266
OS 54.6123622 -38.77416172
OS 54.6077394 -38.75012316
OS 54.6031166 -38.72423548
OS 54.60034292 -38.69649868
OS 54.5984938 -38.6659882
OS 54.59756924 -38.6336286
OS 54.59756924 -38.63270404
OS 54.59756924 -38.6290058
OS 54.59756924 -38.62253388
OS 54.59756924 -38.6151374
OS 54.5984938 -38.60496724
OS 54.5984938 -38.59387252
OS 54.59941836 -38.58185324
OS 54.60034292 -38.56798484
OS 54.6031166 -38.53932348
OS 54.6077394 -38.508813
OS 54.61328676 -38.47830252
OS 54.616985 -38.46443412
OS 54.62068324 -38.45056572
OS 54.62068324 -38.44964116
OS 54.6216078 -38.44779204
OS 54.62345692 -38.4440938
OS 54.62530604 -38.439471
OS 54.62715516 -38.43299908
OS 54.6308534 -38.42652716
OS 54.63824988 -38.41080964
OS 54.64749548 -38.39416756
OS 54.65951476 -38.37660092
OS 54.67338316 -38.35903428
OS 54.69002524 -38.34424132
OS 54.6909498 -38.34424132
OS 54.69187436 -38.3423922
OS 54.69464804 -38.34054308
OS 54.69834628 -38.33869396
OS 54.70296908 -38.33499572
OS 54.70851644 -38.33222204
OS 54.72238484 -38.32482556
OS 54.73902692 -38.31835364
OS 54.75844268 -38.31188172
OS 54.78155668 -38.30818348
OS 54.8065198 -38.30633436
OS 54.81484084 -38.30633436
OS 54.825011 -38.30725892
OE
OB 49.95350436 -38.72331092 I
OS 50.040413 -38.72331092
OS 50.040413 -38.7954266
OS 49.95350436 -38.7954266
OS 49.95350436 -38.94890356
OS 49.87491676 -38.94890356
OS 49.87491676 -38.7954266
OS 49.5966242 -38.7954266
OS 49.5966242 -38.72331092
OS 49.88970972 -38.30910804
OS 49.95350436 -38.30910804
OS 49.95350436 -38.72331092
OE
OB 50.1467374 -38.95999828 I
OS 50.08386732 -38.95999828
OS 50.26970388 -38.29801332
OS 50.33257396 -38.29801332
OS 50.1467374 -38.95999828
OE
OB 50.59699812 -38.30725892 I
OS 50.6043946 -38.30818348
OS 50.6136402 -38.30910804
OS 50.62381036 -38.31095716
OS 50.63398052 -38.31280628
OS 50.65801908 -38.3192782
OS 50.68205764 -38.3285238
OS 50.69407692 -38.33407116
OS 50.7060962 -38.34054308
OS 50.71719092 -38.34886412
OS 50.72736108 -38.35810972
OS 50.72828564 -38.35903428
OS 50.73013476 -38.35995884
OS 50.73198388 -38.36365708
OS 50.73568212 -38.36735532
OS 50.74030492 -38.37197812
OS 50.74492772 -38.37845004
OS 50.74955052 -38.38492196
OS 50.75509788 -38.393243
OS 50.76434348 -38.41080964
OS 50.77358908 -38.43299908
OS 50.77728732 -38.4440938
OS 50.77913644 -38.45703764
OS 50.78098556 -38.46998148
OS 50.78191012 -38.48384988
OS 50.78191012 -38.485699
OS 50.78191012 -38.4903218
OS 50.78098556 -38.49771828
OS 50.780061 -38.50788844
OS 50.77821188 -38.51898316
OS 50.77451364 -38.531927
OS 50.7708154 -38.5457954
OS 50.76526804 -38.5596638
OS 50.76434348 -38.56151292
OS 50.76249436 -38.56613572
OS 50.75879612 -38.5735322
OS 50.75324876 -38.58370236
OS 50.74585228 -38.59479708
OS 50.73660668 -38.60866548
OS 50.72551196 -38.62253388
OS 50.71256812 -38.6382514
OS 50.710719 -38.64010052
OS 50.7060962 -38.64564788
OS 50.7014734 -38.65027068
OS 50.6968506 -38.65489348
OS 50.69130324 -38.66044084
OS 50.68390676 -38.66783732
OS 50.67651028 -38.6752338
OS 50.66726468 -38.68355484
OS 50.65801908 -38.69280044
OS 50.64692436 -38.7029706
OS 50.63490508 -38.71314076
OS 50.62196124 -38.72516004
OS 50.60716828 -38.73717932
OS 50.59237532 -38.75012316
OS 50.59145076 -38.75104772
OS 50.58960164 -38.75289684
OS 50.5859034 -38.75567052
OS 50.5812806 -38.75936876
OS 50.57573324 -38.76491612
OS 50.56926132 -38.77046348
OS 50.55446836 -38.78248276
OS 50.53875084 -38.79635116
OS 50.52395788 -38.81021956
OS 50.51101404 -38.82223884
OS 50.50546668 -38.82686164
OS 50.50084388 -38.83148444
OS 50.49991932 -38.832409
OS 50.49714564 -38.83518268
OS 50.4934474 -38.83888092
OS 50.4888246 -38.84442828
OS 50.4842018 -38.8509002
OS 50.47865444 -38.85737212
OS 50.46755972 -38.87308964
OS 50.78283468 -38.87308964
OS 50.78283468 -38.94890356
OS 50.35846164 -38.94890356
OS 50.35846164 -38.947979
OS 50.35846164 -38.94428076
OS 50.35846164 -38.9387334
OS 50.3593862 -38.93133692
OS 50.36031076 -38.92301588
OS 50.36215988 -38.91377028
OS 50.364009 -38.90452468
OS 50.36770724 -38.89435452
OS 50.36770724 -38.89342996
OS 50.3686318 -38.8925054
OS 50.37048092 -38.88695804
OS 50.37417916 -38.878637
OS 50.37972652 -38.86754228
OS 50.387123 -38.85459844
OS 50.3963686 -38.83980548
OS 50.40653876 -38.82501252
OS 50.4194826 -38.809295
OS 50.4194826 -38.80837044
OS 50.42133172 -38.80744588
OS 50.42595452 -38.80189852
OS 50.43427556 -38.79357748
OS 50.44629484 -38.7815582
OS 50.46016324 -38.7676898
OS 50.47772988 -38.75104772
OS 50.49899476 -38.73255652
OS 50.52210876 -38.71314076
OS 50.52303332 -38.7122162
OS 50.52673156 -38.70944252
OS 50.53227892 -38.70481972
OS 50.53875084 -38.69927236
OS 50.54707188 -38.69187588
OS 50.55724204 -38.68355484
OS 50.5674122 -38.67430924
OS 50.57943148 -38.66413908
OS 50.60254548 -38.64194964
OS 50.62565948 -38.6197602
OS 50.6367542 -38.60866548
OS 50.64692436 -38.59757076
OS 50.65616996 -38.5874006
OS 50.66356644 -38.57723044
OS 50.66356644 -38.57630588
OS 50.66541556 -38.57538132
OS 50.66726468 -38.57260764
OS 50.6691138 -38.5689094
OS 50.67558572 -38.55873924
OS 50.6829822 -38.54671996
OS 50.68945412 -38.531927
OS 50.69592604 -38.51620948
OS 50.69962428 -38.49864284
OS 50.7014734 -38.48200076
OS 50.7014734 -38.4810762
OS 50.7014734 -38.48015164
OS 50.70054884 -38.47460428
OS 50.69962428 -38.46535868
OS 50.6968506 -38.45518852
OS 50.69315236 -38.44224468
OS 50.68668044 -38.42930084
OS 50.6783594 -38.416357
OS 50.66726468 -38.40341316
OS 50.66541556 -38.40156404
OS 50.66079276 -38.3978658
OS 50.65432084 -38.393243
OS 50.64415068 -38.38677108
OS 50.63120684 -38.38122372
OS 50.61641388 -38.37567636
OS 50.59884724 -38.37197812
OS 50.57943148 -38.37105356
OS 50.57388412 -38.37105356
OS 50.57018588 -38.37197812
OS 50.55909116 -38.37290268
OS 50.54614732 -38.37567636
OS 50.53227892 -38.3793746
OS 50.5165614 -38.38584652
OS 50.50176844 -38.39416756
OS 50.48790004 -38.40526228
OS 50.48605092 -38.4071114
OS 50.48235268 -38.4117342
OS 50.47680532 -38.41913068
OS 50.47125796 -38.4302254
OS 50.46478604 -38.44316924
OS 50.45923868 -38.45981132
OS 50.45554044 -38.47830252
OS 50.45369132 -38.4995674
OS 50.3732546 -38.49124636
OS 50.3732546 -38.4903218
OS 50.37417916 -38.48754812
OS 50.37417916 -38.48292532
OS 50.37510372 -38.4764534
OS 50.37695284 -38.46905692
OS 50.37880196 -38.46073588
OS 50.38157564 -38.45056572
OS 50.38434932 -38.44039556
OS 50.3917458 -38.41820612
OS 50.40284052 -38.39601668
OS 50.40931244 -38.38492196
OS 50.41763348 -38.37382724
OS 50.42595452 -38.36365708
OS 50.43520012 -38.35441148
OS 50.43612468 -38.35348692
OS 50.4379738 -38.35256236
OS 50.44074748 -38.34978868
OS 50.44537028 -38.347015
OS 50.45091764 -38.34331676
OS 50.45738956 -38.33961852
OS 50.46478604 -38.33499572
OS 50.47403164 -38.33037292
OS 50.4842018 -38.32575012
OS 50.49529652 -38.32112732
OS 50.5073158 -38.31742908
OS 50.52025964 -38.31373084
OS 50.53412804 -38.31095716
OS 50.548921 -38.30818348
OS 50.56463852 -38.30725892
OS 50.5812806 -38.30633436
OS 50.5905262 -38.30633436
OS 50.59699812 -38.30725892
OE
OB 48.67576244 -38.94890356 I
OS 48.59717484 -38.94890356
OS 48.59717484 -38.4487166
OS 48.59625028 -38.44964116
OS 48.59162748 -38.4533394
OS 48.58608012 -38.45888676
OS 48.57683452 -38.46535868
OS 48.56666436 -38.47367972
OS 48.55372052 -38.48292532
OS 48.53892756 -38.49309548
OS 48.52228548 -38.50326564
OS 48.52136092 -38.50326564
OS 48.52043636 -38.5041902
OS 48.514889 -38.50788844
OS 48.5056434 -38.51251124
OS 48.49454868 -38.5180586
OS 48.48160484 -38.52453052
OS 48.46773644 -38.53100244
OS 48.45386804 -38.53747436
OS 48.43999964 -38.54302172
OS 48.43999964 -38.4672078
OS 48.4409242 -38.4672078
OS 48.44277332 -38.46535868
OS 48.44647156 -38.46443412
OS 48.45109436 -38.46166044
OS 48.45664172 -38.45888676
OS 48.46311364 -38.45518852
OS 48.47883116 -38.44594292
OS 48.49732236 -38.43577276
OS 48.51581356 -38.42282892
OS 48.53522932 -38.40803596
OS 48.55464508 -38.39231844
OS 48.55556964 -38.39139388
OS 48.5564942 -38.39046932
OS 48.55926788 -38.38769564
OS 48.56296612 -38.38492196
OS 48.57128716 -38.37567636
OS 48.58238188 -38.36458164
OS 48.5934766 -38.3516378
OS 48.60549588 -38.33684484
OS 48.61566604 -38.32205188
OS 48.62491164 -38.30633436
OS 48.67576244 -38.30633436
OS 48.67576244 -38.94890356
OE
OB 48.9032042 -38.95999828 I
OS 48.84033412 -38.95999828
OS 49.02617068 -38.29801332
OS 49.08904076 -38.29801332
OS 48.9032042 -38.95999828
OE
OB 49.35346492 -38.30725892 I
OS 49.3608614 -38.30818348
OS 49.370107 -38.30910804
OS 49.38027716 -38.31095716
OS 49.39044732 -38.31280628
OS 49.41448588 -38.3192782
OS 49.43852444 -38.3285238
OS 49.45054372 -38.33407116
OS 49.462563 -38.34054308
OS 49.47365772 -38.34886412
OS 49.48382788 -38.35810972
OS 49.48475244 -38.35903428
OS 49.48660156 -38.35995884
OS 49.48845068 -38.36365708
OS 49.49214892 -38.36735532
OS 49.49677172 -38.37197812
OS 49.50139452 -38.37845004
OS 49.50601732 -38.38492196
OS 49.51156468 -38.393243
OS 49.52081028 -38.41080964
OS 49.53005588 -38.43299908
OS 49.53375412 -38.4440938
OS 49.53560324 -38.45703764
OS 49.53745236 -38.46998148
OS 49.53837692 -38.48384988
OS 49.53837692 -38.485699
OS 49.53837692 -38.4903218
OS 49.53745236 -38.49771828
OS 49.5365278 -38.50788844
OS 49.53467868 -38.51898316
OS 49.53098044 -38.531927
OS 49.5272822 -38.5457954
OS 49.52173484 -38.5596638
OS 49.52081028 -38.56151292
OS 49.51896116 -38.56613572
OS 49.51526292 -38.5735322
OS 49.50971556 -38.58370236
OS 49.50231908 -38.59479708
OS 49.49307348 -38.60866548
OS 49.48197876 -38.62253388
OS 49.46903492 -38.6382514
OS 49.4671858 -38.64010052
OS 49.462563 -38.64564788
OS 49.4579402 -38.65027068
OS 49.4533174 -38.65489348
OS 49.44777004 -38.66044084
OS 49.44037356 -38.66783732
OS 49.43297708 -38.6752338
OS 49.42373148 -38.68355484
OS 49.41448588 -38.69280044
OS 49.40339116 -38.7029706
OS 49.39137188 -38.71314076
OS 49.37842804 -38.72516004
OS 49.36363508 -38.73717932
OS 49.34884212 -38.75012316
OS 49.34791756 -38.75104772
OS 49.34606844 -38.75289684
OS 49.3423702 -38.75567052
OS 49.3377474 -38.75936876
OS 49.33220004 -38.76491612
OS 49.32572812 -38.77046348
OS 49.31093516 -38.78248276
OS 49.29521764 -38.79635116
OS 49.28042468 -38.81021956
OS 49.26748084 -38.82223884
OS 49.26193348 -38.82686164
OS 49.25731068 -38.83148444
OS 49.25638612 -38.832409
OS 49.25361244 -38.83518268
OS 49.2499142 -38.83888092
OS 49.2452914 -38.84442828
OS 49.2406686 -38.8509002
OS 49.23512124 -38.85737212
OS 49.22402652 -38.87308964
OS 49.53930148 -38.87308964
OS 49.53930148 -38.94890356
OS 49.11492844 -38.94890356
OS 49.11492844 -38.947979
OS 49.11492844 -38.94428076
OS 49.11492844 -38.9387334
OS 49.115853 -38.93133692
OS 49.11677756 -38.92301588
OS 49.11862668 -38.91377028
OS 49.1204758 -38.90452468
OS 49.12417404 -38.89435452
OS 49.12417404 -38.89342996
OS 49.1250986 -38.8925054
OS 49.12694772 -38.88695804
OS 49.13064596 -38.878637
OS 49.13619332 -38.86754228
OS 49.1435898 -38.85459844
OS 49.1528354 -38.83980548
OS 49.16300556 -38.82501252
OS 49.1759494 -38.809295
OS 49.1759494 -38.80837044
OS 49.17779852 -38.80744588
OS 49.18242132 -38.80189852
OS 49.19074236 -38.79357748
OS 49.20276164 -38.7815582
OS 49.21663004 -38.7676898
OS 49.23419668 -38.75104772
OS 49.25546156 -38.73255652
OS 49.27857556 -38.71314076
OS 49.27950012 -38.7122162
OS 49.28319836 -38.70944252
OS 49.28874572 -38.70481972
OS 49.29521764 -38.69927236
OS 49.30353868 -38.69187588
OS 49.31370884 -38.68355484
OS 49.323879 -38.67430924
OS 49.33589828 -38.66413908
OS 49.35901228 -38.64194964
OS 49.38212628 -38.6197602
OS 49.393221 -38.60866548
OS 49.40339116 -38.59757076
OS 49.41263676 -38.5874006
OS 49.42003324 -38.57723044
OS 49.42003324 -38.57630588
OS 49.42188236 -38.57538132
OS 49.42373148 -38.57260764
OS 49.4255806 -38.5689094
OS 49.43205252 -38.55873924
OS 49.439449 -38.54671996
OS 49.44592092 -38.531927
OS 49.45239284 -38.51620948
OS 49.45609108 -38.49864284
OS 49.4579402 -38.48200076
OS 49.4579402 -38.4810762
OS 49.4579402 -38.48015164
OS 49.45701564 -38.47460428
OS 49.45609108 -38.46535868
OS 49.4533174 -38.45518852
OS 49.44961916 -38.44224468
OS 49.44314724 -38.42930084
OS 49.4348262 -38.416357
OS 49.42373148 -38.40341316
OS 49.42188236 -38.40156404
OS 49.41725956 -38.3978658
OS 49.41078764 -38.393243
OS 49.40061748 -38.38677108
OS 49.38767364 -38.38122372
OS 49.37288068 -38.37567636
OS 49.35531404 -38.37197812
OS 49.33589828 -38.37105356
OS 49.33035092 -38.37105356
OS 49.32665268 -38.37197812
OS 49.31555796 -38.37290268
OS 49.30261412 -38.37567636
OS 49.28874572 -38.3793746
OS 49.2730282 -38.38584652
OS 49.25823524 -38.39416756
OS 49.24436684 -38.40526228
OS 49.24251772 -38.4071114
OS 49.23881948 -38.4117342
OS 49.23327212 -38.41913068
OS 49.22772476 -38.4302254
OS 49.22125284 -38.44316924
OS 49.21570548 -38.45981132
OS 49.21200724 -38.47830252
OS 49.21015812 -38.4995674
OS 49.1297214 -38.49124636
OS 49.1297214 -38.4903218
OS 49.13064596 -38.48754812
OS 49.13064596 -38.48292532
OS 49.13157052 -38.4764534
OS 49.13341964 -38.46905692
OS 49.13526876 -38.46073588
OS 49.13804244 -38.45056572
OS 49.14081612 -38.44039556
OS 49.1482126 -38.41820612
OS 49.15930732 -38.39601668
OS 49.16577924 -38.38492196
OS 49.17410028 -38.37382724
OS 49.18242132 -38.36365708
OS 49.19166692 -38.35441148
OS 49.19259148 -38.35348692
OS 49.1944406 -38.35256236
OS 49.19721428 -38.34978868
OS 49.20183708 -38.347015
OS 49.20738444 -38.34331676
OS 49.21385636 -38.33961852
OS 49.22125284 -38.33499572
OS 49.23049844 -38.33037292
OS 49.2406686 -38.32575012
OS 49.25176332 -38.32112732
OS 49.2637826 -38.31742908
OS 49.27672644 -38.31373084
OS 49.29059484 -38.31095716
OS 49.3053878 -38.30818348
OS 49.32110532 -38.30725892
OS 49.3377474 -38.30633436
OS 49.346993 -38.30633436
OS 49.35346492 -38.30725892
OE
OB 51.0944114 -38.30725892 I
OS 51.10643068 -38.30910804
OS 51.12029908 -38.31188172
OS 51.13509204 -38.31557996
OS 51.15080956 -38.32020276
OS 51.16560252 -38.32759924
OS 51.16652708 -38.32759924
OS 51.16745164 -38.3285238
OS 51.17207444 -38.33129748
OS 51.17947092 -38.33592028
OS 51.18871652 -38.3423922
OS 51.19888668 -38.3516378
OS 51.2099814 -38.36180796
OS 51.22015156 -38.37382724
OS 51.23032172 -38.38769564
OS 51.23124628 -38.38954476
OS 51.23494452 -38.39416756
OS 51.23864276 -38.4024886
OS 51.24511468 -38.41450788
OS 51.25066204 -38.42837628
OS 51.25805852 -38.4440938
OS 51.26453044 -38.462585
OS 51.2700778 -38.48292532
OS 51.2700778 -38.48384988
OS 51.27100236 -38.485699
OS 51.27192692 -38.48847268
OS 51.27285148 -38.49309548
OS 51.27377604 -38.49864284
OS 51.2747006 -38.50511476
OS 51.27654972 -38.5134358
OS 51.27747428 -38.5226814
OS 51.2793234 -38.53285156
OS 51.28024796 -38.54394628
OS 51.28117252 -38.55689012
OS 51.28302164 -38.56983396
OS 51.2839462 -38.58462692
OS 51.2839462 -38.59941988
OS 51.28487076 -38.61606196
OS 51.28487076 -38.6336286
OS 51.28487076 -38.63455316
OS 51.28487076 -38.6382514
OS 51.28487076 -38.64472332
OS 51.28487076 -38.6521198
OS 51.2839462 -38.66228996
OS 51.2839462 -38.67338468
OS 51.28302164 -38.68540396
OS 51.28209708 -38.6983478
OS 51.2793234 -38.72793372
OS 51.2747006 -38.7584442
OS 51.26915324 -38.78803012
OS 51.265455 -38.80189852
OS 51.2608322 -38.81576692
OS 51.2608322 -38.81669148
OS 51.25990764 -38.8185406
OS 51.25805852 -38.82223884
OS 51.2562094 -38.82686164
OS 51.25436028 -38.83333356
OS 51.25066204 -38.83980548
OS 51.24326556 -38.855523
OS 51.23401996 -38.87216508
OS 51.22200068 -38.89065628
OS 51.20813228 -38.90729836
OS 51.1914902 -38.92301588
OS 51.19056564 -38.92301588
OS 51.18964108 -38.924865
OS 51.1868674 -38.92671412
OS 51.18316916 -38.92856324
OS 51.17854636 -38.93133692
OS 51.17392356 -38.93503516
OS 51.16005516 -38.94150708
OS 51.14341308 -38.947979
OS 51.12399732 -38.95445092
OS 51.10088332 -38.95814916
OS 51.0759202 -38.95999828
OS 51.0666746 -38.95999828
OS 51.06020268 -38.95907372
OS 51.0528062 -38.95814916
OS 51.0435606 -38.95630004
OS 51.03339044 -38.95445092
OS 51.02229572 -38.95167724
OS 51.011201 -38.947979
OS 50.99918172 -38.94428076
OS 50.98716244 -38.9387334
OS 50.97514316 -38.93226148
OS 50.96312388 -38.924865
OS 50.9511046 -38.9156194
OS 50.94000988 -38.90544924
OS 50.92983972 -38.89435452
OS 50.92891516 -38.89342996
OS 50.92706604 -38.89065628
OS 50.92429236 -38.88603348
OS 50.91966956 -38.878637
OS 50.91504676 -38.87031596
OS 50.91042396 -38.85922124
OS 50.90395204 -38.8462774
OS 50.89840468 -38.83148444
OS 50.89285732 -38.81484236
OS 50.88730996 -38.7954266
OS 50.8817626 -38.77416172
OS 50.8771398 -38.75012316
OS 50.872517 -38.72423548
OS 50.86974332 -38.69649868
OS 50.8678942 -38.6659882
OS 50.86696964 -38.6336286
OS 50.86696964 -38.63270404
OS 50.86696964 -38.6290058
OS 50.86696964 -38.62253388
OS 50.86696964 -38.6151374
OS 50.8678942 -38.60496724
OS 50.8678942 -38.59387252
OS 50.86881876 -38.58185324
OS 50.86974332 -38.56798484
OS 50.872517 -38.53932348
OS 50.8771398 -38.508813
OS 50.88268716 -38.47830252
OS 50.8863854 -38.46443412
OS 50.89008364 -38.45056572
OS 50.89008364 -38.44964116
OS 50.8910082 -38.44779204
OS 50.89285732 -38.4440938
OS 50.89470644 -38.439471
OS 50.89655556 -38.43299908
OS 50.9002538 -38.42652716
OS 50.90765028 -38.41080964
OS 50.91689588 -38.39416756
OS 50.92891516 -38.37660092
OS 50.94278356 -38.35903428
OS 50.95942564 -38.34424132
OS 50.9603502 -38.34424132
OS 50.96127476 -38.3423922
OS 50.96404844 -38.34054308
OS 50.96774668 -38.33869396
OS 50.97236948 -38.33499572
OS 50.97791684 -38.33222204
OS 50.99178524 -38.32482556
OS 51.00842732 -38.31835364
OS 51.02784308 -38.31188172
OS 51.05095708 -38.30818348
OS 51.0759202 -38.30633436
OS 51.08424124 -38.30633436
OS 51.0944114 -38.30725892
OE
OB 51.59182468 -38.30725892 I
OS 51.59922116 -38.30818348
OS 51.60846676 -38.30910804
OS 51.61863692 -38.31095716
OS 51.62880708 -38.31280628
OS 51.65284564 -38.3192782
OS 51.6768842 -38.3285238
OS 51.68890348 -38.33407116
OS 51.70092276 -38.34054308
OS 51.71201748 -38.34886412
OS 51.72218764 -38.35810972
OS 51.7231122 -38.35903428
OS 51.72496132 -38.35995884
OS 51.72681044 -38.36365708
OS 51.73050868 -38.36735532
OS 51.73513148 -38.37197812
OS 51.73975428 -38.37845004
OS 51.74437708 -38.38492196
OS 51.74992444 -38.393243
OS 51.75917004 -38.41080964
OS 51.76841564 -38.43299908
OS 51.77211388 -38.4440938
OS 51.773963 -38.45703764
OS 51.77581212 -38.46998148
OS 51.77673668 -38.48384988
OS 51.77673668 -38.485699
OS 51.77673668 -38.4903218
OS 51.77581212 -38.49771828
OS 51.77488756 -38.50788844
OS 51.77303844 -38.51898316
OS 51.7693402 -38.531927
OS 51.76564196 -38.5457954
OS 51.7600946 -38.5596638
OS 51.75917004 -38.56151292
OS 51.75732092 -38.56613572
OS 51.75362268 -38.5735322
OS 51.74807532 -38.58370236
OS 51.74067884 -38.59479708
OS 51.73143324 -38.60866548
OS 51.72033852 -38.62253388
OS 51.70739468 -38.6382514
OS 51.70554556 -38.64010052
OS 51.70092276 -38.64564788
OS 51.69629996 -38.65027068
OS 51.69167716 -38.65489348
OS 51.6861298 -38.66044084
OS 51.67873332 -38.66783732
OS 51.67133684 -38.6752338
OS 51.66209124 -38.68355484
OS 51.65284564 -38.69280044
OS 51.64175092 -38.7029706
OS 51.62973164 -38.71314076
OS 51.6167878 -38.72516004
OS 51.60199484 -38.73717932
OS 51.58720188 -38.75012316
OS 51.58627732 -38.75104772
OS 51.5844282 -38.75289684
OS 51.58072996 -38.75567052
OS 51.57610716 -38.75936876
OS 51.5705598 -38.76491612
OS 51.56408788 -38.77046348
OS 51.54929492 -38.78248276
OS 51.5335774 -38.79635116
OS 51.51878444 -38.81021956
OS 51.5058406 -38.82223884
OS 51.50029324 -38.82686164
OS 51.49567044 -38.83148444
OS 51.49474588 -38.832409
OS 51.4919722 -38.83518268
OS 51.48827396 -38.83888092
OS 51.48365116 -38.84442828
OS 51.47902836 -38.8509002
OS 51.473481 -38.85737212
OS 51.46238628 -38.87308964
OS 51.77766124 -38.87308964
OS 51.77766124 -38.94890356
OS 51.3532882 -38.94890356
OS 51.3532882 -38.947979
OS 51.3532882 -38.94428076
OS 51.3532882 -38.9387334
OS 51.35421276 -38.93133692
OS 51.35513732 -38.92301588
OS 51.35698644 -38.91377028
OS 51.35883556 -38.90452468
OS 51.3625338 -38.89435452
OS 51.3625338 -38.89342996
OS 51.36345836 -38.8925054
OS 51.36530748 -38.88695804
OS 51.36900572 -38.878637
OS 51.37455308 -38.86754228
OS 51.38194956 -38.85459844
OS 51.39119516 -38.83980548
OS 51.40136532 -38.82501252
OS 51.41430916 -38.809295
OS 51.41430916 -38.80837044
OS 51.41615828 -38.80744588
OS 51.42078108 -38.80189852
OS 51.42910212 -38.79357748
OS 51.4411214 -38.7815582
OS 51.4549898 -38.7676898
OS 51.47255644 -38.75104772
OS 51.49382132 -38.73255652
OS 51.51693532 -38.71314076
OS 51.51785988 -38.7122162
OS 51.52155812 -38.70944252
OS 51.52710548 -38.70481972
OS 51.5335774 -38.69927236
OS 51.54189844 -38.69187588
OS 51.5520686 -38.68355484
OS 51.56223876 -38.67430924
OS 51.57425804 -38.66413908
OS 51.59737204 -38.64194964
OS 51.62048604 -38.6197602
OS 51.63158076 -38.60866548
OS 51.64175092 -38.59757076
OS 51.65099652 -38.5874006
OS 51.658393 -38.57723044
OS 51.658393 -38.57630588
OS 51.66024212 -38.57538132
OS 51.66209124 -38.57260764
OS 51.66394036 -38.5689094
OS 51.67041228 -38.55873924
OS 51.67780876 -38.54671996
OS 51.68428068 -38.531927
OS 51.6907526 -38.51620948
OS 51.69445084 -38.49864284
OS 51.69629996 -38.48200076
OS 51.69629996 -38.4810762
OS 51.69629996 -38.48015164
OS 51.6953754 -38.47460428
OS 51.69445084 -38.46535868
OS 51.69167716 -38.45518852
OS 51.68797892 -38.44224468
OS 51.681507 -38.42930084
OS 51.67318596 -38.416357
OS 51.66209124 -38.40341316
OS 51.66024212 -38.40156404
OS 51.65561932 -38.3978658
OS 51.6491474 -38.393243
OS 51.63897724 -38.38677108
OS 51.6260334 -38.38122372
OS 51.61124044 -38.37567636
OS 51.5936738 -38.37197812
OS 51.57425804 -38.37105356
OS 51.56871068 -38.37105356
OS 51.56501244 -38.37197812
OS 51.55391772 -38.37290268
OS 51.54097388 -38.37567636
OS 51.52710548 -38.3793746
OS 51.51138796 -38.38584652
OS 51.496595 -38.39416756
OS 51.4827266 -38.40526228
OS 51.48087748 -38.4071114
OS 51.47717924 -38.4117342
OS 51.47163188 -38.41913068
OS 51.46608452 -38.4302254
OS 51.4596126 -38.44316924
OS 51.45406524 -38.45981132
OS 51.450367 -38.47830252
OS 51.44851788 -38.4995674
OS 51.36808116 -38.49124636
OS 51.36808116 -38.4903218
OS 51.36900572 -38.48754812
OS 51.36900572 -38.48292532
OS 51.36993028 -38.4764534
OS 51.3717794 -38.46905692
OS 51.37362852 -38.46073588
OS 51.3764022 -38.45056572
OS 51.37917588 -38.44039556
OS 51.38657236 -38.41820612
OS 51.39766708 -38.39601668
OS 51.404139 -38.38492196
OS 51.41246004 -38.37382724
OS 51.42078108 -38.36365708
OS 51.43002668 -38.35441148
OS 51.43095124 -38.35348692
OS 51.43280036 -38.35256236
OS 51.43557404 -38.34978868
OS 51.44019684 -38.347015
OS 51.4457442 -38.34331676
OS 51.45221612 -38.33961852
OS 51.4596126 -38.33499572
OS 51.4688582 -38.33037292
OS 51.47902836 -38.32575012
OS 51.49012308 -38.32112732
OS 51.50214236 -38.31742908
OS 51.5150862 -38.31373084
OS 51.5289546 -38.31095716
OS 51.54374756 -38.30818348
OS 51.55946508 -38.30725892
OS 51.57610716 -38.30633436
OS 51.58535276 -38.30633436
OS 51.59182468 -38.30725892
OE
OB 52.08184148 -38.30725892 I
OS 52.09386076 -38.30910804
OS 52.10865372 -38.31188172
OS 52.1252958 -38.31650452
OS 52.14193788 -38.32205188
OS 52.15857996 -38.32944836
OS 52.15950452 -38.32944836
OS 52.16042908 -38.33037292
OS 52.16597644 -38.3331466
OS 52.17429748 -38.33869396
OS 52.18354308 -38.34516588
OS 52.1946378 -38.35441148
OS 52.20573252 -38.36458164
OS 52.21682724 -38.37660092
OS 52.22607284 -38.39046932
OS 52.2269974 -38.39231844
OS 52.22977108 -38.39694124
OS 52.23346932 -38.40526228
OS 52.23809212 -38.41543244
OS 52.24271492 -38.42745172
OS 52.24641316 -38.44132012
OS 52.24918684 -38.45703764
OS 52.2501114 -38.47275516
OS 52.2501114 -38.47460428
OS 52.2501114 -38.48015164
OS 52.24918684 -38.48754812
OS 52.24733772 -38.49771828
OS 52.24456404 -38.50973756
OS 52.23994124 -38.5226814
OS 52.23439388 -38.53562524
OS 52.2269974 -38.54856908
OS 52.22607284 -38.5504182
OS 52.22329916 -38.55411644
OS 52.2177518 -38.56058836
OS 52.21035532 -38.56798484
OS 52.20110972 -38.57630588
OS 52.190015 -38.58555148
OS 52.17707116 -38.59387252
OS 52.16135364 -38.60219356
OS 52.1622782 -38.60219356
OS 52.16412732 -38.60311812
OS 52.166901 -38.60404268
OS 52.17059924 -38.60496724
OS 52.1807694 -38.60866548
OS 52.19371324 -38.61421284
OS 52.2085062 -38.62160932
OS 52.22329916 -38.63085492
OS 52.23716756 -38.6428742
OS 52.2501114 -38.6567426
OS 52.25103596 -38.65859172
OS 52.2547342 -38.66413908
OS 52.26028156 -38.67338468
OS 52.26582892 -38.68540396
OS 52.27137628 -38.70019692
OS 52.27692364 -38.71776356
OS 52.28062188 -38.73810388
OS 52.28154644 -38.76029332
OS 52.28154644 -38.76121788
OS 52.28154644 -38.76399156
OS 52.28154644 -38.76861436
OS 52.28062188 -38.77416172
OS 52.27969732 -38.7815582
OS 52.2778482 -38.78987924
OS 52.27599908 -38.79912484
OS 52.27414996 -38.809295
OS 52.26675348 -38.83148444
OS 52.26120612 -38.84350372
OS 52.25565876 -38.85459844
OS 52.24826228 -38.86661772
OS 52.23994124 -38.878637
OS 52.23069564 -38.89065628
OS 52.21960092 -38.901751
OS 52.21867636 -38.90267556
OS 52.21682724 -38.90452468
OS 52.213129 -38.90729836
OS 52.2085062 -38.9109966
OS 52.20295884 -38.9156194
OS 52.19556236 -38.9202422
OS 52.18724132 -38.92578956
OS 52.17707116 -38.93041236
OS 52.166901 -38.93595972
OS 52.15488172 -38.94150708
OS 52.14286244 -38.94612988
OS 52.12899404 -38.95075268
OS 52.11420108 -38.95445092
OS 52.09848356 -38.9572246
OS 52.08276604 -38.95907372
OS 52.0651994 -38.95999828
OS 52.05687836 -38.95999828
OS 52.051331 -38.95907372
OS 52.04393452 -38.95814916
OS 52.03561348 -38.9572246
OS 52.02636788 -38.95537548
OS 52.01619772 -38.95352636
OS 51.99400828 -38.947979
OS 51.97089428 -38.9387334
OS 51.958875 -38.93318604
OS 51.94778028 -38.92671412
OS 51.93668556 -38.91839308
OS 51.92559084 -38.91007204
OS 51.92466628 -38.90914748
OS 51.92281716 -38.90729836
OS 51.92004348 -38.90452468
OS 51.9172698 -38.90082644
OS 51.912647 -38.89620364
OS 51.9080242 -38.88973172
OS 51.90247684 -38.8832598
OS 51.89692948 -38.87493876
OS 51.89138212 -38.86569316
OS 51.88583476 -38.85644756
OS 51.8756646 -38.83425812
OS 51.86734356 -38.80837044
OS 51.86456988 -38.79450204
OS 51.86272076 -38.77970908
OS 51.94130836 -38.76953892
OS 51.94130836 -38.77046348
OS 51.94223292 -38.7723126
OS 51.94315748 -38.77601084
OS 51.94408204 -38.78063364
OS 51.9450066 -38.786181
OS 51.94685572 -38.79265292
OS 51.95147852 -38.80652132
OS 51.95795044 -38.8231634
OS 51.96627148 -38.83888092
OS 51.97551708 -38.85367388
OS 51.9866118 -38.86661772
OS 51.98846092 -38.86754228
OS 51.99215916 -38.87124052
OS 51.99955564 -38.87586332
OS 52.00880124 -38.88048612
OS 52.01989596 -38.88603348
OS 52.03376436 -38.89065628
OS 52.04948188 -38.89435452
OS 52.06612396 -38.89527908
OS 52.07167132 -38.89527908
OS 52.07536956 -38.89435452
OS 52.08553972 -38.89342996
OS 52.09848356 -38.89065628
OS 52.11327652 -38.88603348
OS 52.12899404 -38.87956156
OS 52.14471156 -38.87031596
OS 52.15950452 -38.85737212
OS 52.16135364 -38.855523
OS 52.16597644 -38.84997564
OS 52.1715238 -38.8416546
OS 52.17892028 -38.83055988
OS 52.18631676 -38.81669148
OS 52.19186412 -38.80097396
OS 52.19648692 -38.78248276
OS 52.19833604 -38.76214244
OS 52.19833604 -38.76121788
OS 52.19833604 -38.75936876
OS 52.19833604 -38.75659508
OS 52.19741148 -38.75289684
OS 52.19648692 -38.74272668
OS 52.19371324 -38.7307074
OS 52.190015 -38.71591444
OS 52.18354308 -38.70112148
OS 52.17429748 -38.68632852
OS 52.1622782 -38.67246012
OS 52.16042908 -38.670611
OS 52.15580628 -38.66691276
OS 52.1484098 -38.6613654
OS 52.13823964 -38.65489348
OS 52.1252958 -38.64842156
OS 52.10957828 -38.6428742
OS 52.09201164 -38.63917596
OS 52.07259588 -38.63732684
OS 52.06427484 -38.63732684
OS 52.05780292 -38.6382514
OS 52.04948188 -38.63917596
OS 52.04023628 -38.64102508
OS 52.02914156 -38.6428742
OS 52.01712228 -38.64564788
OS 52.02636788 -38.57630588
OS 52.03099068 -38.57630588
OS 52.03468892 -38.57723044
OS 52.0467082 -38.57723044
OS 52.05687836 -38.57538132
OS 52.06889764 -38.5735322
OS 52.08276604 -38.57075852
OS 52.09848356 -38.56613572
OS 52.11327652 -38.5596638
OS 52.12899404 -38.55134276
OS 52.1299186 -38.55134276
OS 52.13084316 -38.5504182
OS 52.13546596 -38.54671996
OS 52.14193788 -38.54024804
OS 52.14933436 -38.531927
OS 52.15673084 -38.51990772
OS 52.16320276 -38.50603932
OS 52.16782556 -38.4903218
OS 52.16967468 -38.4810762
OS 52.16967468 -38.47090604
OS 52.16967468 -38.46998148
OS 52.16967468 -38.46905692
OS 52.16967468 -38.46350956
OS 52.16782556 -38.45611308
OS 52.16597644 -38.44594292
OS 52.1622782 -38.4348482
OS 52.1576554 -38.42282892
OS 52.15025892 -38.41080964
OS 52.14008876 -38.39971492
OS 52.1391642 -38.39879036
OS 52.1345414 -38.39509212
OS 52.12806948 -38.39046932
OS 52.11974844 -38.38492196
OS 52.10865372 -38.38029916
OS 52.09570988 -38.37567636
OS 52.08091692 -38.37197812
OS 52.06427484 -38.37105356
OS 52.05687836 -38.37105356
OS 52.04855732 -38.37290268
OS 52.0374626 -38.3747518
OS 52.02544332 -38.37845004
OS 52.01342404 -38.38307284
OS 52.0004802 -38.39046932
OS 51.98846092 -38.39971492
OS 51.98753636 -38.40063948
OS 51.98383812 -38.40526228
OS 51.97829076 -38.4117342
OS 51.97181884 -38.4209798
OS 51.96534692 -38.43299908
OS 51.958875 -38.44779204
OS 51.95332764 -38.46535868
OS 51.9496294 -38.485699
OS 51.8710418 -38.4718306
OS 51.8710418 -38.47090604
OS 51.87196636 -38.46813236
OS 51.87289092 -38.46443412
OS 51.87381548 -38.45888676
OS 51.8756646 -38.45241484
OS 51.87843828 -38.44501836
OS 51.88398564 -38.42745172
OS 51.89323124 -38.4071114
OS 51.90432596 -38.38677108
OS 51.91819436 -38.36735532
OS 51.935761 -38.34978868
OS 51.93668556 -38.34886412
OS 51.93853468 -38.34793956
OS 51.94130836 -38.34609044
OS 51.9450066 -38.34331676
OS 51.9496294 -38.33961852
OS 51.95610132 -38.33592028
OS 51.96257324 -38.33222204
OS 51.97089428 -38.32759924
OS 51.98938548 -38.32020276
OS 52.01065036 -38.31280628
OS 52.03561348 -38.30818348
OS 52.04855732 -38.30633436
OS 52.07167132 -38.30633436
OS 52.08184148 -38.30725892
OE
OB 56.14158444 -38.38492196 H
OS 55.95852156 -38.38492196
OS 55.95852156 -38.61328828
OS 56.13048972 -38.61328828
OS 56.13696164 -38.61236372
OS 56.14343356 -38.61236372
OS 56.15083004 -38.61143916
OS 56.16839668 -38.60959004
OS 56.18781244 -38.6058918
OS 56.2072282 -38.60034444
OS 56.22479484 -38.59294796
OS 56.23311588 -38.58832516
OS 56.2395878 -38.5827778
OS 56.24143692 -38.58092868
OS 56.24513516 -38.57723044
OS 56.25068252 -38.56983396
OS 56.25715444 -38.56058836
OS 56.26362636 -38.54856908
OS 56.26917372 -38.53377612
OS 56.27287196 -38.51713404
OS 56.27472108 -38.49771828
OS 56.27472108 -38.49679372
OS 56.27472108 -38.49586916
OS 56.27472108 -38.49124636
OS 56.27379652 -38.48292532
OS 56.2719474 -38.47367972
OS 56.27009828 -38.46350956
OS 56.26640004 -38.45149028
OS 56.26085268 -38.44039556
OS 56.25438076 -38.42930084
OS 56.2534562 -38.42837628
OS 56.25068252 -38.42467804
OS 56.24605972 -38.42005524
OS 56.24051236 -38.41358332
OS 56.23219132 -38.4071114
OS 56.22294572 -38.40156404
OS 56.21277556 -38.39601668
OS 56.20075628 -38.39139388
OS 56.19983172 -38.39139388
OS 56.19613348 -38.39046932
OS 56.19058612 -38.38954476
OS 56.18318964 -38.38769564
OS 56.17209492 -38.38677108
OS 56.15822652 -38.38584652
OS 56.14158444 -38.38492196
OE
OB 49.87491676 -38.43669732 H
OS 49.67336268 -38.72331092
OS 49.87491676 -38.72331092
OS 49.87491676 -38.43669732
OE
OB 54.06132444 -38.37105356 H
OS 54.05392796 -38.37105356
OS 54.04560692 -38.37290268
OS 54.0345122 -38.3747518
OS 54.02249292 -38.37845004
OS 54.00954908 -38.38307284
OS 53.9975298 -38.39046932
OS 53.98551052 -38.40063948
OS 53.98458596 -38.40156404
OS 53.98088772 -38.40526228
OS 53.97626492 -38.4117342
OS 53.97164212 -38.42005524
OS 53.96609476 -38.4302254
OS 53.96147196 -38.44224468
OS 53.95777372 -38.45518852
OS 53.95684916 -38.46998148
OS 53.95684916 -38.47090604
OS 53.95684916 -38.4718306
OS 53.95777372 -38.47737796
OS 53.95869828 -38.485699
OS 53.9605474 -38.49586916
OS 53.96424564 -38.50788844
OS 53.96886844 -38.51990772
OS 53.97626492 -38.53285156
OS 53.98551052 -38.54394628
OS 53.98643508 -38.54487084
OS 53.99105788 -38.54856908
OS 53.9975298 -38.55319188
OS 54.00585084 -38.55781468
OS 54.01694556 -38.56336204
OS 54.0298894 -38.56798484
OS 54.04468236 -38.57168308
OS 54.06132444 -38.57260764
OS 54.06317356 -38.57260764
OS 54.06872092 -38.57168308
OS 54.07704196 -38.57075852
OS 54.08813668 -38.5689094
OS 54.10015596 -38.56521116
OS 54.11217524 -38.56058836
OS 54.12511908 -38.55319188
OS 54.1362138 -38.54394628
OS 54.13713836 -38.54302172
OS 54.1408366 -38.53839892
OS 54.1454594 -38.53285156
OS 54.15100676 -38.52453052
OS 54.15655412 -38.51436036
OS 54.16117692 -38.50234108
OS 54.16487516 -38.48847268
OS 54.16579972 -38.47367972
OS 54.16579972 -38.47275516
OS 54.16579972 -38.4718306
OS 54.16579972 -38.46628324
OS 54.1639506 -38.4579622
OS 54.16210148 -38.44779204
OS 54.15840324 -38.43669732
OS 54.15285588 -38.42467804
OS 54.1454594 -38.41265876
OS 54.13528924 -38.40063948
OS 54.13436468 -38.39971492
OS 54.12974188 -38.39601668
OS 54.12326996 -38.39139388
OS 54.11494892 -38.38584652
OS 54.1038542 -38.38029916
OS 54.09183492 -38.37567636
OS 54.07704196 -38.37197812
OS 54.06132444 -38.37105356
OE
OB 54.05855076 -38.63640228 H
OS 54.0530034 -38.63640228
OS 54.04930516 -38.63732684
OS 54.039135 -38.6382514
OS 54.02619116 -38.64102508
OS 54.0113982 -38.64564788
OS 53.99660524 -38.6521198
OS 53.98088772 -38.6613654
OS 53.96701932 -38.67338468
OS 53.9651702 -38.6752338
OS 53.96147196 -38.6798566
OS 53.9559246 -38.68817764
OS 53.94945268 -38.6983478
OS 53.9420562 -38.7122162
OS 53.93650884 -38.72793372
OS 53.9328106 -38.74550036
OS 53.93096148 -38.76491612
OS 53.93096148 -38.76676524
OS 53.93096148 -38.77046348
OS 53.93188604 -38.7769354
OS 53.9328106 -38.78525644
OS 53.93465972 -38.7954266
OS 53.9374334 -38.80652132
OS 53.94113164 -38.81761604
OS 53.94575444 -38.82963532
OS 53.946679 -38.83055988
OS 53.94852812 -38.83518268
OS 53.95222636 -38.84073004
OS 53.95777372 -38.84720196
OS 53.96424564 -38.855523
OS 53.97256668 -38.86384404
OS 53.98181228 -38.87124052
OS 53.992907 -38.878637
OS 53.99475612 -38.87956156
OS 53.99845436 -38.88141068
OS 54.00492628 -38.88418436
OS 54.01324732 -38.88695804
OS 54.02341748 -38.88973172
OS 54.03543676 -38.8925054
OS 54.0483806 -38.89435452
OS 54.06132444 -38.89527908
OS 54.0668718 -38.89527908
OS 54.07057004 -38.89435452
OS 54.08166476 -38.89342996
OS 54.0946086 -38.89065628
OS 54.10940156 -38.88603348
OS 54.12511908 -38.88048612
OS 54.13991204 -38.87124052
OS 54.154705 -38.85922124
OS 54.15655412 -38.85737212
OS 54.16025236 -38.85274932
OS 54.16672428 -38.84442828
OS 54.1731962 -38.83425812
OS 54.17966812 -38.82131428
OS 54.18614004 -38.80559676
OS 54.18983828 -38.78710556
OS 54.1916874 -38.7676898
OS 54.1916874 -38.76676524
OS 54.1916874 -38.76491612
OS 54.1916874 -38.76214244
OS 54.19076284 -38.7584442
OS 54.18983828 -38.74827404
OS 54.1870646 -38.73440564
OS 54.1824418 -38.72053724
OS 54.17596988 -38.70481972
OS 54.16672428 -38.6891022
OS 54.15378044 -38.67430924
OS 54.15193132 -38.67246012
OS 54.14730852 -38.66876188
OS 54.13898748 -38.66228996
OS 54.12789276 -38.65489348
OS 54.11402436 -38.64842156
OS 54.09738228 -38.64194964
OS 54.07889108 -38.6382514
OS 54.05855076 -38.63640228
OE
OB 54.80559524 -38.37105356 H
OS 54.80004788 -38.37105356
OS 54.79634964 -38.37197812
OS 54.78617948 -38.37382724
OS 54.7741602 -38.37660092
OS 54.7602918 -38.38214828
OS 54.74549884 -38.39046932
OS 54.73810236 -38.39601668
OS 54.73070588 -38.40156404
OS 54.72423396 -38.40896052
OS 54.71776204 -38.41728156
OS 54.71776204 -38.41820612
OS 54.71591292 -38.42005524
OS 54.7140638 -38.42375348
OS 54.71129012 -38.42837628
OS 54.70851644 -38.43577276
OS 54.7048182 -38.4440938
OS 54.70204452 -38.45426396
OS 54.69834628 -38.46628324
OS 54.69464804 -38.48015164
OS 54.6909498 -38.49586916
OS 54.68725156 -38.5134358
OS 54.68447788 -38.53285156
OS 54.6817042 -38.555041
OS 54.67985508 -38.57907956
OS 54.67893052 -38.60496724
OS 54.67800596 -38.6336286
OS 54.67800596 -38.63547772
OS 54.67800596 -38.64010052
OS 54.67800596 -38.64842156
OS 54.67893052 -38.65951628
OS 54.67893052 -38.67153556
OS 54.67985508 -38.68632852
OS 54.68077964 -38.70204604
OS 54.68262876 -38.71868812
OS 54.68725156 -38.75474596
OS 54.69002524 -38.7723126
OS 54.69372348 -38.78895468
OS 54.69742172 -38.8046722
OS 54.70296908 -38.81946516
OS 54.70851644 -38.832409
OS 54.71498836 -38.84350372
OS 54.71498836 -38.84442828
OS 54.71683748 -38.84535284
OS 54.72146028 -38.85182476
OS 54.72978132 -38.8601458
OS 54.73995148 -38.8693914
OS 54.75381988 -38.878637
OS 54.7695374 -38.88695804
OS 54.78710404 -38.89342996
OS 54.79634964 -38.89435452
OS 54.8065198 -38.89527908
OS 54.81206716 -38.89527908
OS 54.8157654 -38.89435452
OS 54.825011 -38.8925054
OS 54.83795484 -38.88880716
OS 54.85182324 -38.88233524
OS 54.86754076 -38.87308964
OS 54.87493724 -38.86754228
OS 54.88233372 -38.8601458
OS 54.8897302 -38.85274932
OS 54.89712668 -38.84350372
OS 54.89712668 -38.84257916
OS 54.8989758 -38.84073004
OS 54.90082492 -38.83795636
OS 54.90267404 -38.83333356
OS 54.90637228 -38.82686164
OS 54.90914596 -38.8185406
OS 54.9128442 -38.809295
OS 54.91654244 -38.79820028
OS 54.91931612 -38.78433188
OS 54.92301436 -38.76953892
OS 54.9267126 -38.75197228
OS 54.92948628 -38.73348108
OS 54.9313354 -38.71129164
OS 54.93318452 -38.68817764
OS 54.93503364 -38.66228996
OS 54.93503364 -38.6336286
OS 54.93503364 -38.63270404
OS 54.93503364 -38.63177948
OS 54.93503364 -38.62715668
OS 54.93503364 -38.61883564
OS 54.93410908 -38.60774092
OS 54.93410908 -38.59572164
OS 54.93318452 -38.58092868
OS 54.93225996 -38.56521116
OS 54.93041084 -38.54764452
OS 54.92578804 -38.51251124
OS 54.92301436 -38.4949446
OS 54.91931612 -38.47830252
OS 54.91561788 -38.462585
OS 54.91007052 -38.44779204
OS 54.90452316 -38.4348482
OS 54.89805124 -38.42375348
OS 54.89805124 -38.42282892
OS 54.89620212 -38.42190436
OS 54.894353 -38.41913068
OS 54.89157932 -38.41543244
OS 54.88325828 -38.4071114
OS 54.87308812 -38.39694124
OS 54.85921972 -38.38769564
OS 54.8435022 -38.3793746
OS 54.83518116 -38.37567636
OS 54.82593556 -38.37290268
OS 54.8157654 -38.37197812
OS 54.80559524 -38.37105356
OE
OB 51.07499564 -38.37105356 H
OS 51.06944828 -38.37105356
OS 51.06575004 -38.37197812
OS 51.05557988 -38.37382724
OS 51.0435606 -38.37660092
OS 51.0296922 -38.38214828
OS 51.01489924 -38.39046932
OS 51.00750276 -38.39601668
OS 51.00010628 -38.40156404
OS 50.99363436 -38.40896052
OS 50.98716244 -38.41728156
OS 50.98716244 -38.41820612
OS 50.98531332 -38.42005524
OS 50.9834642 -38.42375348
OS 50.98069052 -38.42837628
OS 50.97791684 -38.43577276
OS 50.9742186 -38.4440938
OS 50.97144492 -38.45426396
OS 50.96774668 -38.46628324
OS 50.96404844 -38.48015164
OS 50.9603502 -38.49586916
OS 50.95665196 -38.5134358
OS 50.95387828 -38.53285156
OS 50.9511046 -38.555041
OS 50.94925548 -38.57907956
OS 50.94833092 -38.60496724
OS 50.94740636 -38.6336286
OS 50.94740636 -38.63547772
OS 50.94740636 -38.64010052
OS 50.94740636 -38.64842156
OS 50.94833092 -38.65951628
OS 50.94833092 -38.67153556
OS 50.94925548 -38.68632852
OS 50.95018004 -38.70204604
OS 50.95202916 -38.71868812
OS 50.95665196 -38.75474596
OS 50.95942564 -38.7723126
OS 50.96312388 -38.78895468
OS 50.96682212 -38.8046722
OS 50.97236948 -38.81946516
OS 50.97791684 -38.832409
OS 50.98438876 -38.84350372
OS 50.98438876 -38.84442828
OS 50.98623788 -38.84535284
OS 50.99086068 -38.85182476
OS 50.99918172 -38.8601458
OS 51.00935188 -38.8693914
OS 51.02322028 -38.878637
OS 51.0389378 -38.88695804
OS 51.05650444 -38.89342996
OS 51.06575004 -38.89435452
OS 51.0759202 -38.89527908
OS 51.08146756 -38.89527908
OS 51.0851658 -38.89435452
OS 51.0944114 -38.8925054
OS 51.10735524 -38.88880716
OS 51.12122364 -38.88233524
OS 51.13694116 -38.87308964
OS 51.14433764 -38.86754228
OS 51.15173412 -38.8601458
OS 51.1591306 -38.85274932
OS 51.16652708 -38.84350372
OS 51.16652708 -38.84257916
OS 51.1683762 -38.84073004
OS 51.17022532 -38.83795636
OS 51.17207444 -38.83333356
OS 51.17577268 -38.82686164
OS 51.17854636 -38.8185406
OS 51.1822446 -38.809295
OS 51.18594284 -38.79820028
OS 51.18871652 -38.78433188
OS 51.19241476 -38.76953892
OS 51.196113 -38.75197228
OS 51.19888668 -38.73348108
OS 51.2007358 -38.71129164
OS 51.20258492 -38.68817764
OS 51.20443404 -38.66228996
OS 51.20443404 -38.6336286
OS 51.20443404 -38.63270404
OS 51.20443404 -38.63177948
OS 51.20443404 -38.62715668
OS 51.20443404 -38.61883564
OS 51.20350948 -38.60774092
OS 51.20350948 -38.59572164
OS 51.20258492 -38.58092868
OS 51.20166036 -38.56521116
OS 51.19981124 -38.54764452
OS 51.19518844 -38.51251124
OS 51.19241476 -38.4949446
OS 51.18871652 -38.47830252
OS 51.18501828 -38.462585
OS 51.17947092 -38.44779204
OS 51.17392356 -38.4348482
OS 51.16745164 -38.42375348
OS 51.16745164 -38.42282892
OS 51.16560252 -38.42190436
OS 51.1637534 -38.41913068
OS 51.16097972 -38.41543244
OS 51.15265868 -38.4071114
OS 51.14248852 -38.39694124
OS 51.12862012 -38.38769564
OS 51.1129026 -38.3793746
OS 51.10458156 -38.37567636
OS 51.09533596 -38.37290268
OS 51.0851658 -38.37197812
OS 51.07499564 -38.37105356
OE
SE

### steps/pcb/layers/comp_+_bot/components
UNITS=MM
#
#Component attribute names
#
@0 .comp_mount_type
@1 .comp_height

# CMP 0
CMP 8 4.39999882 38.599999 0 N J6 Keystone_4871 ;0=1,1=1.5700
PRP ComponentLink1Description 'Datasheet'
PRP ComponentLink1URL ''
PRP Manufacturer 'Keystone Electronics'
PRP Manufacturer_Part_Number '4871'
PRP Supplier_1 ''
PRP Supplier_Part_Number_1 ''
PRP System 'connector'
TOP 0 4.39999882 38.599999 180 N 0 25 Hole
TOP 1 4.39999882 38.599999 180 N 0 18 MT
#
# CMP 1
CMP 8 36.20000126 40.10000108 0 N J5 Keystone_4871 ;0=1,1=1.5700
PRP ComponentLink1Description 'Datasheet'
PRP ComponentLink1URL ''
PRP Manufacturer 'Keystone Electronics'
PRP Manufacturer_Part_Number '4871'
PRP Supplier_1 ''
PRP Supplier_Part_Number_1 ''
PRP System 'connector'
TOP 0 36.20000126 40.10000108 180 N 0 19 Hole
TOP 1 36.20000126 40.10000108 180 N 0 11 MT
#
# CMP 2
CMP 8 35.50000012 -1.00000054 0 N J4 Keystone_4871 ;0=1,1=1.5700
PRP ComponentLink1Description 'Datasheet'
PRP ComponentLink1URL ''
PRP Manufacturer 'Keystone Electronics'
PRP Manufacturer_Part_Number '4871'
PRP Supplier_1 ''
PRP Supplier_Part_Number_1 ''
PRP System 'connector'
TOP 0 35.50000012 -1.00000054 180 N 0 20 Hole
TOP 1 35.50000012 -1.00000054 180 N 0 12 MT
#
# CMP 3
CMP 8 4.39999882 2.00000108 0 N J3 Keystone_4871 ;0=1,1=1.5700
PRP ComponentLink1Description 'Datasheet'
PRP ComponentLink1URL ''
PRP Manufacturer 'Keystone Electronics'
PRP Manufacturer_Part_Number '4871'
PRP Supplier_1 ''
PRP Supplier_Part_Number_1 ''
PRP System 'connector'
TOP 0 4.39999882 2.00000108 180 N 0 21 Hole
TOP 1 4.39999882 2.00000108 180 N 0 13 MT
#
# CMP 4
CMP 15 14.2699994 43.34999966 0 N P10 Mill-Max_8600-0-05-80-00-00-03-0 ;0=2,1=10.1600
PRP Actual_Diameter ''
PRP Applications ''
PRP Board_Thickness ''
PRP Cable_End_Type ''
PRP Category 'Terminals - PC Pin, Single Post Connectors'
PRP Color ''
PRP Connector_Style ''
PRP Connector_Type ''
PRP Contact_Finish 'Tin'
PRP Contact_Material 'Brass Alloy'
PRP Contact_Shape ''
PRP Contact_Type ''
PRP Current_Rating ''
PRP Datasheet_URL 'https://www.digikey.com/en/products/detail/mill-max-manufacturing-corp/8600-0-05-80-00-00-03-0/7775333?s=N4IgTCBcDaIBwDYAMSC0akFZVw39AzOiALoC%2BQA'
PRP Fastening_Type ''
PRP Features ''
PRP FFC__FCB_Thickness ''
PRP Flange_Diameter '0.072_ (1.83mm)'
PRP Flat_Flex_Type ''
PRP Frequency_-_Max ''
PRP Height ''
PRP Impedance ''
PRP Includes ''
PRP Industry_Recognized_Mating_Diameter ''
PRP Insulation 'Non-Insulated'
PRP Internal_Switch(s) ''
PRP Length_-_Above_Flange '0.364_ (9.25mm)'
PRP Length_-_Below_Flange '0.060_ (1.52mm)'
PRP Length_-_Overall '0.460_ (11.68mm)'
PRP Locking_Feature ''
PRP Manufacturer 'Mill-Max Manufacturing Corp.'
PRP Manufacturer_Part_Number '8600-0-05-80-00-00-03-0'
PRP Mated_Stacking_Heights ''
PRP Mating_Length/Depth ''
PRP Mating_Orientation ''
PRP Max_Operating_Temperature '125°C'
PRP Min_Operating_Temperature '-55°C'
PRP Mounting__Pins ''
PRP Mounting_Feature ''
PRP Mounting_Hole_Diameter '0.043_ (1.09mm)'
PRP Mounting_Type 'Through Hole, Vertical'
PRP Number_of_Levels ''
PRP Number_of_Ports ''
PRP Number_of_Positions/Contacts ''
PRP Part_Status ''
PRP Pin_Size_-_Above_Flange '0.040_ (1.02mm) Dia'
PRP Pin_Size_-_Below_Flange '0.035_ (0.89mm) Square'
PRP Pitch ''
PRP Positions_Per_Level ''
PRP RoHS 'Yes'
PRP Rows '1'
PRP Screw_Thread ''
PRP Series '8600'
PRP Shielding ''
PRP Shrouded ''
PRP Signal_Lines ''
PRP Signal_Pins '1'
PRP Size_/_Dimension ''
PRP Special_Notes ''
PRP Specifications ''
PRP Style ''
PRP Supplier_1 'Digikey'
PRP Supplier_Part_Number_1 '8600-0-05-80-00-00-03-0-ND'
PRP System 'connector'
PRP Terminal_Style 'Single End'
PRP Terminal_Type 'PC Pin'
PRP Termination 'Press-Fit, Square'
PRP Torque_-_Screw ''
PRP Type ''
PRP Voltage_Rating ''
PRP Wire_Gauge ''
PRP Wire_Termination ''
TOP 0 14.2699994 43.3299997 180 N 12 2 1
#
# CMP 5
CMP 15 11.2219994 43.34999966 0 N P9 Mill-Max_8600-0-05-80-00-00-03-0 ;0=2,1=10.1600
PRP Actual_Diameter ''
PRP Applications ''
PRP Board_Thickness ''
PRP Cable_End_Type ''
PRP Category 'Terminals - PC Pin, Single Post Connectors'
PRP Color ''
PRP Connector_Style ''
PRP Connector_Type ''
PRP Contact_Finish 'Tin'
PRP Contact_Material 'Brass Alloy'
PRP Contact_Shape ''
PRP Contact_Type ''
PRP Current_Rating ''
PRP Datasheet_URL 'https://www.digikey.com/en/products/detail/mill-max-manufacturing-corp/8600-0-05-80-00-00-03-0/7775333?s=N4IgTCBcDaIBwDYAMSC0akFZVw39AzOiALoC%2BQA'
PRP Fastening_Type ''
PRP Features ''
PRP FFC__FCB_Thickness ''
PRP Flange_Diameter '0.072_ (1.83mm)'
PRP Flat_Flex_Type ''
PRP Frequency_-_Max ''
PRP Height ''
PRP Impedance ''
PRP Includes ''
PRP Industry_Recognized_Mating_Diameter ''
PRP Insulation 'Non-Insulated'
PRP Internal_Switch(s) ''
PRP Length_-_Above_Flange '0.364_ (9.25mm)'
PRP Length_-_Below_Flange '0.060_ (1.52mm)'
PRP Length_-_Overall '0.460_ (11.68mm)'
PRP Locking_Feature ''
PRP Manufacturer 'Mill-Max Manufacturing Corp.'
PRP Manufacturer_Part_Number '8600-0-05-80-00-00-03-0'
PRP Mated_Stacking_Heights ''
PRP Mating_Length/Depth ''
PRP Mating_Orientation ''
PRP Max_Operating_Temperature '125°C'
PRP Min_Operating_Temperature '-55°C'
PRP Mounting__Pins ''
PRP Mounting_Feature ''
PRP Mounting_Hole_Diameter '0.043_ (1.09mm)'
PRP Mounting_Type 'Through Hole, Vertical'
PRP Number_of_Levels ''
PRP Number_of_Ports ''
PRP Number_of_Positions/Contacts ''
PRP Part_Status ''
PRP Pin_Size_-_Above_Flange '0.040_ (1.02mm) Dia'
PRP Pin_Size_-_Below_Flange '0.035_ (0.89mm) Square'
PRP Pitch ''
PRP Positions_Per_Level ''
PRP RoHS 'Yes'
PRP Rows '1'
PRP Screw_Thread ''
PRP Series '8600'
PRP Shielding ''
PRP Shrouded ''
PRP Signal_Lines ''
PRP Signal_Pins '1'
PRP Size_/_Dimension ''
PRP Special_Notes ''
PRP Specifications ''
PRP Style ''
PRP Supplier_1 'Digikey'
PRP Supplier_Part_Number_1 '8600-0-05-80-00-00-03-0-ND'
PRP System 'connector'
PRP Terminal_Style 'Single End'
PRP Terminal_Type 'PC Pin'
PRP Termination 'Press-Fit, Square'
PRP Torque_-_Screw ''
PRP Type ''
PRP Voltage_Rating ''
PRP Wire_Gauge ''
PRP Wire_Termination ''
TOP 0 11.2219994 43.3299997 180 N 13 1 1
#
# CMP 6
CMP 15 8.1739994 43.34999966 0 N P8 Mill-Max_8600-0-05-80-00-00-03-0 ;0=2,1=10.1600
PRP Actual_Diameter ''
PRP Applications ''
PRP Board_Thickness ''
PRP Cable_End_Type ''
PRP Category 'Terminals - PC Pin, Single Post Connectors'
PRP Color ''
PRP Connector_Style ''
PRP Connector_Type ''
PRP Contact_Finish 'Tin'
PRP Contact_Material 'Brass Alloy'
PRP Contact_Shape ''
PRP Contact_Type ''
PRP Current_Rating ''
PRP Datasheet_URL 'https://www.digikey.com/en/products/detail/mill-max-manufacturing-corp/8600-0-05-80-00-00-03-0/7775333?s=N4IgTCBcDaIBwDYAMSC0akFZVw39AzOiALoC%2BQA'
PRP Fastening_Type ''
PRP Features ''
PRP FFC__FCB_Thickness ''
PRP Flange_Diameter '0.072_ (1.83mm)'
PRP Flat_Flex_Type ''
PRP Frequency_-_Max ''
PRP Height ''
PRP Impedance ''
PRP Includes ''
PRP Industry_Recognized_Mating_Diameter ''
PRP Insulation 'Non-Insulated'
PRP Internal_Switch(s) ''
PRP Length_-_Above_Flange '0.364_ (9.25mm)'
PRP Length_-_Below_Flange '0.060_ (1.52mm)'
PRP Length_-_Overall '0.460_ (11.68mm)'
PRP Locking_Feature ''
PRP Manufacturer 'Mill-Max Manufacturing Corp.'
PRP Manufacturer_Part_Number '8600-0-05-80-00-00-03-0'
PRP Mated_Stacking_Heights ''
PRP Mating_Length/Depth ''
PRP Mating_Orientation ''
PRP Max_Operating_Temperature '125°C'
PRP Min_Operating_Temperature '-55°C'
PRP Mounting__Pins ''
PRP Mounting_Feature ''
PRP Mounting_Hole_Diameter '0.043_ (1.09mm)'
PRP Mounting_Type 'Through Hole, Vertical'
PRP Number_of_Levels ''
PRP Number_of_Ports ''
PRP Number_of_Positions/Contacts ''
PRP Part_Status ''
PRP Pin_Size_-_Above_Flange '0.040_ (1.02mm) Dia'
PRP Pin_Size_-_Below_Flange '0.035_ (0.89mm) Square'
PRP Pitch ''
PRP Positions_Per_Level ''
PRP RoHS 'Yes'
PRP Rows '1'
PRP Screw_Thread ''
PRP Series '8600'
PRP Shielding ''
PRP Shrouded ''
PRP Signal_Lines ''
PRP Signal_Pins '1'
PRP Size_/_Dimension ''
PRP Special_Notes ''
PRP Specifications ''
PRP Style ''
PRP Supplier_1 'Digikey'
PRP Supplier_Part_Number_1 '8600-0-05-80-00-00-03-0-ND'
PRP System 'connector'
PRP Terminal_Style 'Single End'
PRP Terminal_Type 'PC Pin'
PRP Termination 'Press-Fit, Square'
PRP Torque_-_Screw ''
PRP Type ''
PRP Voltage_Rating ''
PRP Wire_Gauge ''
PRP Wire_Termination ''
TOP 0 8.1739994 43.3299997 180 N 8 0 1
#
# CMP 7
CMP 15 5.1259994 43.34999966 0 N P7 Mill-Max_8600-0-05-80-00-00-03-0 ;0=2,1=10.1600
PRP Actual_Diameter ''
PRP Applications ''
PRP Board_Thickness ''
PRP Cable_End_Type ''
PRP Category 'Terminals - PC Pin, Single Post Connectors'
PRP Color ''
PRP Connector_Style ''
PRP Connector_Type ''
PRP Contact_Finish 'Tin'
PRP Contact_Material 'Brass Alloy'
PRP Contact_Shape ''
PRP Contact_Type ''
PRP Current_Rating ''
PRP Datasheet_URL 'https://www.digikey.com/en/products/detail/mill-max-manufacturing-corp/8600-0-05-80-00-00-03-0/7775333?s=N4IgTCBcDaIBwDYAMSC0akFZVw39AzOiALoC%2BQA'
PRP Fastening_Type ''
PRP Features ''
PRP FFC__FCB_Thickness ''
PRP Flange_Diameter '0.072_ (1.83mm)'
PRP Flat_Flex_Type ''
PRP Frequency_-_Max ''
PRP Height ''
PRP Impedance ''
PRP Includes ''
PRP Industry_Recognized_Mating_Diameter ''
PRP Insulation 'Non-Insulated'
PRP Internal_Switch(s) ''
PRP Length_-_Above_Flange '0.364_ (9.25mm)'
PRP Length_-_Below_Flange '0.060_ (1.52mm)'
PRP Length_-_Overall '0.460_ (11.68mm)'
PRP Locking_Feature ''
PRP Manufacturer 'Mill-Max Manufacturing Corp.'
PRP Manufacturer_Part_Number '8600-0-05-80-00-00-03-0'
PRP Mated_Stacking_Heights ''
PRP Mating_Length/Depth ''
PRP Mating_Orientation ''
PRP Max_Operating_Temperature '125°C'
PRP Min_Operating_Temperature '-55°C'
PRP Mounting__Pins ''
PRP Mounting_Feature ''
PRP Mounting_Hole_Diameter '0.043_ (1.09mm)'
PRP Mounting_Type 'Through Hole, Vertical'
PRP Number_of_Levels ''
PRP Number_of_Ports ''
PRP Number_of_Positions/Contacts ''
PRP Part_Status ''
PRP Pin_Size_-_Above_Flange '0.040_ (1.02mm) Dia'
PRP Pin_Size_-_Below_Flange '0.035_ (0.89mm) Square'
PRP Pitch ''
PRP Positions_Per_Level ''
PRP RoHS 'Yes'
PRP Rows '1'
PRP Screw_Thread ''
PRP Series '8600'
PRP Shielding ''
PRP Shrouded ''
PRP Signal_Lines ''
PRP Signal_Pins '1'
PRP Size_/_Dimension ''
PRP Special_Notes ''
PRP Specifications ''
PRP Style ''
PRP Supplier_1 'Digikey'
PRP Supplier_Part_Number_1 '8600-0-05-80-00-00-03-0-ND'
PRP System 'connector'
PRP Terminal_Style 'Single End'
PRP Terminal_Type 'PC Pin'
PRP Termination 'Press-Fit, Square'
PRP Torque_-_Screw ''
PRP Type ''
PRP Voltage_Rating ''
PRP Wire_Gauge ''
PRP Wire_Termination ''
TOP 0 5.1259994 43.3299997 180 N 7 0 1
#
# CMP 8
CMP 15 2.0779994 43.34999966 0 N P6 Mill-Max_8600-0-05-80-00-00-03-0 ;0=2,1=10.1600
PRP Actual_Diameter ''
PRP Applications ''
PRP Board_Thickness ''
PRP Cable_End_Type ''
PRP Category 'Terminals - PC Pin, Single Post Connectors'
PRP Color ''
PRP Connector_Style ''
PRP Connector_Type ''
PRP Contact_Finish 'Tin'
PRP Contact_Material 'Brass Alloy'
PRP Contact_Shape ''
PRP Contact_Type ''
PRP Current_Rating ''
PRP Datasheet_URL 'https://www.digikey.com/en/products/detail/mill-max-manufacturing-corp/8600-0-05-80-00-00-03-0/7775333?s=N4IgTCBcDaIBwDYAMSC0akFZVw39AzOiALoC%2BQA'
PRP Fastening_Type ''
PRP Features ''
PRP FFC__FCB_Thickness ''
PRP Flange_Diameter '0.072_ (1.83mm)'
PRP Flat_Flex_Type ''
PRP Frequency_-_Max ''
PRP Height ''
PRP Impedance ''
PRP Includes ''
PRP Industry_Recognized_Mating_Diameter ''
PRP Insulation 'Non-Insulated'
PRP Internal_Switch(s) ''
PRP Length_-_Above_Flange '0.364_ (9.25mm)'
PRP Length_-_Below_Flange '0.060_ (1.52mm)'
PRP Length_-_Overall '0.460_ (11.68mm)'
PRP Locking_Feature ''
PRP Manufacturer 'Mill-Max Manufacturing Corp.'
PRP Manufacturer_Part_Number '8600-0-05-80-00-00-03-0'
PRP Mated_Stacking_Heights ''
PRP Mating_Length/Depth ''
PRP Mating_Orientation ''
PRP Max_Operating_Temperature '125°C'
PRP Min_Operating_Temperature '-55°C'
PRP Mounting__Pins ''
PRP Mounting_Feature ''
PRP Mounting_Hole_Diameter '0.043_ (1.09mm)'
PRP Mounting_Type 'Through Hole, Vertical'
PRP Number_of_Levels ''
PRP Number_of_Ports ''
PRP Number_of_Positions/Contacts ''
PRP Part_Status ''
PRP Pin_Size_-_Above_Flange '0.040_ (1.02mm) Dia'
PRP Pin_Size_-_Below_Flange '0.035_ (0.89mm) Square'
PRP Pitch ''
PRP Positions_Per_Level ''
PRP RoHS 'Yes'
PRP Rows '1'
PRP Screw_Thread ''
PRP Series '8600'
PRP Shielding ''
PRP Shrouded ''
PRP Signal_Lines ''
PRP Signal_Pins '1'
PRP Size_/_Dimension ''
PRP Special_Notes ''
PRP Specifications ''
PRP Style ''
PRP Supplier_1 'Digikey'
PRP Supplier_Part_Number_1 '8600-0-05-80-00-00-03-0-ND'
PRP System 'connector'
PRP Terminal_Style 'Single End'
PRP Terminal_Type 'PC Pin'
PRP Termination 'Press-Fit, Square'
PRP Torque_-_Screw ''
PRP Type ''
PRP Voltage_Rating ''
PRP Wire_Gauge ''
PRP Wire_Termination ''
TOP 0 2.0779994 43.3299997 180 N 11 0 1
#
# CMP 9
CMP 16 0 0 0 N P5 Mill-Max_8600-0-05-80-00-00-03-0 ;0=2,1=10.1600
PRP Actual_Diameter ''
PRP Applications ''
PRP Board_Thickness ''
PRP Cable_End_Type ''
PRP Category 'Terminals - PC Pin, Single Post Connectors'
PRP Color ''
PRP Connector_Style ''
PRP Connector_Type ''
PRP Contact_Finish 'Tin'
PRP Contact_Material 'Brass Alloy'
PRP Contact_Shape ''
PRP Contact_Type ''
PRP Current_Rating ''
PRP Datasheet_URL 'https://www.digikey.com/en/products/detail/mill-max-manufacturing-corp/8600-0-05-80-00-00-03-0/7775333?s=N4IgTCBcDaIBwDYAMSC0akFZVw39AzOiALoC%2BQA'
PRP Fastening_Type ''
PRP Features ''
PRP FFC__FCB_Thickness ''
PRP Flange_Diameter '0.072_ (1.83mm)'
PRP Flat_Flex_Type ''
PRP Frequency_-_Max ''
PRP Height ''
PRP Impedance ''
PRP Includes ''
PRP Industry_Recognized_Mating_Diameter ''
PRP Insulation 'Non-Insulated'
PRP Internal_Switch(s) ''
PRP Length_-_Above_Flange '0.364_ (9.25mm)'
PRP Length_-_Below_Flange '0.060_ (1.52mm)'
PRP Length_-_Overall '0.460_ (11.68mm)'
PRP Locking_Feature ''
PRP Manufacturer 'Mill-Max Manufacturing Corp.'
PRP Manufacturer_Part_Number '8600-0-05-80-00-00-03-0'
PRP Mated_Stacking_Heights ''
PRP Mating_Length/Depth ''
PRP Mating_Orientation ''
PRP Max_Operating_Temperature '125°C'
PRP Min_Operating_Temperature '-55°C'
PRP Mounting__Pins ''
PRP Mounting_Feature ''
PRP Mounting_Hole_Diameter '0.043_ (1.09mm)'
PRP Mounting_Type 'Through Hole, Vertical'
PRP Number_of_Levels ''
PRP Number_of_Ports ''
PRP Number_of_Positions/Contacts ''
PRP Part_Status ''
PRP Pin_Size_-_Above_Flange '0.040_ (1.02mm) Dia'
PRP Pin_Size_-_Below_Flange '0.035_ (0.89mm) Square'
PRP Pitch ''
PRP Positions_Per_Level ''
PRP RoHS 'Yes'
PRP Rows '1'
PRP Screw_Thread ''
PRP Series '8600'
PRP Shielding ''
PRP Shrouded ''
PRP Signal_Lines ''
PRP Signal_Pins '1'
PRP Size_/_Dimension ''
PRP Special_Notes ''
PRP Specifications ''
PRP Style ''
PRP Supplier_1 'Digikey'
PRP Supplier_Part_Number_1 '8600-0-05-80-00-00-03-0-ND'
PRP System 'connector'
PRP Terminal_Style 'Single End'
PRP Terminal_Type 'PC Pin'
PRP Termination 'Press-Fit, Square'
PRP Torque_-_Screw ''
PRP Type ''
PRP Voltage_Rating ''
PRP Wire_Gauge ''
PRP Wire_Termination ''
TOP 0 0 0 180 N 15 7 1
#
# CMP 10
CMP 17 0 40.67999992 0 N P4 Mill-Max_8600-0-05-80-00-00-03-0 ;0=2,1=10.1600
PRP Actual_Diameter ''
PRP Applications ''
PRP Board_Thickness ''
PRP Cable_End_Type ''
PRP Category 'Terminals - PC Pin, Single Post Connectors'
PRP Color ''
PRP Connector_Style ''
PRP Connector_Type ''
PRP Contact_Finish 'Tin'
PRP Contact_Material 'Brass Alloy'
PRP Contact_Shape ''
PRP Contact_Type ''
PRP Current_Rating ''
PRP Datasheet_URL 'https://www.digikey.com/en/products/detail/mill-max-manufacturing-corp/8600-0-05-80-00-00-03-0/7775333?s=N4IgTCBcDaIBwDYAMSC0akFZVw39AzOiALoC%2BQA'
PRP Fastening_Type ''
PRP Features ''
PRP FFC__FCB_Thickness ''
PRP Flange_Diameter '0.072_ (1.83mm)'
PRP Flat_Flex_Type ''
PRP Frequency_-_Max ''
PRP Height ''
PRP Impedance ''
PRP Includes ''
PRP Industry_Recognized_Mating_Diameter ''
PRP Insulation 'Non-Insulated'
PRP Internal_Switch(s) ''
PRP Length_-_Above_Flange '0.364_ (9.25mm)'
PRP Length_-_Below_Flange '0.060_ (1.52mm)'
PRP Length_-_Overall '0.460_ (11.68mm)'
PRP Locking_Feature ''
PRP Manufacturer 'Mill-Max Manufacturing Corp.'
PRP Manufacturer_Part_Number '8600-0-05-80-00-00-03-0'
PRP Mated_Stacking_Heights ''
PRP Mating_Length/Depth ''
PRP Mating_Orientation ''
PRP Max_Operating_Temperature '125°C'
PRP Min_Operating_Temperature '-55°C'
PRP Mounting__Pins ''
PRP Mounting_Feature ''
PRP Mounting_Hole_Diameter '0.043_ (1.09mm)'
PRP Mounting_Type 'Through Hole, Vertical'
PRP Number_of_Levels ''
PRP Number_of_Ports ''
PRP Number_of_Positions/Contacts ''
PRP Part_Status ''
PRP Pin_Size_-_Above_Flange '0.040_ (1.02mm) Dia'
PRP Pin_Size_-_Below_Flange '0.035_ (0.89mm) Square'
PRP Pitch ''
PRP Positions_Per_Level ''
PRP RoHS 'Yes'
PRP Rows '1'
PRP Screw_Thread ''
PRP Series '8600'
PRP Shielding ''
PRP Shrouded ''
PRP Signal_Lines ''
PRP Signal_Pins '1'
PRP Size_/_Dimension ''
PRP Special_Notes ''
PRP Specifications ''
PRP Style ''
PRP Supplier_1 'Digikey'
PRP Supplier_Part_Number_1 '8600-0-05-80-00-00-03-0-ND'
PRP System 'connector'
PRP Terminal_Style 'Single End'
PRP Terminal_Type 'PC Pin'
PRP Termination 'Press-Fit, Square'
PRP Torque_-_Screw ''
PRP Type ''
PRP Voltage_Rating ''
PRP Wire_Gauge ''
PRP Wire_Termination ''
TOP 0 0 40.64 180 N 14 23 1
#
# CMP 11
CMP 18 40.67999992 40.67999992 0 N P3 Mill-Max_8600-0-05-80-00-00-03-0 ;0=2,1=10.1600
PRP Actual_Diameter ''
PRP Applications ''
PRP Board_Thickness ''
PRP Cable_End_Type ''
PRP Category 'Terminals - PC Pin, Single Post Connectors'
PRP Color ''
PRP Connector_Style ''
PRP Connector_Type ''
PRP Contact_Finish 'Tin'
PRP Contact_Material 'Brass Alloy'
PRP Contact_Shape ''
PRP Contact_Type ''
PRP Current_Rating ''
PRP Datasheet_URL 'https://www.digikey.com/en/products/detail/mill-max-manufacturing-corp/8600-0-05-80-00-00-03-0/7775333?s=N4IgTCBcDaIBwDYAMSC0akFZVw39AzOiALoC%2BQA'
PRP Fastening_Type ''
PRP Features ''
PRP FFC__FCB_Thickness ''
PRP Flange_Diameter '0.072_ (1.83mm)'
PRP Flat_Flex_Type ''
PRP Frequency_-_Max ''
PRP Height ''
PRP Impedance ''
PRP Includes ''
PRP Industry_Recognized_Mating_Diameter ''
PRP Insulation 'Non-Insulated'
PRP Internal_Switch(s) ''
PRP Length_-_Above_Flange '0.364_ (9.25mm)'
PRP Length_-_Below_Flange '0.060_ (1.52mm)'
PRP Length_-_Overall '0.460_ (11.68mm)'
PRP Locking_Feature ''
PRP Manufacturer 'Mill-Max Manufacturing Corp.'
PRP Manufacturer_Part_Number '8600-0-05-80-00-00-03-0'
PRP Mated_Stacking_Heights ''
PRP Mating_Length/Depth ''
PRP Mating_Orientation ''
PRP Max_Operating_Temperature '125°C'
PRP Min_Operating_Temperature '-55°C'
PRP Mounting__Pins ''
PRP Mounting_Feature ''
PRP Mounting_Hole_Diameter '0.043_ (1.09mm)'
PRP Mounting_Type 'Through Hole, Vertical'
PRP Number_of_Levels ''
PRP Number_of_Ports ''
PRP Number_of_Positions/Contacts ''
PRP Part_Status ''
PRP Pin_Size_-_Above_Flange '0.040_ (1.02mm) Dia'
PRP Pin_Size_-_Below_Flange '0.035_ (0.89mm) Square'
PRP Pitch ''
PRP Positions_Per_Level ''
PRP RoHS 'Yes'
PRP Rows '1'
PRP Screw_Thread ''
PRP Series '8600'
PRP Shielding ''
PRP Shrouded ''
PRP Signal_Lines ''
PRP Signal_Pins '1'
PRP Size_/_Dimension ''
PRP Special_Notes ''
PRP Specifications ''
PRP Style ''
PRP Supplier_1 'Digikey'
PRP Supplier_Part_Number_1 '8600-0-05-80-00-00-03-0-ND'
PRP System 'connector'
PRP Terminal_Style 'Single End'
PRP Terminal_Type 'PC Pin'
PRP Termination 'Press-Fit, Square'
PRP Torque_-_Screw ''
PRP Type ''
PRP Voltage_Rating ''
PRP Wire_Gauge ''
PRP Wire_Termination ''
TOP 0 40.64 40.64 180 N 9 2 1
#
# CMP 12
CMP 16 40.67999992 20.33999996 0 N P2 Mill-Max_8600-0-05-80-00-00-03-0 ;0=2,1=10.1600
PRP Actual_Diameter ''
PRP Applications ''
PRP Board_Thickness ''
PRP Cable_End_Type ''
PRP Category 'Terminals - PC Pin, Single Post Connectors'
PRP Color ''
PRP Connector_Style ''
PRP Connector_Type ''
PRP Contact_Finish 'Tin'
PRP Contact_Material 'Brass Alloy'
PRP Contact_Shape ''
PRP Contact_Type ''
PRP Current_Rating ''
PRP Datasheet_URL 'https://www.digikey.com/en/products/detail/mill-max-manufacturing-corp/8600-0-05-80-00-00-03-0/7775333?s=N4IgTCBcDaIBwDYAMSC0akFZVw39AzOiALoC%2BQA'
PRP Fastening_Type ''
PRP Features ''
PRP FFC__FCB_Thickness ''
PRP Flange_Diameter '0.072_ (1.83mm)'
PRP Flat_Flex_Type ''
PRP Frequency_-_Max ''
PRP Height ''
PRP Impedance ''
PRP Includes ''
PRP Industry_Recognized_Mating_Diameter ''
PRP Insulation 'Non-Insulated'
PRP Internal_Switch(s) ''
PRP Length_-_Above_Flange '0.364_ (9.25mm)'
PRP Length_-_Below_Flange '0.060_ (1.52mm)'
PRP Length_-_Overall '0.460_ (11.68mm)'
PRP Locking_Feature ''
PRP Manufacturer 'Mill-Max Manufacturing Corp.'
PRP Manufacturer_Part_Number '8600-0-05-80-00-00-03-0'
PRP Mated_Stacking_Heights ''
PRP Mating_Length/Depth ''
PRP Mating_Orientation ''
PRP Max_Operating_Temperature '125°C'
PRP Min_Operating_Temperature '-55°C'
PRP Mounting__Pins ''
PRP Mounting_Feature ''
PRP Mounting_Hole_Diameter '0.043_ (1.09mm)'
PRP Mounting_Type 'Through Hole, Vertical'
PRP Number_of_Levels ''
PRP Number_of_Ports ''
PRP Number_of_Positions/Contacts ''
PRP Part_Status ''
PRP Pin_Size_-_Above_Flange '0.040_ (1.02mm) Dia'
PRP Pin_Size_-_Below_Flange '0.035_ (0.89mm) Square'
PRP Pitch ''
PRP Positions_Per_Level ''
PRP RoHS 'Yes'
PRP Rows '1'
PRP Screw_Thread ''
PRP Series '8600'
PRP Shielding ''
PRP Shrouded ''
PRP Signal_Lines ''
PRP Signal_Pins '1'
PRP Size_/_Dimension ''
PRP Special_Notes ''
PRP Specifications ''
PRP Style ''
PRP Supplier_1 'Digikey'
PRP Supplier_Part_Number_1 '8600-0-05-80-00-00-03-0-ND'
PRP System 'connector'
PRP Terminal_Style 'Single End'
PRP Terminal_Type 'PC Pin'
PRP Termination 'Press-Fit, Square'
PRP Torque_-_Screw ''
PRP Type ''
PRP Voltage_Rating ''
PRP Wire_Gauge ''
PRP Wire_Termination ''
TOP 0 40.67999992 20.33999996 180 N 14 20 1
#
# CMP 13
CMP 19 40.67999992 0 0 N P1 Mill-Max_8600-0-05-80-00-00-03-0 ;0=2,1=10.1600
PRP Actual_Diameter ''
PRP Applications ''
PRP Board_Thickness ''
PRP Cable_End_Type ''
PRP Category 'Terminals - PC Pin, Single Post Connectors'
PRP Color ''
PRP Connector_Style ''
PRP Connector_Type ''
PRP Contact_Finish 'Tin'
PRP Contact_Material 'Brass Alloy'
PRP Contact_Shape ''
PRP Contact_Type ''
PRP Current_Rating ''
PRP Datasheet_URL 'https://www.digikey.com/en/products/detail/mill-max-manufacturing-corp/8600-0-05-80-00-00-03-0/7775333?s=N4IgTCBcDaIBwDYAMSC0akFZVw39AzOiALoC%2BQA'
PRP Fastening_Type ''
PRP Features ''
PRP FFC__FCB_Thickness ''
PRP Flange_Diameter '0.072_ (1.83mm)'
PRP Flat_Flex_Type ''
PRP Frequency_-_Max ''
PRP Height ''
PRP Impedance ''
PRP Includes ''
PRP Industry_Recognized_Mating_Diameter ''
PRP Insulation 'Non-Insulated'
PRP Internal_Switch(s) ''
PRP Length_-_Above_Flange '0.364_ (9.25mm)'
PRP Length_-_Below_Flange '0.060_ (1.52mm)'
PRP Length_-_Overall '0.460_ (11.68mm)'
PRP Locking_Feature ''
PRP Manufacturer 'Mill-Max Manufacturing Corp.'
PRP Manufacturer_Part_Number '8600-0-05-80-00-00-03-0'
PRP Mated_Stacking_Heights ''
PRP Mating_Length/Depth ''
PRP Mating_Orientation ''
PRP Max_Operating_Temperature '125°C'
PRP Min_Operating_Temperature '-55°C'
PRP Mounting__Pins ''
PRP Mounting_Feature ''
PRP Mounting_Hole_Diameter '0.043_ (1.09mm)'
PRP Mounting_Type 'Through Hole, Vertical'
PRP Number_of_Levels ''
PRP Number_of_Ports ''
PRP Number_of_Positions/Contacts ''
PRP Part_Status ''
PRP Pin_Size_-_Above_Flange '0.040_ (1.02mm) Dia'
PRP Pin_Size_-_Below_Flange '0.035_ (0.89mm) Square'
PRP Pitch ''
PRP Positions_Per_Level ''
PRP RoHS 'Yes'
PRP Rows '1'
PRP Screw_Thread ''
PRP Series '8600'
PRP Shielding ''
PRP Shrouded ''
PRP Signal_Lines ''
PRP Signal_Pins '1'
PRP Size_/_Dimension ''
PRP Special_Notes ''
PRP Specifications ''
PRP Style ''
PRP Supplier_1 'Digikey'
PRP Supplier_Part_Number_1 '8600-0-05-80-00-00-03-0-ND'
PRP System 'connector'
PRP Terminal_Style 'Single End'
PRP Terminal_Type 'PC Pin'
PRP Termination 'Press-Fit, Square'
PRP Torque_-_Screw ''
PRP Type ''
PRP Voltage_Rating ''
PRP Wire_Gauge ''
PRP Wire_Termination ''
TOP 0 40.64 0 180 N 10 0 1
#
# CMP 14
CMP 11 14.38500044 19.16500104 180 N R2 Yageo_RC0402FR-0791KL ;0=1,1=0.4000
PRP Case/Package '0402 (1005 Metric)'
PRP Category 'Chip Resistor - Surface Mount'
PRP Composition 'Thick Film'
PRP Datasheet_URL 'https://www.yageo.com/upload/media/product/productsearch/datasheet/rchip/PYu-RC_Group_51_RoHS_L_12.pdf'
PRP Features ''
PRP Height '0.016_ (0.40mm)'
PRP Manufacturer 'Yageo'
PRP Manufacturer_Part_Number 'RC0402FR-0791KL'
PRP Max_Operating_Temperature '155°C'
PRP Min_Operating_Temperature '-55°C'
PRP Mounting_Type ''
PRP Part_Status ''
PRP Power_(Watts) '62.5mW'
PRP Ratings ''
PRP Resistance '91k'
PRP RoHS ''
PRP Series 'RC_L'
PRP Size_/_Dimension '0.039_ L x 0.020_ W (1.00mm x 0.50mm)'
PRP Supplier_1 'Digi-Key'
PRP Supplier_Part_Number_1 '311-91.0KLRCT-ND'
PRP Temperature_Coefficient '±100ppm/°C'
PRP Termination_Style ''
PRP Tolerance '±1%'
TOP 0 13.9050014 19.16500104 0 N 16 6 1
TOP 1 14.86499948 19.16500104 0 N 3 3 2
#
# CMP 15
CMP 10 15.86500002 20.5550008 270 N R6 Yageo_RC0201JR-070RL ;0=1,1=0.2600
PRP Case/Package '0201 (0603 Metric)'
PRP Category 'Chip Resistor - Surface Mount'
PRP Composition 'Thick Film'
PRP Datasheet_URL 'https://www.yageo.com/upload/media/product/productsearch/datasheet/rchip/PYu-RC_Group_51_RoHS_L_11.pdf'
PRP Features ''
PRP Height '0.010_ (0.26mm)'
PRP Manufacturer 'Yageo'
PRP Manufacturer_Part_Number 'RC0201JR-070RL'
PRP Max_Operating_Temperature ''
PRP Min_Operating_Temperature ''
PRP Mounting_Type ''
PRP Part_Status ''
PRP Power_(Watts) '50mW'
PRP Ratings ''
PRP Resistance '0'
PRP RoHS ''
PRP Series 'RC'
PRP Size_/_Dimension '0.024_ L x 0.012_ W (0.60mm x 0.30mm)'
PRP Supplier_1 'Digi-Key'
PRP Supplier_Part_Number_1 '311-0.0NCT-ND'
PRP Temperature_Coefficient ''
PRP Termination_Style ''
PRP Tolerance 'Jumper'
TOP 0 15.86500002 20.21500148 270 N 1 2 1
TOP 1 15.86500002 20.89500012 270 N 14 18 2
#
# CMP 16
CMP 11 16.95499784 20.69500052 270 N R5 Panasonic_ERJ-2RKF2702X ;0=1,1=0.4000
PRP Case/Package '0402 (1005 Metric)'
PRP Category 'Chip Resistor - Surface Mount'
PRP Composition 'Thick Film'
PRP Datasheet_URL 'https://www.digikey.com/en/products/detail/panasonic-electronic-components/ERJ-2RKF2702X/1746175?s=N4IgTCBcDaIKICUBSBaMCDSAxMB2ADGABogC6AvkA'
PRP Features 'Automotive AEC-Q200'
PRP Height '0.016_ (0.40mm)'
PRP Manufacturer 'Panasonic'
PRP Manufacturer_Part_Number 'ERJ-2RKF2702X'
PRP Max_Operating_Temperature '155°C'
PRP Min_Operating_Temperature '-55°C'
PRP Mounting_Type ''
PRP Part_Status ''
PRP Power_(Watts) '100mW'
PRP Ratings 'AEC-Q200'
PRP Resistance '27k'
PRP RoHS 'Yes'
PRP Series 'ERJ-2RK'
PRP Size_/_Dimension '0.039_ L x 0.020_ W (1.00mm x 0.50mm)'
PRP Supplier_1 'Digikey'
PRP Supplier_Part_Number_1 'P27.0KLCT-ND'
PRP Temperature_Coefficient '±100ppm/°C'
PRP Termination_Style ''
PRP Tolerance '±1%'
TOP 0 16.95499784 20.21500148 270 N 1 0 1
TOP 1 16.95499784 21.17499956 270 N 2 0 2
#
# CMP 17
CMP 0 16.6249985 22.29000114 0 N C9 Murata_GRM033R61A332KA01D ;0=1,1=0.3300
PRP Applications 'General Purpose'
PRP Capacitance '3.3nF'
PRP Case/Package '0201 (0603 Metric)'
PRP Category ''
PRP Composition 'Ceramic'
PRP Datasheet_URL 'https://www.digikey.com/en/products/detail/murata-electronics/GRM033R61A332KA01D/702429?s=N4IgTCBcDaIOICUCyAGAzGhA2AjAQQzAGk8UcAREAXQF8g'
PRP Dielectric_Material ''
PRP ESR_(Equivalent_Series_Resistance) ''
PRP Failure_Rate ''
PRP Features ''
PRP Height '0.013_ (0.33mm)'
PRP Impedance ''
PRP Lead_Spacing ''
PRP Lead_Style ''
PRP Manufacturer 'Murata'
PRP Manufacturer_Part_Number 'GRM033R61A332KA01D'
PRP Max_Operating_Temperature '85°C'
PRP Min_Operating_Temperature '-55°C'
PRP Mounting_Type ''
PRP Part_Status ''
PRP Polarization 'Non-polar'
PRP Ratings ''
PRP RoHS 'Yes'
PRP Series 'GRM'
PRP Size_/_Dimension '0.024_ L x 0.012_ W (0.60mm x 0.30mm)'
PRP Supplier_1 'Digikey'
PRP Supplier_Part_Number_1 '490-3163-1-ND'
PRP Temperature_Coefficient 'X5R'
PRP Thickness_(Max) ''
PRP Tolerance '±10%'
PRP Type ''
PRP Voltage_-_Rated ''
PRP Voltage_Rating '10V'
PRP Voltage_Rating_-_AC ''
PRP Voltage_Rating_-_DC ''
TOP 0 16.95499784 22.29000114 180 N 2 1 1
TOP 1 16.29499916 22.29000114 180 N 14 12 2
#
# CMP 18
CMP 6 23.41500016 16.85250122 180 N L1 4.7uH ;0=1,1=3.0000
PRP Manufacturer 'Eaton'
PRP Manufacturer_Part_Number 'HCM0703-4R7-R'
TOP 0 20.76500038 16.85250122 0 N 4 4 1
TOP 1 26.06499994 16.85250122 0 N 16 5 2
#
# CMP 19
CMP 11 14.38500044 18.0150008 0 N R4 Yageo_RC0402FR-0730KL ;0=1,1=0.4000
PRP Case/Package '0402 (1005 Metric)'
PRP Category 'Chip Resistor - Surface Mount'
PRP Composition 'Thick Film'
PRP Datasheet_URL 'https://www.yageo.com/upload/media/product/productsearch/datasheet/rchip/PYu-RC_Group_51_RoHS_L_11.pdf'
PRP Features ''
PRP Height '0.016_ (0.40mm)'
PRP Manufacturer 'Yageo'
PRP Manufacturer_Part_Number 'RC0402FR-0730KL'
PRP Max_Operating_Temperature '155°C'
PRP Min_Operating_Temperature '-55°C'
PRP Mounting_Type ''
PRP Part_Status ''
PRP Power_(Watts) '62.5mW'
PRP Ratings ''
PRP Resistance '30k'
PRP RoHS ''
PRP Series 'RC_L'
PRP Size_/_Dimension '0.039_ L x 0.020_ W (1.00mm x 0.50mm)'
PRP Supplier_1 'Digi-Key'
PRP Supplier_Part_Number_1 '311-30.0KLRCT-ND'
PRP Temperature_Coefficient '±100ppm/°C'
PRP Termination_Style ''
PRP Tolerance '±1%'
TOP 0 14.86499948 18.0150008 180 N 3 0 1
TOP 1 13.9050014 18.0150008 180 N 14 6 2
#
# CMP 20
CMP 1 23.4150027 12.29000082 0 N C12 Murata_GRM155R61H104KE14D ;0=1,1=0.5500
PRP Applications 'General Purpose'
PRP Capacitance '0.1µF'
PRP Case/Package '0402 (1005 Metric)'
PRP Category 'Ceramic Capacitors'
PRP Composition 'Ceramic'
PRP Datasheet_URL 'https://www.digikey.com/en/products/detail/murata-electronics/GRM155R61H104KE14D/4905152?s=N4IgTCBcDaIOICUCyBGArGhA2FAJFADACwDSAoikQCIgC6AvkA'
PRP Dielectric_Material ''
PRP ESR_(Equivalent_Series_Resistance) ''
PRP Failure_Rate ''
PRP Features ''
PRP Height '0.022_ (0.55mm)'
PRP Impedance ''
PRP Lead_Spacing ''
PRP Lead_Style ''
PRP Manufacturer 'Murata'
PRP Manufacturer_Part_Number 'GRM155R61H104KE14D'
PRP Max_Operating_Temperature '85°C'
PRP Min_Operating_Temperature '-55°C'
PRP Mounting_Type 'Surface Mount, MLCC'
PRP Part_Status ''
PRP Polarization 'Non-polar'
PRP Ratings ''
PRP RoHS 'Yes'
PRP Series 'GRM155R61H'
PRP Size_/_Dimension '0.039_ L x 0.020_ W (1.00mm x 0.50mm)'
PRP Supplier_1 'Digikey'
PRP Supplier_Part_Number_1 '490-10697-1-ND'
PRP Temperature_Coefficient 'X5R'
PRP Thickness_(Max) ''
PRP Tolerance '±10%'
PRP Type ''
PRP Voltage_-_Rated ''
PRP Voltage_Rating '50V'
PRP Voltage_Rating_-_AC ''
PRP Voltage_Rating_-_DC ''
TOP 0 23.87500178 12.29000082 180 N 16 3 1
TOP 1 22.95500362 12.29000082 180 N 14 13 2
#
# CMP 21
CMP 5 17.16499996 17.96500344 180 N U3 DiodesInc_AP63356QZV-7 ;0=1,1=0.9000
PRP ComponentLink1Description 'Datasheet'
PRP ComponentLink1URL ''
PRP Manufacturer 'Diodes Incorporated'
PRP Manufacturer_Part_Number 'AP63356QZV-7'
PRP Supplier_1 ''
PRP Supplier_Part_Number_1 ''
PRP System 'connector'
TOP 0 16.41500146 16.99000158 0 N 15 5 1
TOP 1 16.31500166 18.04000202 0 N 15 6 2
TOP 2 16.31500166 18.49000112 0 N 3 2 3
TOP 3 16.31500166 18.94000276 0 N 1 1 4
TOP 4 18.0150008 18.94000276 0 N 0 17 5
TOP 5 18.0150008 18.49000112 0 N 5 1 6
TOP 6 18.0150008 18.04000202 0 N 4 2 7
TOP 7 17.915001 16.99000158 0 N 14 17 8
TOP 8 17.1650025 16.85250122 0 N 4 3 9
#
# CMP 22
CMP 13 33.7400011 7.6400025 180 N R3 Yageo_RC1206JR-070RL ;0=1,1=0.7000
PRP Case/Package '1206 (3216 Metric)'
PRP Category 'Chip Resistor - Surface Mount'
PRP Composition 'Thick Film'
PRP Datasheet_URL 'https://www.digikey.com/en/products/detail/yageo/RC1206JR-070RL/729184?s=N4IgTCBcDaIEoGECMYAMA2AUnAtKg7KnADIgC6AvkA'
PRP Features 'Moisture Resistant'
PRP Height '0.026_ (0.65mm)'
PRP Manufacturer 'Yageo'
PRP Manufacturer_Part_Number 'RC1206JR-070RL'
PRP Max_Operating_Temperature '155°C'
PRP Min_Operating_Temperature '-55°C'
PRP Mounting_Type ''
PRP Part_Status ''
PRP Power_(Watts) '250mW'
PRP Ratings ''
PRP Resistance '0'
PRP RoHS 'Yes'
PRP Series 'RC_L'
PRP Size_/_Dimension '0.122_ L x 0.063_ W (3.10mm x 1.60mm)'
PRP Supplier_1 'Digikey'
PRP Supplier_Part_Number_1 '311-0.0ERCT-ND'
PRP Temperature_Coefficient ''
PRP Termination_Style ''
PRP Tolerance 'Jumper'
TOP 0 32.24000156 7.63999996 0 N 16 7 1
TOP 1 35.24000064 7.63999996 0 N 6 3 2
#
# CMP 23
CMP 12 39.78999916 15.24 270 N R1 100k ;0=1,1=0.5500
PRP Manufacturer 'Panasonic'
PRP Manufacturer_Part_Number 'ERJ-3EKF1003V'
TOP 0 39.78999916 14.51500018 0 N 14 19 1
TOP 1 39.78999916 15.96499982 0 N 13 0 2
#
# CMP 24
CMP 1 18.68000074 21.17499956 180 N C3 Murata_GRM155R61H104KE14D ;0=1,1=0.5500
PRP Applications 'General Purpose'
PRP Capacitance '0.1µF'
PRP Case/Package '0402 (1005 Metric)'
PRP Category 'Ceramic Capacitors'
PRP Composition 'Ceramic'
PRP Datasheet_URL 'https://www.digikey.com/en/products/detail/murata-electronics/GRM155R61H104KE14D/4905152?s=N4IgTCBcDaIOICUCyBGArGhA2FAJFADACwDSAoikQCIgC6AvkA'
PRP Dielectric_Material ''
PRP ESR_(Equivalent_Series_Resistance) ''
PRP Failure_Rate ''
PRP Features ''
PRP Height '0.022_ (0.55mm)'
PRP Impedance ''
PRP Lead_Spacing ''
PRP Lead_Style ''
PRP Manufacturer 'Murata'
PRP Manufacturer_Part_Number 'GRM155R61H104KE14D'
PRP Max_Operating_Temperature '85°C'
PRP Min_Operating_Temperature '-55°C'
PRP Mounting_Type 'Surface Mount, MLCC'
PRP Part_Status ''
PRP Polarization 'Non-polar'
PRP Ratings ''
PRP RoHS 'Yes'
PRP Series 'GRM155R61H'
PRP Size_/_Dimension '0.039_ L x 0.020_ W (1.00mm x 0.50mm)'
PRP Supplier_1 'Digikey'
PRP Supplier_Part_Number_1 '490-10697-1-ND'
PRP Temperature_Coefficient 'X5R'
PRP Thickness_(Max) ''
PRP Tolerance '±10%'
PRP Type ''
PRP Voltage_-_Rated ''
PRP Voltage_Rating '50V'
PRP Voltage_Rating_-_AC ''
PRP Voltage_Rating_-_DC ''
TOP 0 18.22000166 21.17499956 0 N 5 0 1
TOP 1 19.13999982 21.17499956 0 N 4 1 2
#
# CMP 25
CMP 4 16.81500066 9.79000074 180 N C5 Murata_GRM21BR6YA106KE43L ;0=1,1=1.4500
PRP Applications 'General Purpose'
PRP Capacitance '10µF'
PRP Case/Package '0805 (2013 Metric)'
PRP Category 'Ceramic Capacitors'
PRP Composition 'Ceramic'
PRP Datasheet_URL 'https://www.digikey.com/en/products/detail/murata-electronics/GRM21BR6YA106KE43L/5027598?s=N4IgTCBcDaIOICUCyYCMAhBA2AmgQVQAYsBpAUQBYBmAGRAF0BfIA'
PRP Dielectric_Material ''
PRP ESR_(Equivalent_Series_Resistance) ''
PRP Failure_Rate ''
PRP Features ''
PRP Height '0.057_ (1.45mm)'
PRP Impedance ''
PRP Lead_Spacing ''
PRP Lead_Style ''
PRP Manufacturer 'Murata'
PRP Manufacturer_Part_Number 'GRM21BR6YA106KE43L'
PRP Max_Operating_Temperature '85°C'
PRP Min_Operating_Temperature '-55°C'
PRP Mounting_Type 'Surface Mount, MLCC'
PRP Part_Status ''
PRP Polarization 'Non-polar'
PRP Ratings ''
PRP RoHS 'Yes'
PRP Series 'GRM21BR6YA'
PRP Size_/_Dimension '0.079_ L x 0.049_ W (2.00mm x 1.25mm)'
PRP Supplier_1 'Digikey'
PRP Supplier_Part_Number_1 '490-10514-1-ND'
PRP Temperature_Coefficient 'X5R'
PRP Thickness_(Max) ''
PRP Tolerance '±10%'
PRP Type ''
PRP Voltage_-_Rated ''
PRP Voltage_Rating '35V'
PRP Voltage_Rating_-_AC ''
PRP Voltage_Rating_-_DC ''
TOP 0 15.91499992 9.7899982 0 N 15 4 1
TOP 1 17.7150014 9.7899982 0 N 14 16 2
#
# CMP 26
CMP 1 40.0900011 8.09999904 270 N C2 Murata_GRM155R61H104KE14D ;0=1,1=0.5500
PRP Applications 'General Purpose'
PRP Capacitance '0.1µF'
PRP Case/Package '0402 (1005 Metric)'
PRP Category 'Ceramic Capacitors'
PRP Composition 'Ceramic'
PRP Datasheet_URL 'https://www.digikey.com/en/products/detail/murata-electronics/GRM155R61H104KE14D/4905152?s=N4IgTCBcDaIOICUCyBGArGhA2FAJFADACwDSAoikQCIgC6AvkA'
PRP Dielectric_Material ''
PRP ESR_(Equivalent_Series_Resistance) ''
PRP Failure_Rate ''
PRP Features ''
PRP Height '0.022_ (0.55mm)'
PRP Impedance ''
PRP Lead_Spacing ''
PRP Lead_Style ''
PRP Manufacturer 'Murata'
PRP Manufacturer_Part_Number 'GRM155R61H104KE14D'
PRP Max_Operating_Temperature '85°C'
PRP Min_Operating_Temperature '-55°C'
PRP Mounting_Type 'Surface Mount, MLCC'
PRP Part_Status ''
PRP Polarization 'Non-polar'
PRP Ratings ''
PRP RoHS 'Yes'
PRP Series 'GRM155R61H'
PRP Size_/_Dimension '0.039_ L x 0.020_ W (1.00mm x 0.50mm)'
PRP Supplier_1 'Digikey'
PRP Supplier_Part_Number_1 '490-10697-1-ND'
PRP Temperature_Coefficient 'X5R'
PRP Thickness_(Max) ''
PRP Tolerance '±10%'
PRP Type ''
PRP Voltage_-_Rated ''
PRP Voltage_Rating '50V'
PRP Voltage_Rating_-_AC ''
PRP Voltage_Rating_-_DC ''
TOP 0 40.0900011 7.63999996 270 N 6 1 1
TOP 1 40.0900011 8.55999812 270 N 14 7 2
#
# CMP 27
CMP 2 38.30999958 9.94000044 180 N C1 Murata_GRM155R6YA105KE11D ;0=1,1=0.6100
PRP Applications 'General Purpose'
PRP Capacitance '1µF'
PRP Case/Package '0402 (1005 Metric)'
PRP Category 'Ceramic Capacitors'
PRP Composition 'Ceramic'
PRP Datasheet_URL 'https://www.digikey.com/en/products/detail/murata-electronics/GRM155R6YA105KE11D/4905162?s=N4IgTCBcDaIOICUCyBGArGhA2AmgQRQAY0BpAURRQBEQBdAXyA'
PRP Dielectric_Material ''
PRP ESR_(Equivalent_Series_Resistance) ''
PRP Failure_Rate ''
PRP Features ''
PRP Height '0.024_ (0.60mm)'
PRP Impedance ''
PRP Lead_Spacing ''
PRP Lead_Style ''
PRP Manufacturer 'Murata'
PRP Manufacturer_Part_Number 'GRM155R6YA105KE11D'
PRP Max_Operating_Temperature '85°C'
PRP Min_Operating_Temperature '-55°C'
PRP Mounting_Type 'Surface Mount, MLCC'
PRP Part_Status ''
PRP Polarization 'Non-polar'
PRP Ratings ''
PRP RoHS 'Yes'
PRP Series 'GRM155R6YA'
PRP Size_/_Dimension '0.039_ L x 0.020_ W (1.00mm x 0.50mm)'
PRP Supplier_1 'Digikey'
PRP Supplier_Part_Number_1 '490-10019-1-ND'
PRP Temperature_Coefficient 'X5R'
PRP Thickness_(Max) ''
PRP Tolerance '±10%'
PRP Type ''
PRP Voltage_-_Rated ''
PRP Voltage_Rating '35V'
PRP Voltage_Rating_-_AC ''
PRP Voltage_Rating_-_DC ''
TOP 0 37.8500005 9.94000044 0 N 6 2 1
TOP 1 38.76999866 9.94000044 0 N 14 14 2
#
# CMP 28
CMP 0 14.86499948 20.54500082 90 N C4 Murata_GRM0335C1E330JA01D ;0=1,1=0.3300
PRP Applications 'General Purpose'
PRP Capacitance '33pF'
PRP Case/Package '0201 (0603 Metric)'
PRP Category 'Ceramic Capacitors'
PRP Composition 'Ceramic'
PRP Datasheet_URL 'https://www.digikey.com/en/products/detail/murata-electronics/GRM0335C1E330JA01D/4358214?s=N4IgTCBcDaIOICUCyAGAzGgrAYQIwFEMUApAQRVwBEQBdAXyA'
PRP Dielectric_Material ''
PRP ESR_(Equivalent_Series_Resistance) ''
PRP Failure_Rate ''
PRP Features ''
PRP Height '0.013_ (0.33mm)'
PRP Impedance ''
PRP Lead_Spacing ''
PRP Lead_Style ''
PRP Manufacturer 'Murata'
PRP Manufacturer_Part_Number 'GRM0335C1E330JA01D'
PRP Max_Operating_Temperature '125°C'
PRP Min_Operating_Temperature '-55°C'
PRP Mounting_Type 'Surface Mount, MLCC'
PRP Part_Status ''
PRP Polarization 'Non-polar'
PRP Ratings ''
PRP RoHS 'Yes'
PRP Series 'GRM0335C1E'
PRP Size_/_Dimension '0.024_ L x 0.012_ W (0.60mm x 0.30mm)'
PRP Supplier_1 'Digikey'
PRP Supplier_Part_Number_1 '490-10678-1-ND'
PRP Temperature_Coefficient 'C0G, NP0'
PRP Thickness_(Max) ''
PRP Tolerance '±5%'
PRP Type ''
PRP Voltage_-_Rated ''
PRP Voltage_Rating '25V'
PRP Voltage_Rating_-_AC ''
PRP Voltage_Rating_-_DC ''
TOP 0 14.86499948 20.87500016 90 N 16 1 1
TOP 1 14.86499948 20.21500148 90 N 3 1 2
#
# CMP 29
CMP 14 20.24000016 42.13999954 0 N J2 Wurth_9774040243R ;0=2,1=4.0000
PRP Actual_Diameter ''
PRP Applications ''
PRP Board_Thickness ''
PRP Cable_End_Type ''
PRP Category 'Board Spacers, Standoffs'
PRP Color ''
PRP Connector_Style ''
PRP Connector_Type ''
PRP Contact_Finish ''
PRP Contact_Material 'Steel'
PRP Contact_Shape ''
PRP Contact_Type ''
PRP Current_Rating ''
PRP Datasheet_URL 'https://www.digikey.com/en/products/detail/w%C3%BCrth-elektronik/9774040243R/5320633?s=N4IgTCBcDaIJwHYEBYAMazIMwCUQF0BfIA'
PRP Fastening_Type ''
PRP Features ''
PRP FFC__FCB_Thickness ''
PRP Flange_Diameter ''
PRP Flat_Flex_Type ''
PRP Frequency_-_Max ''
PRP Height '0.157_ (4.00mm)'
PRP Impedance ''
PRP Includes ''
PRP Industry_Recognized_Mating_Diameter ''
PRP Insulation ''
PRP Internal_Switch(s) ''
PRP Length_-_Above_Flange ''
PRP Length_-_Below_Flange ''
PRP Length_-_Overall ''
PRP Locking_Feature ''
PRP Manufacturer 'Wurth Elektronik'
PRP Manufacturer_Part_Number '9774040243R'
PRP Mated_Stacking_Heights ''
PRP Mating_Length/Depth ''
PRP Mating_Orientation ''
PRP Max_Operating_Temperature '150°C'
PRP Min_Operating_Temperature '-55°C'
PRP Mounting__Pins ''
PRP Mounting_Feature ''
PRP Mounting_Hole_Diameter ''
PRP Mounting_Type 'Through Hole, Vertical'
PRP Number_of_Levels ''
PRP Number_of_Ports ''
PRP Number_of_Positions/Contacts ''
PRP Part_Status ''
PRP Pin_Size_-_Above_Flange ''
PRP Pin_Size_-_Below_Flange ''
PRP Pitch ''
PRP Positions_Per_Level ''
PRP RoHS 'Yes'
PRP Rows ''
PRP Screw_Thread 'M2x0.4'
PRP Series 'WA-SMSI'
PRP Shielding ''
PRP Shrouded ''
PRP Signal_Lines ''
PRP Signal_Pins ''
PRP Size_/_Dimension ''
PRP Special_Notes ''
PRP Specifications ''
PRP Style ''
PRP Supplier_1 'Digikey'
PRP Supplier_Part_Number_1 '732-7090-1-ND'
PRP System 'connector'
PRP Terminal_Style ''
PRP Terminal_Type ''
PRP Termination ''
PRP Torque_-_Screw ''
PRP Type 'Round Standoff'
PRP Voltage_Rating ''
PRP Wire_Gauge ''
PRP Wire_Termination ''
TOP 0 20.24000016 42.13999954 180 N 0 28 MT1
#
# CMP 30
CMP 14 20.43999976 -1.26000002 0 N J1 Wurth_9774040243R ;0=2,1=4.0000
PRP Actual_Diameter ''
PRP Applications ''
PRP Board_Thickness ''
PRP Cable_End_Type ''
PRP Category 'Board Spacers, Standoffs'
PRP Color ''
PRP Connector_Style ''
PRP Connector_Type ''
PRP Contact_Finish ''
PRP Contact_Material 'Steel'
PRP Contact_Shape ''
PRP Contact_Type ''
PRP Current_Rating ''
PRP Datasheet_URL 'https://www.digikey.com/en/products/detail/w%C3%BCrth-elektronik/9774040243R/5320633?s=N4IgTCBcDaIJwHYEBYAMazIMwCUQF0BfIA'
PRP Fastening_Type ''
PRP Features ''
PRP FFC__FCB_Thickness ''
PRP Flange_Diameter ''
PRP Flat_Flex_Type ''
PRP Frequency_-_Max ''
PRP Height '0.157_ (4.00mm)'
PRP Impedance ''
PRP Includes ''
PRP Industry_Recognized_Mating_Diameter ''
PRP Insulation ''
PRP Internal_Switch(s) ''
PRP Length_-_Above_Flange ''
PRP Length_-_Below_Flange ''
PRP Length_-_Overall ''
PRP Locking_Feature ''
PRP Manufacturer 'Wurth Elektronik'
PRP Manufacturer_Part_Number '9774040243R'
PRP Mated_Stacking_Heights ''
PRP Mating_Length/Depth ''
PRP Mating_Orientation ''
PRP Max_Operating_Temperature '150°C'
PRP Min_Operating_Temperature '-55°C'
PRP Mounting__Pins ''
PRP Mounting_Feature ''
PRP Mounting_Hole_Diameter ''
PRP Mounting_Type 'Through Hole, Vertical'
PRP Number_of_Levels ''
PRP Number_of_Ports ''
PRP Number_of_Positions/Contacts ''
PRP Part_Status ''
PRP Pin_Size_-_Above_Flange ''
PRP Pin_Size_-_Below_Flange ''
PRP Pitch ''
PRP Positions_Per_Level ''
PRP RoHS 'Yes'
PRP Rows ''
PRP Screw_Thread 'M2x0.4'
PRP Series 'WA-SMSI'
PRP Shielding ''
PRP Shrouded ''
PRP Signal_Lines ''
PRP Signal_Pins ''
PRP Size_/_Dimension ''
PRP Special_Notes ''
PRP Specifications ''
PRP Style ''
PRP Supplier_1 'Digikey'
PRP Supplier_Part_Number_1 '732-7090-1-ND'
PRP System 'connector'
PRP Terminal_Style ''
PRP Terminal_Type ''
PRP Termination ''
PRP Torque_-_Screw ''
PRP Type 'Round Standoff'
PRP Voltage_Rating ''
PRP Wire_Gauge ''
PRP Wire_Termination ''
TOP 0 20.43999976 -1.26000002 180 N 0 22 MT1
#
# CMP 31
CMP 3 23.3150029 7.78999966 0 N C11 Murata_GRM21BR61A226ME51L ;0=1,1=1.4000
PRP Applications 'General Purpose'
PRP Capacitance '22µF'
PRP Case/Package '0805 (2013 Metric)'
PRP Category 'Ceramic Capacitors'
PRP Composition 'Ceramic'
PRP Datasheet_URL 'https://www.digikey.com/en/products/detail/murata-electronics/GRM21BR61A226ME51L/5027595?s=N4IgTCBcDaIOICUCyYCMAhBA2VBBMYWSAogKyoAyIAugL5A'
PRP Dielectric_Material ''
PRP ESR_(Equivalent_Series_Resistance) ''
PRP Failure_Rate ''
PRP Features ''
PRP Height '0.055_ (1.40mm)'
PRP Impedance ''
PRP Lead_Spacing ''
PRP Lead_Style ''
PRP Manufacturer 'Murata'
PRP Manufacturer_Part_Number 'GRM21BR61A226ME51L'
PRP Max_Operating_Temperature '85°C'
PRP Min_Operating_Temperature '-55°C'
PRP Mounting_Type 'Surface Mount, MLCC'
PRP Part_Status ''
PRP Polarization 'Non-polar'
PRP Ratings ''
PRP RoHS 'Yes'
PRP Series 'GRM21BR61A'
PRP Size_/_Dimension '0.079_ L x 0.049_ W (2.00mm x 1.25mm)'
PRP Supplier_1 'Digikey'
PRP Supplier_Part_Number_1 '490-10511-1-ND'
PRP Temperature_Coefficient 'X5R'
PRP Thickness_(Max) ''
PRP Tolerance '±20%'
PRP Type ''
PRP Voltage_-_Rated ''
PRP Voltage_Rating '10V'
PRP Voltage_Rating_-_AC ''
PRP Voltage_Rating_-_DC ''
TOP 0 24.21500364 7.7900022 180 N 16 4 1
TOP 1 22.41500216 7.7900022 180 N 14 15 2
#
# CMP 32
CMP 3 23.3150029 10.28999974 0 N C10 Murata_GRM21BR61A226ME51L ;0=1,1=1.4000
PRP Applications 'General Purpose'
PRP Capacitance '22µF'
PRP Case/Package '0805 (2013 Metric)'
PRP Category 'Ceramic Capacitors'
PRP Composition 'Ceramic'
PRP Datasheet_URL 'https://www.digikey.com/en/products/detail/murata-electronics/GRM21BR61A226ME51L/5027595?s=N4IgTCBcDaIOICUCyYCMAhBA2VBBMYWSAogKyoAyIAugL5A'
PRP Dielectric_Material ''
PRP ESR_(Equivalent_Series_Resistance) ''
PRP Failure_Rate ''
PRP Features ''
PRP Height '0.055_ (1.40mm)'
PRP Impedance ''
PRP Lead_Spacing ''
PRP Lead_Style ''
PRP Manufacturer 'Murata'
PRP Manufacturer_Part_Number 'GRM21BR61A226ME51L'
PRP Max_Operating_Temperature '85°C'
PRP Min_Operating_Temperature '-55°C'
PRP Mounting_Type 'Surface Mount, MLCC'
PRP Part_Status ''
PRP Polarization 'Non-polar'
PRP Ratings ''
PRP RoHS 'Yes'
PRP Series 'GRM21BR61A'
PRP Size_/_Dimension '0.079_ L x 0.049_ W (2.00mm x 1.25mm)'
PRP Supplier_1 'Digikey'
PRP Supplier_Part_Number_1 '490-10511-1-ND'
PRP Temperature_Coefficient 'X5R'
PRP Thickness_(Max) ''
PRP Tolerance '±20%'
PRP Type ''
PRP Voltage_-_Rated ''
PRP Voltage_Rating '10V'
PRP Voltage_Rating_-_AC ''
PRP Voltage_Rating_-_DC ''
TOP 0 24.21500364 10.29000228 180 N 16 2 1
TOP 1 22.41500216 10.29000228 180 N 14 8 2
#
# CMP 33
CMP 1 17.1150026 14.7900009 180 N C6 Murata_GRM155R61H104KE14D ;0=1,1=0.5500
PRP Applications 'General Purpose'
PRP Capacitance '0.1µF'
PRP Case/Package '0402 (1005 Metric)'
PRP Category 'Ceramic Capacitors'
PRP Composition 'Ceramic'
PRP Datasheet_URL 'https://www.digikey.com/en/products/detail/murata-electronics/GRM155R61H104KE14D/4905152?s=N4IgTCBcDaIOICUCyBGArGhA2FAJFADACwDSAoikQCIgC6AvkA'
PRP Dielectric_Material ''
PRP ESR_(Equivalent_Series_Resistance) ''
PRP Failure_Rate ''
PRP Features ''
PRP Height '0.022_ (0.55mm)'
PRP Impedance ''
PRP Lead_Spacing ''
PRP Lead_Style ''
PRP Manufacturer 'Murata'
PRP Manufacturer_Part_Number 'GRM155R61H104KE14D'
PRP Max_Operating_Temperature '85°C'
PRP Min_Operating_Temperature '-55°C'
PRP Mounting_Type 'Surface Mount, MLCC'
PRP Part_Status ''
PRP Polarization 'Non-polar'
PRP Ratings ''
PRP RoHS 'Yes'
PRP Series 'GRM155R61H'
PRP Size_/_Dimension '0.039_ L x 0.020_ W (1.00mm x 0.50mm)'
PRP Supplier_1 'Digikey'
PRP Supplier_Part_Number_1 '490-10697-1-ND'
PRP Temperature_Coefficient 'X5R'
PRP Thickness_(Max) ''
PRP Tolerance '±10%'
PRP Type ''
PRP Voltage_-_Rated ''
PRP Voltage_Rating '50V'
PRP Voltage_Rating_-_AC ''
PRP Voltage_Rating_-_DC ''
TOP 0 16.65500352 14.7900009 0 N 15 1 1
TOP 1 17.57500168 14.7900009 0 N 14 9 2
#
# CMP 34
CMP 3 16.81500066 7.39000046 180 N C8 Murata_GRM21BR61A226ME51L ;0=1,1=1.4000
PRP Applications 'General Purpose'
PRP Capacitance '22µF'
PRP Case/Package '0805 (2013 Metric)'
PRP Category 'Ceramic Capacitors'
PRP Composition 'Ceramic'
PRP Datasheet_URL 'https://www.digikey.com/en/products/detail/murata-electronics/GRM21BR61A226ME51L/5027595?s=N4IgTCBcDaIOICUCyYCMAhBA2VBBMYWSAogKyoAyIAugL5A'
PRP Dielectric_Material ''
PRP ESR_(Equivalent_Series_Resistance) ''
PRP Failure_Rate ''
PRP Features ''
PRP Height '0.055_ (1.40mm)'
PRP Impedance ''
PRP Lead_Spacing ''
PRP Lead_Style ''
PRP Manufacturer 'Murata'
PRP Manufacturer_Part_Number 'GRM21BR61A226ME51L'
PRP Max_Operating_Temperature '85°C'
PRP Min_Operating_Temperature '-55°C'
PRP Mounting_Type 'Surface Mount, MLCC'
PRP Part_Status ''
PRP Polarization 'Non-polar'
PRP Ratings ''
PRP RoHS 'Yes'
PRP Series 'GRM21BR61A'
PRP Size_/_Dimension '0.079_ L x 0.049_ W (2.00mm x 1.25mm)'
PRP Supplier_1 'Digikey'
PRP Supplier_Part_Number_1 '490-10511-1-ND'
PRP Temperature_Coefficient 'X5R'
PRP Thickness_(Max) ''
PRP Tolerance '±20%'
PRP Type ''
PRP Voltage_-_Rated ''
PRP Voltage_Rating '10V'
PRP Voltage_Rating_-_AC ''
PRP Voltage_Rating_-_DC ''
TOP 0 15.91499992 7.38999792 0 N 15 2 1
TOP 1 17.7150014 7.38999792 0 N 14 10 2
#
# CMP 35
CMP 4 16.81500066 12.39000316 180 N C7 Murata_GRM21BR6YA106KE43L ;0=1,1=1.4500
PRP Applications 'General Purpose'
PRP Capacitance '10µF'
PRP Case/Package '0805 (2013 Metric)'
PRP Category 'Ceramic Capacitors'
PRP Composition 'Ceramic'
PRP Datasheet_URL 'https://www.digikey.com/en/products/detail/murata-electronics/GRM21BR6YA106KE43L/5027598?s=N4IgTCBcDaIOICUCyYCMAhBA2AmgQVQAYsBpAUQBYBmAGRAF0BfIA'
PRP Dielectric_Material ''
PRP ESR_(Equivalent_Series_Resistance) ''
PRP Failure_Rate ''
PRP Features ''
PRP Height '0.057_ (1.45mm)'
PRP Impedance ''
PRP Lead_Spacing ''
PRP Lead_Style ''
PRP Manufacturer 'Murata'
PRP Manufacturer_Part_Number 'GRM21BR6YA106KE43L'
PRP Max_Operating_Temperature '85°C'
PRP Min_Operating_Temperature '-55°C'
PRP Mounting_Type 'Surface Mount, MLCC'
PRP Part_Status ''
PRP Polarization 'Non-polar'
PRP Ratings ''
PRP RoHS 'Yes'
PRP Series 'GRM21BR6YA'
PRP Size_/_Dimension '0.079_ L x 0.049_ W (2.00mm x 1.25mm)'
PRP Supplier_1 'Digikey'
PRP Supplier_Part_Number_1 '490-10514-1-ND'
PRP Temperature_Coefficient 'X5R'
PRP Thickness_(Max) ''
PRP Tolerance '±10%'
PRP Type ''
PRP Voltage_-_Rated ''
PRP Voltage_Rating '35V'
PRP Voltage_Rating_-_AC ''
PRP Voltage_Rating_-_DC ''
TOP 0 15.91499992 12.39000062 0 N 15 3 1
TOP 1 17.7150014 12.39000062 0 N 14 11 2
#

### steps/pcb/layers/comp_+_top/components
UNITS=MM
#
#Component attribute names
#
@0 .comp_mount_type
@1 .comp_height

# CMP 0
CMP 7 21.3400005 20.33999996 180 N U2 IQD_ICPT-1 ;0=2,1=14.5000
PRP ComponentLink1Description 'Datasheet'
PRP ComponentLink1URL ''
PRP Manufacturer 'Microchip'
PRP Manufacturer_Part_Number '090-02984-001'
PRP Supplier_1 ''
PRP Supplier_Part_Number_1 ''
PRP System 'connector'
TOP 0 4.8300005 33.03999996 90 N 0 24 1
TOP 1 4.8300005 17.79999996 90 N 0 23 2
TOP 2 4.8300005 12.71999996 90 N 7 1 3
TOP 3 4.8300005 7.63999996 90 N 8 1 4
TOP 4 37.8500005 7.63999996 90 N 6 4 5
TOP 5 37.8500005 12.71999996 90 N 14 21 6
TOP 6 37.8500005 17.79999996 90 N 13 2 7
TOP 7 37.8500005 22.87999996 90 N 12 0 8
TOP 8 37.8500005 33.03999996 180 N 9 0 9
#
# CMP 1
CMP 9 21.3400005 20.33999996 180 N U1 Microchip_SA45 ;0=2,1=11.4300
PRP ComponentLink1Description 'Datasheet'
PRP ComponentLink1URL ''
PRP Manufacturer 'Microchip'
PRP Manufacturer_Part_Number '090-02984-001'
PRP Supplier_1 ''
PRP Supplier_Part_Number_1 ''
PRP System 'connector'
TOP 0 4.8300005 33.03999996 90 N 0 26 1
TOP 1 4.8300005 17.79999996 90 N 0 27 4
TOP 2 4.8300005 12.71999996 90 N 7 2 5
TOP 3 4.8300005 7.63999996 90 N 8 2 6
TOP 4 37.8500005 7.63999996 90 N 6 5 7
TOP 5 37.8500005 12.71999996 90 N 14 22 8
TOP 6 37.8500005 17.79999996 90 N 13 3 9
TOP 7 37.8500005 22.87999996 90 N 12 1 10
TOP 8 37.8500005 33.03999996 180 N 9 1 12
#

### steps/pcb/layers/drill_non-plated_bottom-top/tools
UNITS=MM
THICKNESS=0
USER_PARAMS=

TOOLS {
    NUM=1
    TYPE=NON_PLATED
    MIN_TOL=50.8
    MAX_TOL=50.8
    BIT=
    FINISH_SIZE=2999.99908
    DRILL_SIZE=2999.99908
}

### steps/pcb/layers/drill_plated_bottom-top/tools
UNITS=MM
THICKNESS=0
USER_PARAMS=

TOOLS {
    NUM=1
    TYPE=VIA
    MIN_TOL=299.9994
    MAX_TOL=0
    BIT=
    FINISH_SIZE=299.9994
    DRILL_SIZE=299.9994
}

TOOLS {
    NUM=2
    TYPE=PLATED
    MIN_TOL=0
    MAX_TOL=0
    BIT=
    FINISH_SIZE=762
    DRILL_SIZE=762
}

TOOLS {
    NUM=3
    TYPE=PLATED
    MIN_TOL=0
    MAX_TOL=0
    BIT=
    FINISH_SIZE=961.9996
    DRILL_SIZE=961.9996
}

TOOLS {
    NUM=4
    TYPE=PLATED
    MIN_TOL=76.2
    MAX_TOL=76.2
    BIT=
    FINISH_SIZE=1090.00036
    DRILL_SIZE=1090.00036
}

TOOLS {
    NUM=5
    TYPE=PLATED
    MIN_TOL=75.00112
    MAX_TOL=75.00112
    BIT=
    FINISH_SIZE=1200.00014
    DRILL_SIZE=1200.00014
}

TOOLS {
    NUM=6
    TYPE=PLATED
    MIN_TOL=75.00112
    MAX_TOL=75.00112
    BIT=
    FINISH_SIZE=3700.00022
    DRILL_SIZE=3700.00022
}

